G04 ================== begin FILE IDENTIFICATION RECORD ==================*
G04 Layout Name:  9127_F0T_Expander_BD_F_v02_0110_1240.brd*
G04 Film Name:    gnd4*
G04 File Format:  Gerber RS274X*
G04 File Origin:  Cadence Allegro 17.2-S081*
G04 Origin Date:  Wed Jan 11 16:06:29 2023*
G04 *
G04 Layer:  DRAWING FORMAT/TITLE_BLOCK_A*
G04 Layer:  PIN/SPECIAL_DRILL*
G04 Layer:  VIA CLASS/GND4*
G04 Layer:  PIN/GND4*
G04 Layer:  MANUFACTURING/PHOTOPLOT_OUTLINE*
G04 Layer:  ETCH/GND4*
G04 Layer:  DRAWING FORMAT/TITLE_BLOCK*
G04 Layer:  DRAWING FORMAT/TITLE_DATA_GND4*
G04 *
G04 Offset:    (0.00 0.00)*
G04 Mirror:    No*
G04 Mode:      Negative*
G04 Rotation:  0*
G04 FullContactRelief:  No*
G04 UndefLineWidth:     6.00*
G04 ================== end FILE IDENTIFICATION RECORD ====================*
%FSLAX25Y25*MOIN*%
%IR0*IPPOS*OFA0.00000B0.00000*MIA0B0*SFA1.00000B1.00000*%
%ADD15C,.03*%
%ADD53C,.06*%
%ADD23C,.024*%
%ADD54C,.061*%
%ADD33C,.0322*%
%ADD45C,.071*%
%AMMACRO29*
4,1,36,0.0,.01,
-.001736,.009848,
-.00342,.009397,
-.005,.00866,
-.006428,.00766,
-.00766,.006428,
-.00866,.005,
-.009397,.00342,
-.009848,.001736,
-.01,0.0,
-.009848,-.001736,
-.009397,-.00342,
-.00866,-.005,
-.00766,-.006428,
-.006428,-.00766,
-.005,-.00866,
-.00342,-.009397,
-.001736,-.009848,
0.0,-.01,
.001736,-.009848,
.00342,-.009397,
.005,-.00866,
.006428,-.00766,
.00766,-.006428,
.00866,-.005,
.009397,-.00342,
.009848,-.001736,
.01,0.0,
.009848,.001736,
.009397,.00342,
.00866,.005,
.00766,.006428,
.006428,.00766,
.005,.00866,
.00342,.009397,
.001736,.009848,
0.0,.01,
0.0*
%
%ADD29MACRO29*%
%ADD28C,.026*%
%ADD51C,.082*%
%ADD43C,.028*%
%AMMACRO39*
4,1,20,-.0075,-.05555,
-.0075,-.06273,
-.013677,-.060878,
-.019439,-.057981,
-.024611,-.054127,
-.029034,-.049434,
-.032576,-.044045,
-.035127,-.038122,
-.036612,-.031846,
-.037,-.0265,
-.037,-.0075,
-.03,-.0075,
-.03,-.0265,
-.029544,-.03171,
-.028191,-.036762,
-.02598,-.041502,
-.022981,-.045786,
-.019282,-.049484,
-.014998,-.052484,
-.010258,-.054694,
-.0075,-.05555,
270.*
4,1,20,.0075,-.06273,
.0075,-.05555,
.01243,-.053806,
.016983,-.051232,
.02102,-.047906,
.024418,-.043931,
.027073,-.039425,
.028906,-.034527,
.029861,-.029385,
.03,-.0265,
.03,-.0075,
.037,-.0075,
.037,-.0265,
.036438,-.032925,
.034769,-.039154,
.032043,-.044999,
.028344,-.050282,
.023784,-.054842,
.018501,-.058541,
.012656,-.061266,
.0075,-.06273,
270.*
4,1,20,-.0075,.06273,
-.0075,.05555,
-.01243,.053806,
-.016983,.051232,
-.02102,.047906,
-.024418,.043931,
-.027073,.039425,
-.028906,.034527,
-.029861,.029385,
-.03,.0265,
-.03,.0075,
-.037,.0075,
-.037,.0265,
-.036438,.032925,
-.034769,.039154,
-.032043,.044999,
-.028344,.050282,
-.023784,.054842,
-.018501,.058541,
-.012656,.061266,
-.0075,.06273,
270.*
4,1,20,.0075,.05555,
.0075,.06273,
.013677,.060878,
.019439,.057981,
.024611,.054127,
.029034,.049434,
.032576,.044045,
.035127,.038122,
.036612,.031846,
.037,.0265,
.037,.0075,
.03,.0075,
.03,.0265,
.029544,.03171,
.028191,.036762,
.02598,.041502,
.022981,.045786,
.019282,.049484,
.014998,.052484,
.010258,.054694,
.0075,.05555,
270.*
%
%ADD39MACRO39*%
%AMMACRO31*
4,1,36,.0025,0.0,
.002462,.000434,
.002349,.000855,
.002165,.00125,
.001915,.001607,
.001607,.001915,
.00125,.002165,
.000855,.002349,
.000434,.002462,
0.0,.0025,
-.000434,.002462,
-.000855,.002349,
-.00125,.002165,
-.001607,.001915,
-.001915,.001607,
-.002165,.00125,
-.002349,.000855,
-.002462,.000434,
-.0025,0.0,
-.002462,-.000434,
-.002349,-.000855,
-.002165,-.00125,
-.001915,-.001607,
-.001607,-.001915,
-.00125,-.002165,
-.000855,-.002349,
-.000434,-.002462,
0.0,-.0025,
.000434,-.002462,
.000855,-.002349,
.00125,-.002165,
.001607,-.001915,
.001915,-.001607,
.002165,-.00125,
.002349,-.000855,
.002462,-.000434,
.0025,0.0,
315.*
%
%ADD31MACRO31*%
%AMMACRO14*
4,1,36,.0025,0.0,
.002462,.000434,
.002349,.000855,
.002165,.00125,
.001915,.001607,
.001607,.001915,
.00125,.002165,
.000855,.002349,
.000434,.002462,
0.0,.0025,
-.000434,.002462,
-.000855,.002349,
-.00125,.002165,
-.001607,.001915,
-.001915,.001607,
-.002165,.00125,
-.002349,.000855,
-.002462,.000434,
-.0025,0.0,
-.002462,-.000434,
-.002349,-.000855,
-.002165,-.00125,
-.001915,-.001607,
-.001607,-.001915,
-.00125,-.002165,
-.000855,-.002349,
-.000434,-.002462,
0.0,-.0025,
.000434,-.002462,
.000855,-.002349,
.00125,-.002165,
.001607,-.001915,
.001915,-.001607,
.002165,-.00125,
.002349,-.000855,
.002462,-.000434,
.0025,0.0,
180.*
%
%ADD14MACRO14*%
%AMMACRO10*
4,1,36,.0025,0.0,
.002462,.000434,
.002349,.000855,
.002165,.00125,
.001915,.001607,
.001607,.001915,
.00125,.002165,
.000855,.002349,
.000434,.002462,
0.0,.0025,
-.000434,.002462,
-.000855,.002349,
-.00125,.002165,
-.001607,.001915,
-.001915,.001607,
-.002165,.00125,
-.002349,.000855,
-.002462,.000434,
-.0025,0.0,
-.002462,-.000434,
-.002349,-.000855,
-.002165,-.00125,
-.001915,-.001607,
-.001607,-.001915,
-.00125,-.002165,
-.000855,-.002349,
-.000434,-.002462,
0.0,-.0025,
.000434,-.002462,
.000855,-.002349,
.00125,-.002165,
.001607,-.001915,
.001915,-.001607,
.002165,-.00125,
.002349,-.000855,
.002462,-.000434,
.0025,0.0,
270.*
%
%ADD10MACRO10*%
%AMMACRO46*
4,1,36,-.0025,0.0,
-.002462,.000434,
-.002349,.000855,
-.002165,.00125,
-.001915,.001607,
-.001607,.001915,
-.00125,.002165,
-.000855,.002349,
-.000434,.002462,
0.0,.0025,
.000434,.002462,
.000855,.002349,
.00125,.002165,
.001607,.001915,
.001915,.001607,
.002165,.00125,
.002349,.000855,
.002462,.000434,
.0025,0.0,
.002462,-.000434,
.002349,-.000855,
.002165,-.00125,
.001915,-.001607,
.001607,-.001915,
.00125,-.002165,
.000855,-.002349,
.000434,-.002462,
0.0,-.0025,
-.000434,-.002462,
-.000855,-.002349,
-.00125,-.002165,
-.001607,-.001915,
-.001915,-.001607,
-.002165,-.00125,
-.002349,-.000855,
-.002462,-.000434,
-.0025,0.0,
180.*
%
%ADD46MACRO46*%
%AMMACRO37*
4,1,36,.003,0.0,
.002954,.000521,
.002819,.001026,
.002598,.0015,
.002298,.001928,
.001928,.002298,
.0015,.002598,
.001026,.002819,
.000521,.002954,
0.0,.003,
-.000521,.002954,
-.001026,.002819,
-.0015,.002598,
-.001928,.002298,
-.002298,.001928,
-.002598,.0015,
-.002819,.001026,
-.002954,.000521,
-.003,0.0,
-.002954,-.000521,
-.002819,-.001026,
-.002598,-.0015,
-.002298,-.001928,
-.001928,-.002298,
-.0015,-.002598,
-.001026,-.002819,
-.000521,-.002954,
0.0,-.003,
.000521,-.002954,
.001026,-.002819,
.0015,-.002598,
.001928,-.002298,
.002298,-.001928,
.002598,-.0015,
.002819,-.001026,
.002954,-.000521,
.003,0.0,
270.*
%
%ADD37MACRO37*%
%AMMACRO25*
4,1,36,.003,0.0,
.002954,.000521,
.002819,.001026,
.002598,.0015,
.002298,.001928,
.001928,.002298,
.0015,.002598,
.001026,.002819,
.000521,.002954,
0.0,.003,
-.000521,.002954,
-.001026,.002819,
-.0015,.002598,
-.001928,.002298,
-.002298,.001928,
-.002598,.0015,
-.002819,.001026,
-.002954,.000521,
-.003,0.0,
-.002954,-.000521,
-.002819,-.001026,
-.002598,-.0015,
-.002298,-.001928,
-.001928,-.002298,
-.0015,-.002598,
-.001026,-.002819,
-.000521,-.002954,
0.0,-.003,
.000521,-.002954,
.001026,-.002819,
.0015,-.002598,
.001928,-.002298,
.002298,-.001928,
.002598,-.0015,
.002819,-.001026,
.002954,-.000521,
.003,0.0,
180.*
%
%ADD25MACRO25*%
%ADD22C,.074*%
%AMMACRO42*
4,1,36,-.003,0.0,
-.002954,.000521,
-.002819,.001026,
-.002598,.0015,
-.002298,.001928,
-.001928,.002298,
-.0015,.002598,
-.001026,.002819,
-.000521,.002954,
0.0,.003,
.000521,.002954,
.001026,.002819,
.0015,.002598,
.001928,.002298,
.002298,.001928,
.002598,.0015,
.002819,.001026,
.002954,.000521,
.003,0.0,
.002954,-.000521,
.002819,-.001026,
.002598,-.0015,
.002298,-.001928,
.001928,-.002298,
.0015,-.002598,
.001026,-.002819,
.000521,-.002954,
0.0,-.003,
-.000521,-.002954,
-.001026,-.002819,
-.0015,-.002598,
-.001928,-.002298,
-.002298,-.001928,
-.002598,-.0015,
-.002819,-.001026,
-.002954,-.000521,
-.003,0.0,
180.*
%
%ADD42MACRO42*%
%ADD26C,.0435*%
%ADD35C,.0257*%
%ADD58C,.087*%
%ADD18C,.0277*%
%AMMACRO44*
4,1,18,.09673,.06845,
.107147,.050613,
.114308,.031238,
.117996,.010914,
.118098,-.009741,
.114613,-.030101,
.107644,-.049546,
.097406,-.067485,
.09673,-.06845,
.10175,-.07347,
.112962,-.054685,
.120742,-.034239,
.124853,-.012752,
.125171,.009122,
.121685,.030719,
.114502,.051383,
.10384,.070486,
.10175,.07347,
.09673,.06845,
90.*
4,1,18,.06845,-.09673,
.050613,-.107147,
.031238,-.114308,
.010914,-.117996,
-.009741,-.118098,
-.030101,-.114613,
-.049546,-.107644,
-.067485,-.097406,
-.06845,-.09673,
-.07347,-.10175,
-.054685,-.112962,
-.034239,-.120742,
-.012752,-.124853,
.009122,-.125171,
.030719,-.121685,
.051383,-.114502,
.070486,-.10384,
.07347,-.10175,
.06845,-.09673,
90.*
4,1,18,-.09673,-.06845,
-.107147,-.050613,
-.114308,-.031238,
-.117996,-.010914,
-.118098,.009741,
-.114613,.030101,
-.107644,.049546,
-.097406,.067485,
-.09673,.06845,
-.10175,.07347,
-.112962,.054685,
-.120742,.034239,
-.124853,.012752,
-.125171,-.009122,
-.121685,-.030719,
-.114502,-.051383,
-.10384,-.070486,
-.10175,-.07347,
-.09673,-.06845,
90.*
4,1,18,-.06845,.09673,
-.050613,.107147,
-.031238,.114308,
-.010914,.117996,
.009741,.118098,
.030101,.114613,
.049546,.107644,
.067485,.097406,
.06845,.09673,
.07347,.10175,
.054685,.112962,
.034239,.120742,
.012752,.124853,
-.009122,.125171,
-.030719,.121685,
-.051383,.114502,
-.070486,.10384,
-.07347,.10175,
-.06845,.09673,
90.*
%
%ADD44MACRO44*%
%AMMACRO11*
4,1,15,.06231,.03403,
.067273,.022693,
.070191,.010666,
.070977,-.001684,
.069606,-.013984,
.066121,-.025858,
.06231,-.03403,
.06745,-.03917,
.073227,-.026862,
.076779,-.013739,
.077998,-.000197,
.076848,.01335,
.073362,.026492,
.067647,.038828,
.06745,.03917,
.06231,.03403,
0.0*
4,1,15,.03403,-.06231,
.022693,-.067273,
.010666,-.070191,
-.001684,-.070977,
-.013984,-.069606,
-.025858,-.066121,
-.03403,-.06231,
-.03917,-.06745,
-.026862,-.073227,
-.013739,-.076779,
-.000197,-.077998,
.01335,-.076848,
.026492,-.073362,
.038828,-.067647,
.03917,-.06745,
.03403,-.06231,
0.0*
4,1,15,-.06231,-.03403,
-.067273,-.022693,
-.070191,-.010666,
-.070977,.001684,
-.069606,.013984,
-.066121,.025858,
-.06231,.03403,
-.06745,.03917,
-.073227,.026862,
-.076779,.013739,
-.077998,.000197,
-.076848,-.01335,
-.073362,-.026492,
-.067647,-.038828,
-.06745,-.03917,
-.06231,-.03403,
0.0*
4,1,15,-.03403,.06231,
-.022693,.067273,
-.010666,.070191,
.001684,.070977,
.013984,.069606,
.025858,.066121,
.03403,.06231,
.03917,.06745,
.026862,.073227,
.013739,.076779,
.000197,.077998,
-.01335,.076848,
-.026492,.073362,
-.038828,.067647,
-.03917,.06745,
-.03403,.06231,
0.0*
%
%ADD11MACRO11*%
%ADD20C,.099*%
%AMMACRO19*
4,1,18,.09673,.06845,
.107147,.050613,
.114308,.031238,
.117996,.010914,
.118098,-.009741,
.114613,-.030101,
.107644,-.049546,
.097406,-.067485,
.09673,-.06845,
.10175,-.07347,
.112962,-.054685,
.120742,-.034239,
.124853,-.012752,
.125171,.009122,
.121685,.030719,
.114502,.051383,
.10384,.070486,
.10175,.07347,
.09673,.06845,
0.0*
4,1,18,.06845,-.09673,
.050613,-.107147,
.031238,-.114308,
.010914,-.117996,
-.009741,-.118098,
-.030101,-.114613,
-.049546,-.107644,
-.067485,-.097406,
-.06845,-.09673,
-.07347,-.10175,
-.054685,-.112962,
-.034239,-.120742,
-.012752,-.124853,
.009122,-.125171,
.030719,-.121685,
.051383,-.114502,
.070486,-.10384,
.07347,-.10175,
.06845,-.09673,
0.0*
4,1,18,-.09673,-.06845,
-.107147,-.050613,
-.114308,-.031238,
-.117996,-.010914,
-.118098,.009741,
-.114613,.030101,
-.107644,.049546,
-.097406,.067485,
-.09673,.06845,
-.10175,.07347,
-.112962,.054685,
-.120742,.034239,
-.124853,.012752,
-.125171,-.009122,
-.121685,-.030719,
-.114502,-.051383,
-.10384,-.070486,
-.10175,-.07347,
-.09673,-.06845,
0.0*
4,1,18,-.06845,.09673,
-.050613,.107147,
-.031238,.114308,
-.010914,.117996,
.009741,.118098,
.030101,.114613,
.049546,.107644,
.067485,.097406,
.06845,.09673,
.07347,.10175,
.054685,.112962,
.034239,.120742,
.012752,.124853,
-.009122,.125171,
-.030719,.121685,
-.051383,.114502,
-.070486,.10384,
-.07347,.10175,
-.06845,.09673,
0.0*
%
%ADD19MACRO19*%
%ADD34C,.0299*%
%AMMACRO61*
4,1,19,-.0075,-.03785,
-.011528,-.036185,
-.015205,-.033846,
-.01842,-.030904,
-.021075,-.027448,
-.02309,-.023584,
-.024404,-.019428,
-.024975,-.015108,
-.025,-.014,
-.025,-.0075,
-.018,-.0075,
-.018,-.014,
-.017727,-.017125,
-.016915,-.020155,
-.015589,-.022998,
-.01379,-.025567,
-.011572,-.027785,
-.009002,-.029584,
-.0075,-.03036,
-.0075,-.03785,
180.*
4,1,19,.0075,-.03785,
.0075,-.03036,
.010227,-.02881,
.012643,-.02681,
.014676,-.024421,
.016262,-.021715,
.017355,-.018774,
.017921,-.015689,
.018,-.014,
.018,-.0075,
.025,-.0075,
.025,-.014,
.02462,-.018342,
.023492,-.022551,
.02165,-.026501,
.019151,-.030071,
.016069,-.033153,
.012499,-.035652,
.008549,-.037494,
.0075,-.03785,
180.*
4,1,19,-.025,.0075,
-.025,.014,
-.02462,.018342,
-.023492,.022551,
-.02165,.026501,
-.019151,.030071,
-.016069,.033153,
-.012499,.035652,
-.008549,.037494,
-.0075,.03785,
-.0075,.03036,
-.010227,.02881,
-.012643,.02681,
-.014676,.024421,
-.016262,.021715,
-.017355,.018774,
-.017921,.015689,
-.018,.014,
-.018,.0075,
-.025,.0075,
180.*
4,1,19,.018,.0075,
.018,.014,
.017727,.017125,
.016915,.020155,
.015589,.022998,
.01379,.025567,
.011572,.027785,
.009002,.029584,
.0075,.03036,
.0075,.03785,
.011528,.036185,
.015205,.033846,
.01842,.030904,
.021075,.027448,
.02309,.023584,
.024404,.019428,
.024975,.015108,
.025,.014,
.025,.0075,
.018,.0075,
180.*
%
%ADD61MACRO61*%
%AMMACRO38*
4,1,16,.02584,.01524,
.028094,.010521,
.029494,.005483,
.029998,.000278,
.029591,-.004935,
.028284,-.009999,
.026118,-.014758,
.02584,-.01524,
.03092,-.02032,
.033979,-.014642,
.036005,-.008519,
.036938,-.002138,
.036748,.004309,
.035441,.010625,
.033058,.016618,
.03092,.02032,
.02584,.01524,
0.0*
4,1,16,.01524,-.02584,
.010521,-.028094,
.005483,-.029494,
.000278,-.029998,
-.004935,-.029591,
-.009999,-.028284,
-.014758,-.026118,
-.01524,-.02584,
-.02032,-.03092,
-.014642,-.033979,
-.008519,-.036005,
-.002138,-.036938,
.004309,-.036748,
.010625,-.035441,
.016618,-.033058,
.02032,-.03092,
.01524,-.02584,
0.0*
4,1,16,-.02584,-.01524,
-.028094,-.010521,
-.029494,-.005483,
-.029998,-.000278,
-.029591,.004935,
-.028284,.009999,
-.026118,.014758,
-.02584,.01524,
-.03092,.02032,
-.033979,.014642,
-.036005,.008519,
-.036938,.002138,
-.036748,-.004309,
-.035441,-.010625,
-.033058,-.016618,
-.03092,-.02032,
-.02584,-.01524,
0.0*
4,1,16,-.01524,.02584,
-.010521,.028094,
-.005483,.029494,
-.000278,.029998,
.004935,.029591,
.009999,.028284,
.014758,.026118,
.01524,.02584,
.02032,.03092,
.014642,.033979,
.008519,.036005,
.002138,.036938,
-.004309,.036748,
-.010625,.035441,
-.016618,.033058,
-.02032,.03092,
-.01524,.02584,
0.0*
%
%ADD38MACRO38*%
%AMMACRO50*
4,1,15,.02142,.01082,
.022973,.006936,
.023829,.002841,
.02396,-.00134,
.023364,-.00548,
.022057,-.009454,
.02142,-.01082,
.02657,-.01597,
.02894,-.011114,
.03043,-.005919,
.030995,-.000545,
.030619,.004845,
.029313,.010088,
.027115,.015025,
.02657,.01597,
.02142,.01082,
90.*
4,1,15,.01082,-.02142,
.006936,-.022973,
.002841,-.023829,
-.00134,-.02396,
-.00548,-.023364,
-.009454,-.022057,
-.01082,-.02142,
-.01597,-.02657,
-.011114,-.02894,
-.005919,-.03043,
-.000545,-.030995,
.004845,-.030619,
.010088,-.029313,
.015025,-.027115,
.01597,-.02657,
.01082,-.02142,
90.*
4,1,15,-.02142,-.01082,
-.022973,-.006936,
-.023829,-.002841,
-.02396,.00134,
-.023364,.00548,
-.022057,.009454,
-.02142,.01082,
-.02657,.01597,
-.02894,.011114,
-.03043,.005919,
-.030995,.000545,
-.030619,-.004845,
-.029313,-.010088,
-.027115,-.015025,
-.02657,-.01597,
-.02142,-.01082,
90.*
4,1,15,-.01082,.02142,
-.006936,.022973,
-.002841,.023829,
.00134,.02396,
.00548,.023364,
.009454,.022057,
.01082,.02142,
.01597,.02657,
.011114,.02894,
.005919,.03043,
.000545,.030995,
-.004845,.030619,
-.010088,.029313,
-.015025,.027115,
-.01597,.02657,
-.01082,.02142,
90.*
%
%ADD50MACRO50*%
%AMMACRO48*
4,1,18,.07103,.05689,
.07983,.043691,
.086204,.029165,
.089959,.013753,
.09098,-.002077,
.089237,-.017844,
.084783,-.033069,
.077753,-.047289,
.07103,-.05689,
.07601,-.06186,
.085597,-.047721,
.092583,-.032132,
.096757,-.015567,
.09799,.001471,
.096246,.018464,
.091577,.034897,
.084126,.050269,
.07601,.06186,
.07103,.05689,
90.*
4,1,18,.05689,-.07103,
.043691,-.07983,
.029165,-.086204,
.013753,-.089959,
-.002077,-.09098,
-.017844,-.089237,
-.033069,-.084783,
-.047289,-.077753,
-.05689,-.07103,
-.06186,-.07601,
-.047721,-.085597,
-.032132,-.092583,
-.015567,-.096757,
.001471,-.09799,
.018464,-.096246,
.034897,-.091577,
.050269,-.084126,
.06186,-.07601,
.05689,-.07103,
90.*
4,1,18,-.07103,-.05689,
-.07983,-.043691,
-.086204,-.029165,
-.089959,-.013753,
-.09098,.002077,
-.089237,.017844,
-.084783,.033069,
-.077753,.047289,
-.07103,.05689,
-.07601,.06186,
-.085597,.047721,
-.092583,.032132,
-.096757,.015567,
-.09799,-.001471,
-.096246,-.018464,
-.091577,-.034897,
-.084126,-.050269,
-.07601,-.06186,
-.07103,-.05689,
90.*
4,1,18,-.05689,.07103,
-.043691,.07983,
-.029165,.086204,
-.013753,.089959,
.002077,.09098,
.017844,.089237,
.033069,.084783,
.047289,.077753,
.05689,.07103,
.06186,.07601,
.047721,.085597,
.032132,.092583,
.015567,.096757,
-.001471,.09799,
-.018464,.096246,
-.034897,.091577,
-.050269,.084126,
-.06186,.07601,
-.05689,.07103,
90.*
%
%ADD48MACRO48*%
%AMMACRO62*
4,1,19,-.0075,-.04535,
-.011528,-.043685,
-.015205,-.041346,
-.01842,-.038404,
-.021075,-.034948,
-.02309,-.031084,
-.024404,-.026928,
-.024975,-.022608,
-.025,-.0215,
-.025,-.0075,
-.018,-.0075,
-.018,-.0215,
-.017727,-.024625,
-.016915,-.027655,
-.015589,-.030498,
-.01379,-.033067,
-.011572,-.035285,
-.009002,-.037084,
-.0075,-.03786,
-.0075,-.04535,
180.*
4,1,19,.0075,-.04535,
.0075,-.03786,
.010227,-.03631,
.012643,-.03431,
.014676,-.031921,
.016262,-.029215,
.017355,-.026274,
.017921,-.023189,
.018,-.0215,
.018,-.0075,
.025,-.0075,
.025,-.0215,
.02462,-.025842,
.023492,-.030051,
.02165,-.034001,
.019151,-.037571,
.016069,-.040653,
.012499,-.043152,
.008549,-.044994,
.0075,-.04535,
180.*
4,1,19,-.025,.0075,
-.025,.0215,
-.02462,.025842,
-.023492,.030051,
-.02165,.034001,
-.019151,.037571,
-.016069,.040653,
-.012499,.043152,
-.008549,.044994,
-.0075,.04535,
-.0075,.03786,
-.010227,.03631,
-.012643,.03431,
-.014676,.031921,
-.016262,.029215,
-.017355,.026274,
-.017921,.023189,
-.018,.0215,
-.018,.0075,
-.025,.0075,
180.*
4,1,19,.018,.0075,
.018,.0215,
.017727,.024625,
.016915,.027655,
.015589,.030498,
.01379,.033067,
.011572,.035285,
.009002,.037084,
.0075,.03786,
.0075,.04535,
.011528,.043685,
.015205,.041346,
.01842,.038404,
.021075,.034948,
.02309,.031084,
.024404,.026928,
.024975,.022608,
.025,.0215,
.025,.0075,
.018,.0075,
180.*
%
%ADD62MACRO62*%
%AMMACRO55*
4,1,15,.02475,.01414,
.026829,.009627,
.028094,.004822,
.028504,-.000129,
.028049,-.005077,
.026741,-.009871,
.02475,-.01414,
.02984,-.01923,
.032726,-.013756,
.034617,-.007864,
.035457,-.001734,
.03522,.00445,
.033912,.010498,
.031574,.016227,
.02984,.01923,
.02475,.01414,
0.0*
4,1,15,.01414,-.02475,
.009627,-.026829,
.004822,-.028094,
-.000129,-.028504,
-.005077,-.028049,
-.009871,-.026741,
-.01414,-.02475,
-.01923,-.02984,
-.013756,-.032726,
-.007864,-.034617,
-.001734,-.035457,
.00445,-.03522,
.010498,-.033912,
.016227,-.031574,
.01923,-.02984,
.01414,-.02475,
0.0*
4,1,15,-.02475,-.01414,
-.026829,-.009627,
-.028094,-.004822,
-.028504,.000129,
-.028049,.005077,
-.026741,.009871,
-.02475,.01414,
-.02984,.01923,
-.032726,.013756,
-.034617,.007864,
-.035457,.001734,
-.03522,-.00445,
-.033912,-.010498,
-.031574,-.016227,
-.02984,-.01923,
-.02475,-.01414,
0.0*
4,1,15,-.01414,.02475,
-.009627,.026829,
-.004822,.028094,
.000129,.028504,
.005077,.028049,
.009871,.026741,
.01414,.02475,
.01923,.02984,
.013756,.032726,
.007864,.034617,
.001734,.035457,
-.00445,.03522,
-.010498,.033912,
-.016227,.031574,
-.01923,.02984,
-.01414,.02475,
0.0*
%
%ADD55MACRO55*%
%AMMACRO59*
4,1,15,.03682,.01914,
.039584,.012455,
.041146,.005393,
.041457,-.001834,
.040509,-.009005,
.03833,-.015903,
.03682,-.01914,
.04197,-.0243,
.045552,-.016643,
.04775,-.00848,
.048497,-.000059,
.047771,.008363,
.045593,.016531,
.042029,.024197,
.04197,.0243,
.03682,.01914,
90.*
4,1,15,.01914,-.03682,
.012455,-.039584,
.005393,-.041146,
-.001834,-.041457,
-.009005,-.040509,
-.015903,-.03833,
-.01914,-.03682,
-.0243,-.04197,
-.016643,-.045552,
-.00848,-.04775,
-.000059,-.048497,
.008363,-.047771,
.016531,-.045593,
.024197,-.042029,
.0243,-.04197,
.01914,-.03682,
90.*
4,1,15,-.03682,-.01914,
-.039584,-.012455,
-.041146,-.005393,
-.041457,.001834,
-.040509,.009005,
-.03833,.015903,
-.03682,.01914,
-.04197,.0243,
-.045552,.016643,
-.04775,.00848,
-.048497,.000059,
-.047771,-.008363,
-.045593,-.016531,
-.042029,-.024197,
-.04197,-.0243,
-.03682,-.01914,
90.*
4,1,15,-.01914,.03682,
-.012455,.039584,
-.005393,.041146,
.001834,.041457,
.009005,.040509,
.015903,.03833,
.01914,.03682,
.0243,.04197,
.016643,.045552,
.00848,.04775,
.000059,.048497,
-.008363,.047771,
-.016531,.045593,
-.024197,.042029,
-.0243,.04197,
-.01914,.03682,
90.*
%
%ADD59MACRO59*%
%AMMACRO60*
4,1,15,-.03682,.01914,
-.039584,.012455,
-.041146,.005393,
-.041457,-.001834,
-.040509,-.009005,
-.03833,-.015903,
-.03682,-.01914,
-.04197,-.0243,
-.045552,-.016643,
-.04775,-.00848,
-.048497,-.000059,
-.047771,.008363,
-.045593,.016531,
-.042029,.024197,
-.04197,.0243,
-.03682,.01914,
90.*
4,1,15,-.01914,-.03682,
-.012455,-.039584,
-.005393,-.041146,
.001834,-.041457,
.009005,-.040509,
.015903,-.03833,
.01914,-.03682,
.0243,-.04197,
.016643,-.045552,
.00848,-.04775,
.000059,-.048497,
-.008363,-.047771,
-.016531,-.045593,
-.024197,-.042029,
-.0243,-.04197,
-.01914,-.03682,
90.*
4,1,15,.03682,-.01914,
.039584,-.012455,
.041146,-.005393,
.041457,.001834,
.040509,.009005,
.03833,.015903,
.03682,.01914,
.04197,.0243,
.045552,.016643,
.04775,.00848,
.048497,.000059,
.047771,-.008363,
.045593,-.016531,
.042029,-.024197,
.04197,-.0243,
.03682,-.01914,
90.*
4,1,15,.01914,.03682,
.012455,.039584,
.005393,.041146,
-.001834,.041457,
-.009005,.040509,
-.015903,.03833,
-.01914,.03682,
-.0243,.04197,
-.016643,.045552,
-.00848,.04775,
-.000059,.048497,
.008363,.047771,
.016531,.045593,
.024197,.042029,
.0243,.04197,
.01914,.03682,
90.*
%
%ADD60MACRO60*%
%ADD63C,.142*%
%ADD13C,.125*%
%ADD30C,.208*%
%ADD47C,.164*%
%ADD17C,.155*%
%ADD40C,.256*%
%AMMACRO32*
4,1,36,0.0,.0085,
.001476,.008371,
.002907,.007987,
.00425,.007361,
.005464,.006511,
.006511,.005464,
.007361,.00425,
.007987,.002907,
.008371,.001476,
.0085,0.0,
.008371,-.001476,
.007987,-.002907,
.007361,-.00425,
.006511,-.005464,
.005464,-.006511,
.00425,-.007361,
.002907,-.007987,
.001476,-.008371,
0.0,-.0085,
-.001476,-.008371,
-.002907,-.007987,
-.00425,-.007361,
-.005464,-.006511,
-.006511,-.005464,
-.007361,-.00425,
-.007987,-.002907,
-.008371,-.001476,
-.0085,0.0,
-.008371,.001476,
-.007987,.002907,
-.007361,.00425,
-.006511,.005464,
-.005464,.006511,
-.00425,.007361,
-.002907,.007987,
-.001476,.008371,
0.0,.0085,
180.*
%
%ADD32MACRO32*%
%AMMACRO49*
4,1,36,0.0,.0185,
-.003212,.018219,
-.006327,.017384,
-.00925,.016021,
-.011892,.014172,
-.014172,.011892,
-.016021,.00925,
-.017384,.006327,
-.018219,.003212,
-.0185,0.0,
-.018219,-.003212,
-.017384,-.006327,
-.016021,-.00925,
-.014172,-.011892,
-.011892,-.014172,
-.00925,-.016021,
-.006327,-.017384,
-.003212,-.018219,
0.0,-.0185,
.003212,-.018219,
.006327,-.017384,
.00925,-.016021,
.011892,-.014172,
.014172,-.011892,
.016021,-.00925,
.017384,-.006327,
.018219,-.003212,
.0185,0.0,
.018219,.003212,
.017384,.006327,
.016021,.00925,
.014172,.011892,
.011892,.014172,
.00925,.016021,
.006327,.017384,
.003212,.018219,
0.0,.0185,
270.*
%
%ADD49MACRO49*%
%AMMACRO21*
4,1,20,-.0075,-.05555,
-.0075,-.06273,
-.013677,-.060878,
-.019439,-.057981,
-.024611,-.054127,
-.029034,-.049434,
-.032576,-.044045,
-.035127,-.038122,
-.036612,-.031846,
-.037,-.0265,
-.037,-.0075,
-.03,-.0075,
-.03,-.0265,
-.029544,-.03171,
-.028191,-.036762,
-.02598,-.041502,
-.022981,-.045786,
-.019282,-.049484,
-.014998,-.052484,
-.010258,-.054694,
-.0075,-.05555,
90.*
4,1,20,.0075,-.06273,
.0075,-.05555,
.01243,-.053806,
.016983,-.051232,
.02102,-.047906,
.024418,-.043931,
.027073,-.039425,
.028906,-.034527,
.029861,-.029385,
.03,-.0265,
.03,-.0075,
.037,-.0075,
.037,-.0265,
.036438,-.032925,
.034769,-.039154,
.032043,-.044999,
.028344,-.050282,
.023784,-.054842,
.018501,-.058541,
.012656,-.061266,
.0075,-.06273,
90.*
4,1,20,-.0075,.06273,
-.0075,.05555,
-.01243,.053806,
-.016983,.051232,
-.02102,.047906,
-.024418,.043931,
-.027073,.039425,
-.028906,.034527,
-.029861,.029385,
-.03,.0265,
-.03,.0075,
-.037,.0075,
-.037,.0265,
-.036438,.032925,
-.034769,.039154,
-.032043,.044999,
-.028344,.050282,
-.023784,.054842,
-.018501,.058541,
-.012656,.061266,
-.0075,.06273,
90.*
4,1,20,.0075,.05555,
.0075,.06273,
.013677,.060878,
.019439,.057981,
.024611,.054127,
.029034,.049434,
.032576,.044045,
.035127,.038122,
.036612,.031846,
.037,.0265,
.037,.0075,
.03,.0075,
.03,.0265,
.029544,.03171,
.028191,.036762,
.02598,.041502,
.022981,.045786,
.019282,.049484,
.014998,.052484,
.010258,.054694,
.0075,.05555,
90.*
%
%ADD21MACRO21*%
%AMMACRO16*
4,1,36,.0025,0.0,
.002462,.000434,
.002349,.000855,
.002165,.00125,
.001915,.001607,
.001607,.001915,
.00125,.002165,
.000855,.002349,
.000434,.002462,
0.0,.0025,
-.000434,.002462,
-.000855,.002349,
-.00125,.002165,
-.001607,.001915,
-.001915,.001607,
-.002165,.00125,
-.002349,.000855,
-.002462,.000434,
-.0025,0.0,
-.002462,-.000434,
-.002349,-.000855,
-.002165,-.00125,
-.001915,-.001607,
-.001607,-.001915,
-.00125,-.002165,
-.000855,-.002349,
-.000434,-.002462,
0.0,-.0025,
.000434,-.002462,
.000855,-.002349,
.00125,-.002165,
.001607,-.001915,
.001915,-.001607,
.002165,-.00125,
.002349,-.000855,
.002462,-.000434,
.0025,0.0,
90.*
%
%ADD16MACRO16*%
%AMMACRO36*
4,1,36,.003,0.0,
.002954,.000521,
.002819,.001026,
.002598,.0015,
.002298,.001928,
.001928,.002298,
.0015,.002598,
.001026,.002819,
.000521,.002954,
0.0,.003,
-.000521,.002954,
-.001026,.002819,
-.0015,.002598,
-.001928,.002298,
-.002298,.001928,
-.002598,.0015,
-.002819,.001026,
-.002954,.000521,
-.003,0.0,
-.002954,-.000521,
-.002819,-.001026,
-.002598,-.0015,
-.002298,-.001928,
-.001928,-.002298,
-.0015,-.002598,
-.001026,-.002819,
-.000521,-.002954,
0.0,-.003,
.000521,-.002954,
.001026,-.002819,
.0015,-.002598,
.001928,-.002298,
.002298,-.001928,
.002598,-.0015,
.002819,-.001026,
.002954,-.000521,
.003,0.0,
90.*
%
%ADD36MACRO36*%
%AMMACRO12*
4,1,36,.0025,0.0,
.002462,.000434,
.002349,.000855,
.002165,.00125,
.001915,.001607,
.001607,.001915,
.00125,.002165,
.000855,.002349,
.000434,.002462,
0.0,.0025,
-.000434,.002462,
-.000855,.002349,
-.00125,.002165,
-.001607,.001915,
-.001915,.001607,
-.002165,.00125,
-.002349,.000855,
-.002462,.000434,
-.0025,0.0,
-.002462,-.000434,
-.002349,-.000855,
-.002165,-.00125,
-.001915,-.001607,
-.001607,-.001915,
-.00125,-.002165,
-.000855,-.002349,
-.000434,-.002462,
0.0,-.0025,
.000434,-.002462,
.000855,-.002349,
.00125,-.002165,
.001607,-.001915,
.001915,-.001607,
.002165,-.00125,
.002349,-.000855,
.002462,-.000434,
.0025,0.0,
0.0*
%
%ADD12MACRO12*%
%AMMACRO52*
4,1,36,-.0025,0.0,
-.002462,.000434,
-.002349,.000855,
-.002165,.00125,
-.001915,.001607,
-.001607,.001915,
-.00125,.002165,
-.000855,.002349,
-.000434,.002462,
0.0,.0025,
.000434,.002462,
.000855,.002349,
.00125,.002165,
.001607,.001915,
.001915,.001607,
.002165,.00125,
.002349,.000855,
.002462,.000434,
.0025,0.0,
.002462,-.000434,
.002349,-.000855,
.002165,-.00125,
.001915,-.001607,
.001607,-.001915,
.00125,-.002165,
.000855,-.002349,
.000434,-.002462,
0.0,-.0025,
-.000434,-.002462,
-.000855,-.002349,
-.00125,-.002165,
-.001607,-.001915,
-.001915,-.001607,
-.002165,-.00125,
-.002349,-.000855,
-.002462,-.000434,
-.0025,0.0,
0.0*
%
%ADD52MACRO52*%
%AMMACRO27*
4,1,36,.003,0.0,
.002954,.000521,
.002819,.001026,
.002598,.0015,
.002298,.001928,
.001928,.002298,
.0015,.002598,
.001026,.002819,
.000521,.002954,
0.0,.003,
-.000521,.002954,
-.001026,.002819,
-.0015,.002598,
-.001928,.002298,
-.002298,.001928,
-.002598,.0015,
-.002819,.001026,
-.002954,.000521,
-.003,0.0,
-.002954,-.000521,
-.002819,-.001026,
-.002598,-.0015,
-.002298,-.001928,
-.001928,-.002298,
-.0015,-.002598,
-.001026,-.002819,
-.000521,-.002954,
0.0,-.003,
.000521,-.002954,
.001026,-.002819,
.0015,-.002598,
.001928,-.002298,
.002298,-.001928,
.002598,-.0015,
.002819,-.001026,
.002954,-.000521,
.003,0.0,
0.0*
%
%ADD27MACRO27*%
%AMMACRO24*
4,1,36,-.003,0.0,
-.002954,.000521,
-.002819,.001026,
-.002598,.0015,
-.002298,.001928,
-.001928,.002298,
-.0015,.002598,
-.001026,.002819,
-.000521,.002954,
0.0,.003,
.000521,.002954,
.001026,.002819,
.0015,.002598,
.001928,.002298,
.002298,.001928,
.002598,.0015,
.002819,.001026,
.002954,.000521,
.003,0.0,
.002954,-.000521,
.002819,-.001026,
.002598,-.0015,
.002298,-.001928,
.001928,-.002298,
.0015,-.002598,
.001026,-.002819,
.000521,-.002954,
0.0,-.003,
-.000521,-.002954,
-.001026,-.002819,
-.0015,-.002598,
-.001928,-.002298,
-.002298,-.001928,
-.002598,-.0015,
-.002819,-.001026,
-.002954,-.000521,
-.003,0.0,
0.0*
%
%ADD24MACRO24*%
%AMMACRO41*
4,1,16,.02584,.01524,
.028094,.010521,
.029494,.005483,
.029998,.000278,
.029591,-.004935,
.028284,-.009999,
.026118,-.014758,
.02584,-.01524,
.03092,-.02032,
.033979,-.014642,
.036005,-.008519,
.036938,-.002138,
.036748,.004309,
.035441,.010625,
.033058,.016618,
.03092,.02032,
.02584,.01524,
180.*
4,1,16,.01524,-.02584,
.010521,-.028094,
.005483,-.029494,
.000278,-.029998,
-.004935,-.029591,
-.009999,-.028284,
-.014758,-.026118,
-.01524,-.02584,
-.02032,-.03092,
-.014642,-.033979,
-.008519,-.036005,
-.002138,-.036938,
.004309,-.036748,
.010625,-.035441,
.016618,-.033058,
.02032,-.03092,
.01524,-.02584,
180.*
4,1,16,-.02584,-.01524,
-.028094,-.010521,
-.029494,-.005483,
-.029998,-.000278,
-.029591,.004935,
-.028284,.009999,
-.026118,.014758,
-.02584,.01524,
-.03092,.02032,
-.033979,.014642,
-.036005,.008519,
-.036938,.002138,
-.036748,-.004309,
-.035441,-.010625,
-.033058,-.016618,
-.03092,-.02032,
-.02584,-.01524,
180.*
4,1,16,-.01524,.02584,
-.010521,.028094,
-.005483,.029494,
-.000278,.029998,
.004935,.029591,
.009999,.028284,
.014758,.026118,
.01524,.02584,
.02032,.03092,
.014642,.033979,
.008519,.036005,
.002138,.036938,
-.004309,.036748,
-.010625,.035441,
-.016618,.033058,
-.02032,.03092,
-.01524,.02584,
180.*
%
%ADD41MACRO41*%
%AMMACRO56*
4,1,15,.03682,.01914,
.039584,.012455,
.041146,.005393,
.041457,-.001834,
.040509,-.009005,
.03833,-.015903,
.03682,-.01914,
.04197,-.0243,
.045552,-.016643,
.04775,-.00848,
.048497,-.000059,
.047771,.008363,
.045593,.016531,
.042029,.024197,
.04197,.0243,
.03682,.01914,
270.*
4,1,15,.01914,-.03682,
.012455,-.039584,
.005393,-.041146,
-.001834,-.041457,
-.009005,-.040509,
-.015903,-.03833,
-.01914,-.03682,
-.0243,-.04197,
-.016643,-.045552,
-.00848,-.04775,
-.000059,-.048497,
.008363,-.047771,
.016531,-.045593,
.024197,-.042029,
.0243,-.04197,
.01914,-.03682,
270.*
4,1,15,-.03682,-.01914,
-.039584,-.012455,
-.041146,-.005393,
-.041457,.001834,
-.040509,.009005,
-.03833,.015903,
-.03682,.01914,
-.04197,.0243,
-.045552,.016643,
-.04775,.00848,
-.048497,.000059,
-.047771,-.008363,
-.045593,-.016531,
-.042029,-.024197,
-.04197,-.0243,
-.03682,-.01914,
270.*
4,1,15,-.01914,.03682,
-.012455,.039584,
-.005393,.041146,
.001834,.041457,
.009005,.040509,
.015903,.03833,
.01914,.03682,
.0243,.04197,
.016643,.045552,
.00848,.04775,
.000059,.048497,
-.008363,.047771,
-.016531,.045593,
-.024197,.042029,
-.0243,.04197,
-.01914,.03682,
270.*
%
%ADD56MACRO56*%
%AMMACRO57*
4,1,15,-.03682,.01914,
-.039584,.012455,
-.041146,.005393,
-.041457,-.001834,
-.040509,-.009005,
-.03833,-.015903,
-.03682,-.01914,
-.04197,-.0243,
-.045552,-.016643,
-.04775,-.00848,
-.048497,-.000059,
-.047771,.008363,
-.045593,.016531,
-.042029,.024197,
-.04197,.0243,
-.03682,.01914,
270.*
4,1,15,-.01914,-.03682,
-.012455,-.039584,
-.005393,-.041146,
.001834,-.041457,
.009005,-.040509,
.015903,-.03833,
.01914,-.03682,
.0243,-.04197,
.016643,-.045552,
.00848,-.04775,
.000059,-.048497,
-.008363,-.047771,
-.016531,-.045593,
-.024197,-.042029,
-.0243,-.04197,
-.01914,-.03682,
270.*
4,1,15,.03682,-.01914,
.039584,-.012455,
.041146,-.005393,
.041457,.001834,
.040509,.009005,
.03833,.015903,
.03682,.01914,
.04197,.0243,
.045552,.016643,
.04775,.00848,
.048497,.000059,
.047771,-.008363,
.045593,-.016531,
.042029,-.024197,
.04197,-.0243,
.03682,-.01914,
270.*
4,1,15,.01914,.03682,
.012455,.039584,
.005393,.041146,
-.001834,.041457,
-.009005,.040509,
-.015903,.03833,
-.01914,.03682,
-.0243,.04197,
-.016643,.045552,
-.00848,.04775,
-.000059,.048497,
.008363,.047771,
.016531,.045593,
.024197,.042029,
.0243,.04197,
.01914,.03682,
270.*
%
%ADD57MACRO57*%
%ADD64C,.006*%
%ADD76C,.03006*%
%ADD82C,.02404*%
%ADD80C,.07005*%
%ADD73C,.08404*%
%ADD66C,.07306*%
%ADD79C,.09208*%
%ADD74C,.07606*%
%ADD72C,.08408*%
%ADD78C,.07608*%
%ADD71C,.08409*%
%ADD70O,.1621X.2251*%
%ADD69O,.03604X.07004*%
%ADD67O,.03006X.06406*%
%ADD81C,.16206*%
%ADD68O,.03606X.07006*%
%ADD77C,.17406*%
%ADD65C,.16506*%
%ADD75C,.21786*%
G75*
%LPD*%
G75*
G36*
G01X-1490433Y-1677216D02*
X4496476D01*
Y3837819D01*
X-1490433D01*
Y-1677216D01*
G37*
%LPC*%
G75*
G36*
G01X630370Y-100983D02*
G02X624496Y-95109I0J5874D01*
G01Y-32983D01*
G03X614622Y-23109I-9874J0D01*
G01X68874D01*
G03X59000Y-32983I0J-9874D01*
G01Y-95109D01*
G02X53126Y-100983I-5874J0D01*
G01X7874D01*
G02X2000Y-95109I0J5874D01*
G01Y-15748D01*
G02X7874Y-9874I5874J0D01*
G01X31358D01*
G03X41232Y0I0J9874D01*
G01Y34843D01*
G02X47106Y40717I5874J0D01*
G01X54980D01*
G02X60854Y34843I0J-5874D01*
G01Y0D01*
G03X70728Y-9874I9874J0D01*
G01X133720D01*
G03X143594Y0I0J9874D01*
G01Y34843D01*
G02X149468Y40717I5874J0D01*
G01X157343D01*
G02X163217Y34843I0J-5874D01*
G01Y0D01*
G03X173091Y-9874I9874J0D01*
G01X236083D01*
G03X245957Y0I0J9874D01*
G01Y34843D01*
G02X251831Y40717I5874J0D01*
G01X259705D01*
G02X265579Y34843I0J-5874D01*
G01Y0D01*
G03X275453Y-9874I9874J0D01*
G01X338445D01*
G03X348319Y0I0J9874D01*
G01Y34843D01*
G02X354193Y40717I5874J0D01*
G01X362067D01*
G02X367941Y34843I0J-5874D01*
G01Y0D01*
G03X377815Y-9874I9874J0D01*
G01X488445D01*
G03X498319Y0I0J9874D01*
G01Y34843D01*
G02X504193Y40717I5874J0D01*
G01X512067D01*
G02X517941Y34843I0J-5874D01*
G01Y0D01*
G03X527815Y-9874I9874J0D01*
G01X590807D01*
G03X600681Y0I0J9874D01*
G01Y34843D01*
G02X606555Y40717I5874J0D01*
G01X614429D01*
G02X620303Y34843I0J-5874D01*
G01Y0D01*
G03X630177Y-9874I9874J0D01*
G01X693169D01*
G03X703043Y0I0J9874D01*
G01Y34843D01*
G02X708917Y40717I5874J0D01*
G01X716791D01*
G02X722665Y34843I0J-5874D01*
G01Y0D01*
G03X732539Y-9874I9874J0D01*
G01X795531D01*
G03X805405Y0I0J9874D01*
G01Y34843D01*
G02X811279Y40717I5874J0D01*
G01X819154D01*
G02X825028Y34843I0J-5874D01*
G01Y0D01*
G03X834902Y-9874I9874J0D01*
G01X945531D01*
G03X955405Y0I0J9874D01*
G01Y34843D01*
G02X961279Y40717I5874J0D01*
G01X969154D01*
G02X975028Y34843I0J-5874D01*
G01Y0D01*
G03X984902Y-9874I9874J0D01*
G01X1047894D01*
G03X1057768Y0I0J9874D01*
G01Y34843D01*
G02X1063642Y40717I5874J0D01*
G01X1071516D01*
G02X1077390Y34843I0J-5874D01*
G01Y0D01*
G03X1087264Y-9874I9874J0D01*
G01X1150256D01*
G03X1160130Y0I0J9874D01*
G01Y34843D01*
G02X1166004Y40717I5874J0D01*
G01X1173878D01*
G02X1179752Y34843I0J-5874D01*
G01Y0D01*
G03X1189626Y-9874I9874J0D01*
G01X1252618D01*
G03X1262492Y0I0J9874D01*
G01Y34843D01*
G02X1268366Y40717I5874J0D01*
G01X1276240D01*
G02X1282114Y34843I0J-5874D01*
G01Y0D01*
G03X1291988Y-9874I9874J0D01*
G01X1402618D01*
G03X1412492Y0I0J9874D01*
G01Y34843D01*
G02X1418366Y40717I5874J0D01*
G01X1426240D01*
G02X1432114Y34843I0J-5874D01*
G01Y0D01*
G03X1441988Y-9874I9874J0D01*
G01X1504980D01*
G03X1514854Y0I0J9874D01*
G01Y34843D01*
G02X1520728Y40717I5874J0D01*
G01X1528602D01*
G02X1534476Y34843I0J-5874D01*
G01Y0D01*
G03X1544350Y-9874I9874J0D01*
G01X1607343D01*
G03X1617217Y0I0J9874D01*
G01Y34843D01*
G02X1623091Y40717I5874J0D01*
G01X1630965D01*
G02X1636839Y34843I0J-5874D01*
G01Y0D01*
G03X1646713Y-9874I9874J0D01*
G01X1709705D01*
G03X1719579Y0I0J9874D01*
G01Y34843D01*
G02X1725453Y40717I5874J0D01*
G01X1733327D01*
G02X1739201Y34843I0J-5874D01*
G01Y0D01*
G03X1749075Y-9874I9874J0D01*
G01X1833071D01*
G02X1838945Y-15748I0J-5874D01*
G01Y-95109D01*
G02X1833071Y-100983I-5874J0D01*
G01X630370D01*
G37*
G36*
G01X1833071Y1645992D02*
G02X1838945Y1640118I0J-5874D01*
G01Y970425D01*
G02X1837225Y966273I-5874J1D01*
G01X1826876Y955925D01*
G03X1823984Y948943I6982J-6982D01*
G01Y344836D01*
G03X1826876Y337855I9873J0D01*
G01X1837225Y327506D01*
G02X1838945Y323354I-4153J-4153D01*
G01Y7874D01*
G02X1833071Y2000I-5874J0D01*
G01X1756949D01*
G02X1751075Y7874I0J5874D01*
G01Y46654D01*
G03X1745138Y52591I-5937J0D01*
G01X1713642D01*
G03X1707705Y46654I0J-5937D01*
G01Y7874D01*
G02X1701831Y2000I-5874J0D01*
G01X1654587D01*
G02X1648713Y7874I0J5874D01*
G01Y46654D01*
G03X1642776Y52591I-5937J0D01*
G01X1611280D01*
G03X1605343Y46654I0J-5937D01*
G01Y7874D01*
G02X1599469Y2000I-5874J0D01*
G01X1552224D01*
G02X1546350Y7874I0J5874D01*
G01Y46654D01*
G03X1540413Y52591I-5937J0D01*
G01X1508917D01*
G03X1502980Y46654I0J-5937D01*
G01Y7874D01*
G02X1497106Y2000I-5874J0D01*
G01X1449862D01*
G02X1443988Y7874I0J5874D01*
G01Y46654D01*
G03X1438051Y52591I-5937J0D01*
G01X1406555D01*
G03X1400618Y46654I0J-5937D01*
G01Y7874D01*
G02X1394744Y2000I-5874J0D01*
G01X1299862D01*
G02X1293988Y7874I0J5874D01*
G01Y46654D01*
G03X1288051Y52591I-5937J0D01*
G01X1256555D01*
G03X1250618Y46654I0J-5937D01*
G01Y7874D01*
G02X1244744Y2000I-5874J0D01*
G01X1197500D01*
G02X1191626Y7874I0J5874D01*
G01Y46654D01*
G03X1185689Y52591I-5937J0D01*
G01X1154193D01*
G03X1148256Y46654I0J-5937D01*
G01Y7874D01*
G02X1142382Y2000I-5874J0D01*
G01X1095138D01*
G02X1089264Y7874I0J5874D01*
G01Y46654D01*
G03X1083327Y52591I-5937J0D01*
G01X1051831D01*
G03X1045894Y46654I0J-5937D01*
G01Y7874D01*
G02X1040020Y2000I-5874J0D01*
G01X992776D01*
G02X986902Y7874I0J5874D01*
G01Y46654D01*
G03X980965Y52591I-5937J0D01*
G01X949468D01*
G03X943531Y46654I0J-5937D01*
G01Y7874D01*
G02X937657Y2000I-5874J0D01*
G01X842776D01*
G02X836902Y7874I0J5874D01*
G01Y46654D01*
G03X830965Y52591I-5937J0D01*
G01X799468D01*
G03X793531Y46654I0J-5937D01*
G01Y7874D01*
G02X787657Y2000I-5874J0D01*
G01X740413D01*
G02X734539Y7874I0J5874D01*
G01Y46654D01*
G03X728602Y52591I-5937J0D01*
G01X697106D01*
G03X691169Y46654I0J-5937D01*
G01Y7874D01*
G02X685295Y2000I-5874J0D01*
G01X638051D01*
G02X632177Y7874I0J5874D01*
G01Y46654D01*
G03X626240Y52591I-5937J0D01*
G01X594744D01*
G03X588807Y46654I0J-5937D01*
G01Y7874D01*
G02X582933Y2000I-5874J0D01*
G01X535689D01*
G02X529815Y7874I0J5874D01*
G01Y46654D01*
G03X523878Y52591I-5937J0D01*
G01X492382D01*
G03X486445Y46654I0J-5937D01*
G01Y7874D01*
G02X480571Y2000I-5874J0D01*
G01X385689D01*
G02X379815Y7874I0J5874D01*
G01Y46654D01*
G03X373878Y52591I-5937J0D01*
G01X342382D01*
G03X336445Y46654I0J-5937D01*
G01Y7874D01*
G02X330571Y2000I-5874J0D01*
G01X283327D01*
G02X277453Y7874I0J5874D01*
G01Y46654D01*
G03X271516Y52591I-5937J0D01*
G01X240020D01*
G03X234083Y46654I0J-5937D01*
G01Y7874D01*
G02X228209Y2000I-5874J0D01*
G01X180965D01*
G02X175091Y7874I0J5874D01*
G01Y46654D01*
G03X169154Y52591I-5937J0D01*
G01X137657D01*
G03X131720Y46654I0J-5937D01*
G01Y7874D01*
G02X125846Y2000I-5874J0D01*
G01X78602D01*
G02X72728Y7874I0J5874D01*
G01Y46654D01*
G03X66791Y52591I-5937J0D01*
G01X35295D01*
G03X29358Y46654I0J-5937D01*
G01Y7874D01*
G02X23484Y2000I-5874J0D01*
G01X7874D01*
G02X2000Y7874I0J5874D01*
G01Y323354D01*
G02X3720Y327506I5873J-1D01*
G01X14068Y337855D01*
G03X16961Y344836I-6980J6983D01*
G01Y948943D01*
G03X14068Y955925I-9875J-1D01*
G01X3720Y966273D01*
G02X2000Y970425I4154J4153D01*
G01Y1640118D01*
G02X7874Y1645992I5874J0D01*
G01X789298D01*
G02X793649Y1644063I-1J-5873D01*
G03X800966Y1640819I7317J6631D01*
G01X1070058D01*
G03X1077374Y1644063I-1J9873D01*
G02X1081725Y1645992I4352J-3945D01*
G01X1833071D01*
G37*
G36*
G01Y1818880D02*
G02X1838945Y1813006I0J-5874D01*
G01Y1663740D01*
G02X1833071Y1657866I-5874J0D01*
G01X1763543D01*
G02X1757669Y1663740I0J5874D01*
G01Y1689331D01*
G03X1747795Y1699205I-9874J0D01*
G01X1461575D01*
G03X1451701Y1689331I0J-9874D01*
G01Y1663740D01*
G02X1445827Y1657866I-5874J0D01*
G01X1417087D01*
G02X1411213Y1663740I0J5874D01*
G01Y1689331D01*
G03X1401339Y1699205I-9874J0D01*
G01X1115118D01*
G03X1105244Y1689331I0J-9874D01*
G01Y1663740D01*
G02X1099370Y1657866I-5874J0D01*
G01X1090079D01*
G02X1084205Y1663740I0J5874D01*
G01Y1695110D01*
G03X1074331Y1704984I-9874J0D01*
G01X796693D01*
G03X786819Y1695110I0J-9874D01*
G01Y1663740D01*
G02X780945Y1657866I-5874J0D01*
G01X741575D01*
G02X735701Y1663740I0J5874D01*
G01Y1689331D01*
G03X725827Y1699205I-9874J0D01*
G01X439607D01*
G03X429733Y1689331I0J-9874D01*
G01Y1663740D01*
G02X423859Y1657866I-5874J0D01*
G01X395118D01*
G02X389244Y1663740I0J5874D01*
G01Y1689331D01*
G03X379370Y1699205I-9874J0D01*
G01X93150D01*
G03X83276Y1689331I0J-9874D01*
G01Y1663740D01*
G02X77402Y1657866I-5874J0D01*
G01X7874D01*
G02X2000Y1663740I0J5874D01*
G01Y1813006D01*
G02X7874Y1818880I5874J0D01*
G01X1833071D01*
G37*
%LPD*%
G75*
G36*
G01X607977Y1552080D02*
X555513D01*
G02X555210Y1552383I0J303D01*
G01Y1643194D01*
G02X555513Y1643498I303J1D01*
G01X608266D01*
G02X608570Y1643194I0J-304D01*
G01Y1552672D01*
X607977Y1552080D01*
G37*
G36*
G01X208954Y1643834D02*
G02X209256Y1644136I302J0D01*
G01X261611D01*
G02X261912Y1643834I-1J-302D01*
G01Y1642872D01*
Y1552470D01*
X261722Y1552280D01*
X208952D01*
Y1642872D01*
X208954D01*
Y1643834D01*
G37*
G36*
G01X1232576D02*
G02X1232878Y1644136I302J0D01*
G01X1285233D01*
G02X1285534Y1643834I-1J-302D01*
G01Y1643226D01*
Y1552461D01*
X1285353Y1552280D01*
X1232574D01*
Y1643226D01*
X1232576D01*
Y1643834D01*
G37*
G36*
G01X1579032D02*
G02X1579335Y1644136I303J-1D01*
G01X1631688D01*
G02X1631990Y1643834I0J-302D01*
G01Y1643174D01*
X1631992D01*
Y1552573D01*
X1631698Y1552280D01*
X1579032D01*
Y1643174D01*
Y1643834D01*
G37*
G36*
G01X177763Y1512216D02*
X180583D01*
G02X180786Y1512014I1J-202D01*
G01Y1511392D01*
G03X180836Y1511260I200J0D01*
G02Y1508348I-1664J-1456D01*
G03X180786Y1508216I150J-132D01*
G01Y1506273D01*
G03X180836Y1506141I200J0D01*
G02Y1503229I-1664J-1456D01*
G03X180786Y1503097I150J-132D01*
G01Y1502476D01*
G02X180583Y1502274I-203J1D01*
G01X177763D01*
G02X177560Y1502476I-1J202D01*
G01Y1503097D01*
G03X177510Y1503229I-200J0D01*
G02Y1506141I1664J1456D01*
G03X177560Y1506273I-150J132D01*
G01Y1508216D01*
G03X177510Y1508348I-200J0D01*
G02Y1511260I1664J1456D01*
G03X177560Y1511392I-150J132D01*
G01Y1512014D01*
G02X177763Y1512216I203J-1D01*
G37*
G36*
G01X350991D02*
X353811D01*
G02X354014Y1512014I1J-202D01*
G01Y1511392D01*
G03X354064Y1511260I200J0D01*
G02Y1508348I-1664J-1456D01*
G03X354014Y1508216I150J-132D01*
G01Y1506273D01*
G03X354064Y1506141I200J0D01*
G02Y1503229I-1664J-1456D01*
G03X354014Y1503097I150J-132D01*
G01Y1502476D01*
G02X353811Y1502274I-203J1D01*
G01X350991D01*
G02X350788Y1502476I-1J202D01*
G01Y1503097D01*
G03X350738Y1503229I-200J0D01*
G02Y1506141I1664J1456D01*
G03X350788Y1506273I-150J132D01*
G01Y1508216D01*
G03X350738Y1508348I-200J0D01*
G02Y1511260I1664J1456D01*
G03X350788Y1511392I-150J132D01*
G01Y1512014D01*
G02X350991Y1512216I203J-1D01*
G37*
G36*
G01X186425Y1516546D02*
X189245D01*
G02X189448Y1516344I1J-202D01*
G01Y1515722D01*
G03X189498Y1515590I200J0D01*
G02Y1512678I-1664J-1456D01*
G03X189448Y1512546I150J-132D01*
G01Y1510604D01*
G03X189498Y1510472I200J0D01*
G02Y1507560I-1664J-1456D01*
G03X189448Y1507428I150J-132D01*
G01Y1506806D01*
G02X189245Y1506604I-203J1D01*
G01X186425D01*
G02X186222Y1506806I-1J202D01*
G01Y1507428D01*
G03X186172Y1507560I-200J0D01*
G02Y1510472I1664J1456D01*
G03X186222Y1510604I-150J132D01*
G01Y1512546D01*
G03X186172Y1512678I-200J0D01*
G02Y1515590I1664J1456D01*
G03X186222Y1515722I-150J132D01*
G01Y1516344D01*
G02X186425Y1516546I203J-1D01*
G37*
G36*
G01X359653D02*
X362473D01*
G02X362676Y1516344I1J-202D01*
G01Y1515722D01*
G03X362726Y1515590I200J0D01*
G02Y1512678I-1664J-1456D01*
G03X362676Y1512546I150J-132D01*
G01Y1510604D01*
G03X362726Y1510472I200J0D01*
G02Y1507560I-1664J-1456D01*
G03X362676Y1507428I150J-132D01*
G01Y1506806D01*
G02X362473Y1506604I-203J1D01*
G01X359653D01*
G02X359450Y1506806I-1J202D01*
G01Y1507428D01*
G03X359400Y1507560I-200J0D01*
G02Y1510472I1664J1456D01*
G03X359450Y1510604I-150J132D01*
G01Y1512546D01*
G03X359400Y1512678I-200J0D01*
G02Y1515590I1664J1456D01*
G03X359450Y1515722I-150J132D01*
G01Y1516344D01*
G02X359653Y1516546I203J-1D01*
G37*
G36*
G01X177763Y1568516D02*
X180583D01*
G02X180786Y1568313I0J-203D01*
G01Y1567691D01*
G03X180836Y1567559I200J0D01*
G02Y1564647I-1664J-1456D01*
G03X180786Y1564515I150J-132D01*
G01Y1562573D01*
G03X180836Y1562441I200J0D01*
G02Y1559529I-1664J-1456D01*
G03X180786Y1559397I150J-132D01*
G01Y1558775D01*
G02X180583Y1558572I-203J0D01*
G01X177763D01*
G02X177560Y1558775I0J203D01*
G01Y1559397D01*
G03X177510Y1559529I-200J0D01*
G02Y1562441I1664J1456D01*
G03X177560Y1562573I-150J132D01*
G01Y1564515D01*
G03X177510Y1564647I-200J0D01*
G02Y1567559I1664J1456D01*
G03X177560Y1567691I-150J132D01*
G01Y1568313D01*
G02X177763Y1568516I203J0D01*
G37*
G36*
G01X350991D02*
X353811D01*
G02X354014Y1568313I0J-203D01*
G01Y1567691D01*
G03X354064Y1567559I200J0D01*
G02Y1564647I-1664J-1456D01*
G03X354014Y1564515I150J-132D01*
G01Y1562573D01*
G03X354064Y1562441I200J0D01*
G02Y1559529I-1664J-1456D01*
G03X354014Y1559397I150J-132D01*
G01Y1558775D01*
G02X353811Y1558572I-203J0D01*
G01X350991D01*
G02X350788Y1558775I0J203D01*
G01Y1559397D01*
G03X350738Y1559529I-200J0D01*
G02Y1562441I1664J1456D01*
G03X350788Y1562573I-150J132D01*
G01Y1564515D01*
G03X350738Y1564647I-200J0D01*
G02Y1567559I1664J1456D01*
G03X350788Y1567691I-150J132D01*
G01Y1568313D01*
G02X350991Y1568516I203J0D01*
G37*
G36*
G01X186425Y1572846D02*
X189245D01*
G02X189448Y1572644I1J-202D01*
G01Y1572022D01*
G03X189498Y1571890I200J0D01*
G02Y1568978I-1664J-1456D01*
G03X189448Y1568846I150J-132D01*
G01Y1566903D01*
G03X189498Y1566771I200J0D01*
G02Y1563859I-1664J-1456D01*
G03X189448Y1563727I150J-132D01*
G01Y1563106D01*
G02X189245Y1562904I-203J1D01*
G01X186425D01*
G02X186222Y1563106I-1J202D01*
G01Y1563727D01*
G03X186172Y1563859I-200J0D01*
G02Y1566771I1664J1456D01*
G03X186222Y1566903I-150J132D01*
G01Y1568846D01*
G03X186172Y1568978I-200J0D01*
G02Y1571890I1664J1456D01*
G03X186222Y1572022I-150J132D01*
G01Y1572644D01*
G02X186425Y1572846I203J-1D01*
G37*
G36*
G01X359653D02*
X362473D01*
G02X362676Y1572644I1J-202D01*
G01Y1572022D01*
G03X362726Y1571890I200J0D01*
G02Y1568978I-1664J-1456D01*
G03X362676Y1568846I150J-132D01*
G01Y1566903D01*
G03X362726Y1566771I200J0D01*
G02Y1563859I-1664J-1456D01*
G03X362676Y1563727I150J-132D01*
G01Y1563106D01*
G02X362473Y1562904I-203J1D01*
G01X359653D01*
G02X359450Y1563106I-1J202D01*
G01Y1563727D01*
G03X359400Y1563859I-200J0D01*
G02Y1566771I1664J1456D01*
G03X359450Y1566903I-150J132D01*
G01Y1568846D01*
G03X359400Y1568978I-200J0D01*
G02Y1571890I1664J1456D01*
G03X359450Y1572022I-150J132D01*
G01Y1572644D01*
G02X359653Y1572846I203J-1D01*
G37*
G36*
G01X177763Y1583870D02*
X180583D01*
G02X180786Y1583667I0J-203D01*
G01Y1583045D01*
G03X180836Y1582913I200J0D01*
G02Y1580001I-1664J-1456D01*
G03X180786Y1579869I150J-132D01*
G01Y1577927D01*
G03X180836Y1577795I200J0D01*
G02Y1574883I-1664J-1456D01*
G03X180786Y1574751I150J-132D01*
G01Y1574129D01*
G02X180583Y1573926I-203J0D01*
G01X177763D01*
G02X177560Y1574129I0J203D01*
G01Y1574751D01*
G03X177510Y1574883I-200J0D01*
G02Y1577795I1664J1456D01*
G03X177560Y1577927I-150J132D01*
G01Y1579869D01*
G03X177510Y1580001I-200J0D01*
G02Y1582913I1664J1456D01*
G03X177560Y1583045I-150J132D01*
G01Y1583667D01*
G02X177763Y1583870I203J0D01*
G37*
G36*
G01X933247Y1585829D02*
X940733Y1578343D01*
G03X940735Y1578341I142J140D01*
G03X940910Y1578270I174J178D01*
G01X956757D01*
G02X956899Y1578211I0J-200D01*
G01X960831Y1574278D01*
G02X960890Y1574136I-141J-142D01*
G01Y1543680D01*
G03X960963Y1543504I249J0D01*
G01X965002Y1539465D01*
G03X965004Y1539463I142J140D01*
G03X965179Y1539392I174J178D01*
G01X1020321D01*
G02X1020463Y1539333I0J-200D01*
G01X1032517Y1527279D01*
G02X1032576Y1527137I-141J-142D01*
G01Y1492489D01*
G02X1032517Y1492347I-200J0D01*
G01X1031783Y1491613D01*
G02X1031641Y1491554I-142J141D01*
G01X946768D01*
G02X946626Y1491613I0J200D01*
G01X944169Y1494071D01*
G03X944167Y1494073I-142J-140D01*
G03X943992Y1494144I-174J-178D01*
G01X933579D01*
G03X933404Y1494073I-1J-249D01*
G03X933402Y1494071I140J-142D01*
G01X917849Y1478518D01*
G03X917776Y1478342I176J-176D01*
G01Y1464605D01*
G02X917717Y1464463I-200J0D01*
G01X914897Y1461643D01*
G03X914895Y1461641I140J-142D01*
G03X914824Y1461466I178J-174D01*
G01Y1460513D01*
G02X914765Y1460371I-200J0D01*
G01X914235Y1459842D01*
G03X914162Y1459666I176J-176D01*
G01Y1446033D01*
G02X914104Y1445891I-200J-1D01*
G01X913370Y1445157D01*
G02X913228Y1445098I-142J141D01*
G01X900144D01*
G02X900002Y1445157I0J200D01*
G01X899268Y1445891D01*
G02X899210Y1446033I142J141D01*
G01Y1459640D01*
G03X899137Y1459816I-249J0D01*
G01X898531Y1460422D01*
G02X898472Y1460564I141J142D01*
G01Y1462024D01*
G03X898399Y1462200I-249J0D01*
G01X893401Y1467197D01*
G02X893342Y1467339I141J142D01*
G01Y1473096D01*
G03X893271Y1473271I-249J1D01*
G03X893269Y1473273I-142J-140D01*
G01X888245Y1478297D01*
G03X888069Y1478370I-176J-176D01*
G01X880504D01*
G03X880328Y1478297I0J-249D01*
G01X872973Y1470942D01*
G03X872900Y1470766I176J-176D01*
G01Y1460576D01*
G02X872841Y1460434I-200J0D01*
G01X872211Y1459804D01*
G03X872209Y1459802I140J-142D01*
G03X872138Y1459627I178J-174D01*
G01Y1446008D01*
G02X872079Y1445866I-200J0D01*
G01X871383Y1445170D01*
G02X871241Y1445112I-141J142D01*
G01X858287D01*
G02X858145Y1445171I0J200D01*
G01X857137Y1446178D01*
G02X857078Y1446320I141J142D01*
G01Y1459524D01*
G03X857007Y1459699I-249J1D01*
G03X857005Y1459701I-142J-140D01*
G01X852953Y1463753D01*
G03X852951Y1463755I-142J-140D01*
G03X852776Y1463826I-174J-178D01*
G01X828441D01*
G03X828266Y1463755I-1J-249D01*
G03X828264Y1463753I140J-142D01*
G01X827747Y1463236D01*
G03X827674Y1463060I176J-176D01*
G01Y1461432D01*
G02X827615Y1461290I-200J0D01*
G01X826986Y1460661D01*
G02X826844Y1460602I-142J141D01*
G01X825036D01*
G03X824860Y1460529I0J-249D01*
G01X821948Y1457617D01*
G02X821806Y1457558I-142J141D01*
G01X820451D01*
G03X820275Y1457485I0J-249D01*
G01X820069Y1457279D01*
G03X820067Y1457277I140J-142D01*
G03X819996Y1457102I178J-174D01*
G01Y1446047D01*
G02X819937Y1445905I-200J0D01*
G01X819241Y1445209D01*
G02X819099Y1445150I-142J141D01*
G01X805978D01*
G02X805836Y1445209I0J200D01*
G01X805061Y1445984D01*
G02X805002Y1446126I141J142D01*
G01Y1460243D01*
G02X805061Y1460385I200J0D01*
G01X805487Y1460810D01*
G03X805560Y1460986I-176J176D01*
G01Y1474724D01*
G02X805619Y1474866I200J0D01*
G01X805875Y1475122D01*
G03X805877Y1475124I-140J142D01*
G03X805948Y1475299I-178J174D01*
G01Y1524130D01*
G02X806007Y1524272I200J0D01*
G01X816121Y1534385D01*
G03X816123Y1534387I-140J142D01*
G03X816194Y1534562I-178J174D01*
G01Y1621268D01*
G02X816253Y1621410I200J0D01*
G01X822113Y1627269D01*
G02X822255Y1627328I142J-141D01*
G01X927980D01*
G02X928122Y1627269I0J-200D01*
G01X933115Y1622276D01*
G02X933174Y1622134I-141J-142D01*
G01Y1586005D01*
G03X933247Y1585829I249J0D01*
G37*
G36*
G01X404759Y1350874D02*
X408159D01*
G02Y1347270I0J-1802D01*
G01X404759D01*
G02Y1350874I0J1802D01*
G37*
G36*
G01X402489Y1419078D02*
X405889D01*
G02Y1415472I0J-1803D01*
G01X402489D01*
G02Y1419078I0J1803D01*
G37*
G36*
G01X1443660Y1308896D02*
X1440260D01*
G02Y1312500I0J1802D01*
G01X1443660D01*
G02Y1308896I0J-1802D01*
G37*
G36*
G01X970197Y665850D02*
X966797D01*
G02Y669456I0J1803D01*
G01X970197D01*
G02Y665850I0J-1803D01*
G37*
G36*
G01X501495Y772260D02*
X504895D01*
G02Y768654I0J-1803D01*
G01X501495D01*
G02Y772260I0J1803D01*
G37*
G36*
G01X909508Y623418D02*
X912908D01*
G02Y619814I0J-1802D01*
G01X909508D01*
G02Y623418I0J1802D01*
G37*
G36*
G01X900676Y623338D02*
X904076D01*
G02Y619734I0J-1802D01*
G01X900676D01*
G02Y623338I0J1802D01*
G37*
G36*
G01X526264Y665858D02*
X529664D01*
G02Y662254I0J-1802D01*
G01X526264D01*
G02Y665858I0J1802D01*
G37*
G36*
G01X534264Y663358D02*
X537664D01*
G02Y659754I0J-1802D01*
G01X534264D01*
G02Y663358I0J1802D01*
G37*
G36*
G01X538985Y734790D02*
X535585D01*
G02Y738396I0J1803D01*
G01X538985D01*
G02Y734790I0J-1803D01*
G37*
G36*
G01X530985Y739790D02*
X527585D01*
G02Y743396I0J1803D01*
G01X530985D01*
G02Y739790I0J-1803D01*
G37*
G36*
G01X517731Y742874D02*
X521131D01*
G02Y739268I0J-1803D01*
G01X517731D01*
G02Y742874I0J1803D01*
G37*
G36*
G01X511724Y739232D02*
X508324D01*
G02Y742838I0J1803D01*
G01X511724D01*
G02Y739232I0J-1803D01*
G37*
G36*
G01X415777Y306272D02*
X419177D01*
G02Y302668I0J-1802D01*
G01X415777D01*
G02Y306272I0J1802D01*
G37*
G36*
G01X423651Y309272D02*
X427051D01*
G02Y305668I0J-1802D01*
G01X423651D01*
G02Y309272I0J1802D01*
G37*
G36*
G01X431525Y306272D02*
X434925D01*
G02Y302668I0J-1802D01*
G01X431525D01*
G02Y306272I0J1802D01*
G37*
G36*
G01X434924Y368506D02*
X431524D01*
G02Y372112I0J1803D01*
G01X434924D01*
G02Y368506I0J-1803D01*
G37*
G36*
G01X1047661Y1451746D02*
X1045748Y1449833D01*
G02X1045606Y1449774I-142J141D01*
G01X955889D01*
G02X955747Y1449833I0J200D01*
G01X954749Y1450831D01*
G02X954690Y1450973I141J142D01*
G01Y1485726D01*
G02X954749Y1485868I200J0D01*
G01X956753Y1487871D01*
G02X956895Y1487930I142J-141D01*
G01X1046147D01*
G02X1046289Y1487871I0J-200D01*
G01X1047661Y1486500D01*
G02X1047720Y1486358I-141J-142D01*
G01Y1451888D01*
G02X1047661Y1451746I-200J0D01*
G37*
G36*
G01X952704Y1482405D02*
X953818Y1481291D01*
G03X953834Y1481276I178J174D01*
G01X954122Y1481036D01*
G02X954194Y1480882I-128J-154D01*
G01Y1451027D01*
G02X954135Y1450885I-200J0D01*
G01X953083Y1449833D01*
G02X952941Y1449774I-142J141D01*
G01X930177D01*
G02X930035Y1449833I0J200D01*
G01X928619Y1451249D01*
G02X928560Y1451391I141J142D01*
G01Y1481306D01*
G02X928619Y1481448I200J0D01*
G01X930003Y1482831D01*
G02X930145Y1482890I142J-141D01*
G01X952269D01*
G02X952435Y1482801I0J-200D01*
G01X952673Y1482443D01*
G03X952703Y1482406I207J137D01*
G01X952704Y1482405D01*
G37*
G36*
G01X26772Y1559218D02*
X20472D01*
G02Y1575428I0J8105D01*
G01X26772D01*
G02Y1559218I0J-8105D01*
G37*
G36*
G01X216125Y1441832D02*
X219525D01*
G02Y1438226I0J-1803D01*
G01X216125D01*
G02Y1441832I0J1803D01*
G37*
G36*
G01X413753Y1518690D02*
X417153D01*
G02Y1515084I0J-1803D01*
G01X413753D01*
G02Y1518690I0J1803D01*
G37*
G36*
G01X417334Y1475298D02*
X413934D01*
G02Y1478902I0J1802D01*
G01X417334D01*
G02Y1475298I0J-1802D01*
G37*
G36*
G01X919628Y334530D02*
X916228D01*
G02Y338136I0J1803D01*
G01X919628D01*
G02Y334530I0J-1803D01*
G37*
G36*
G01X905899Y304150D02*
X909299D01*
G02Y300544I0J-1803D01*
G01X905899D01*
G02Y304150I0J1803D01*
G37*
G36*
G01X1033891Y298096D02*
X1037291D01*
G02Y294490I0J-1803D01*
G01X1033891D01*
G02Y298096I0J1803D01*
G37*
G36*
G01X1318363Y312364D02*
X1321763D01*
G02Y308760I0J-1802D01*
G01X1318363D01*
G02Y312364I0J1802D01*
G37*
G36*
G01X1337508Y371598D02*
X1334108D01*
G02Y375204I0J1803D01*
G01X1337508D01*
G02Y371598I0J-1803D01*
G37*
G36*
G01X1326237Y309364D02*
X1329637D01*
G02Y305760I0J-1802D01*
G01X1326237D01*
G02Y309364I0J1802D01*
G37*
G36*
G01X1334111Y312364D02*
X1337511D01*
G02Y308760I0J-1802D01*
G01X1334111D01*
G02Y312364I0J1802D01*
G37*
G36*
G01X1518207Y1176748D02*
X1514467D01*
G02Y1179354I0J1303D01*
G01X1518207D01*
G02Y1176748I0J-1303D01*
G37*
G36*
G01Y1169268D02*
X1514467D01*
G02Y1171872I0J1302D01*
G01X1518207D01*
G02Y1169268I0J-1302D01*
G37*
G36*
G01X1513926Y907148D02*
X1510526D01*
G02Y910754I0J1803D01*
G01X1513926D01*
G02Y907148I0J-1803D01*
G37*
G36*
G01X1531299Y1174878D02*
X1527559D01*
G02Y1177482I0J1302D01*
G01X1531299D01*
G02Y1174878I0J-1302D01*
G37*
G36*
G01X146947Y1176748D02*
X143207D01*
G02Y1179354I0J1303D01*
G01X146947D01*
G02Y1176748I0J-1303D01*
G37*
G36*
G01Y1169268D02*
X143207D01*
G02Y1171872I0J1302D01*
G01X146947D01*
G02Y1169268I0J-1302D01*
G37*
G36*
G01X160039Y1174878D02*
X156299D01*
G02Y1177482I0J1302D01*
G01X160039D01*
G02Y1174878I0J-1302D01*
G37*
G36*
G01X604034Y1176748D02*
X600294D01*
G02Y1179354I0J1303D01*
G01X604034D01*
G02Y1176748I0J-1303D01*
G37*
G36*
G01Y1169268D02*
X600294D01*
G02Y1171872I0J1302D01*
G01X604034D01*
G02Y1169268I0J-1302D01*
G37*
G36*
G01X605733Y942940D02*
X609133D01*
G02Y939336I0J-1802D01*
G01X605733D01*
G02Y942940I0J1802D01*
G37*
G36*
G01X615256Y1176748D02*
X611516D01*
G02Y1179354I0J1303D01*
G01X615256D01*
G02Y1176748I0J-1303D01*
G37*
G36*
G01X1061120D02*
X1057380D01*
G02Y1179354I0J1303D01*
G01X1061120D01*
G02Y1176748I0J-1303D01*
G37*
G36*
G01Y1169268D02*
X1057380D01*
G02Y1171872I0J1302D01*
G01X1061120D01*
G02Y1169268I0J-1302D01*
G37*
G36*
G01X1769063Y921922D02*
X1765663D01*
G02Y925526I0J1802D01*
G01X1769063D01*
G02Y921922I0J-1802D01*
G37*
G36*
G01X1072342Y1176748D02*
X1068602D01*
G02Y1179354I0J1303D01*
G01X1072342D01*
G02Y1176748I0J-1303D01*
G37*
G36*
G01X647411Y379065D02*
X647412D01*
G02Y370659I0J-4203D01*
G01X647411D01*
G02Y379065I0J4203D01*
G37*
G36*
G01X111494Y1456412D02*
G02X111292Y1456210I-202J0D01*
G01X108472D01*
G02X108270Y1456413I1J203D01*
G01Y1457032D01*
G03X108220Y1457164I-200J0D01*
G02Y1460080I1661J1458D01*
G03X108270Y1460212I-150J132D01*
G01Y1462151D01*
G03X108220Y1462283I-200J0D01*
G02Y1465199I1661J1458D01*
G03X108270Y1465331I-150J132D01*
G01Y1465952D01*
G02X108472Y1466154I202J0D01*
G01X111292D01*
G02X111494Y1465951I-1J-203D01*
G01Y1465331D01*
G03X111544Y1465199I200J0D01*
G02Y1462283I-1661J-1458D01*
G03X111494Y1462151I150J-132D01*
G01Y1460212D01*
G03X111544Y1460080I200J0D01*
G02Y1457164I-1661J-1458D01*
G03X111494Y1457032I150J-132D01*
G01Y1456412D01*
G37*
G36*
G01X319368D02*
G02X319166Y1456210I-202J0D01*
G01X316346D01*
G02X316144Y1456413I1J203D01*
G01Y1457032D01*
G03X316094Y1457164I-200J0D01*
G02Y1460080I1661J1458D01*
G03X316144Y1460212I-150J132D01*
G01Y1462151D01*
G03X316094Y1462283I-200J0D01*
G02Y1465199I1661J1458D01*
G03X316144Y1465331I-150J132D01*
G01Y1465952D01*
G02X316346Y1466154I202J0D01*
G01X319166D01*
G02X319368Y1465951I-1J-203D01*
G01Y1465331D01*
G03X319418Y1465199I200J0D01*
G02Y1462283I-1661J-1458D01*
G03X319368Y1462151I150J-132D01*
G01Y1460212D01*
G03X319418Y1460080I200J0D01*
G02Y1457164I-1661J-1458D01*
G03X319368Y1457032I150J-132D01*
G01Y1456412D01*
G37*
G36*
G01X336690D02*
G02X336488Y1456210I-202J0D01*
G01X333668D01*
G02X333466Y1456413I1J203D01*
G01Y1457032D01*
G03X333416Y1457164I-200J0D01*
G02Y1460080I1661J1458D01*
G03X333466Y1460212I-150J132D01*
G01Y1462151D01*
G03X333416Y1462283I-200J0D01*
G02Y1465199I1661J1458D01*
G03X333466Y1465331I-150J132D01*
G01Y1465952D01*
G02X333668Y1466154I202J0D01*
G01X336488D01*
G02X336690Y1465951I-1J-203D01*
G01Y1465331D01*
G03X336740Y1465199I200J0D01*
G02Y1462283I-1661J-1458D01*
G03X336690Y1462151I150J-132D01*
G01Y1460212D01*
G03X336740Y1460080I200J0D01*
G02Y1457164I-1661J-1458D01*
G03X336690Y1457032I150J-132D01*
G01Y1456412D01*
G37*
G36*
G01X628157Y1466154D02*
X630977D01*
G02X631180Y1465951I0J-203D01*
G01Y1465329D01*
G03X631230Y1465197I200J0D01*
G02Y1462285I-1664J-1456D01*
G03X631180Y1462153I150J-132D01*
G01Y1460210D01*
G03X631230Y1460078I200J0D01*
G02Y1457166I-1664J-1456D01*
G03X631180Y1457034I150J-132D01*
G01Y1456413D01*
G02X630977Y1456210I-203J0D01*
G01X628157D01*
G02X627954Y1456413I0J203D01*
G01Y1457034D01*
G03X627904Y1457166I-200J0D01*
G02Y1460078I1664J1456D01*
G03X627954Y1460210I-150J132D01*
G01Y1462153D01*
G03X627904Y1462285I-200J0D01*
G02Y1465197I1664J1456D01*
G03X627954Y1465329I-150J132D01*
G01Y1465951D01*
G02X628157Y1466154I203J0D01*
G37*
G36*
G01X1133462Y1456412D02*
G02X1133260Y1456210I-202J0D01*
G01X1130440D01*
G02X1130238Y1456413I1J203D01*
G01Y1457032D01*
G03X1130188Y1457164I-200J0D01*
G02Y1460080I1661J1458D01*
G03X1130238Y1460212I-150J132D01*
G01Y1462151D01*
G03X1130188Y1462283I-200J0D01*
G02Y1465199I1661J1458D01*
G03X1130238Y1465331I-150J132D01*
G01Y1465952D01*
G02X1130440Y1466154I202J0D01*
G01X1133260D01*
G02X1133462Y1465951I-1J-203D01*
G01Y1465331D01*
G03X1133512Y1465199I200J0D01*
G02Y1462283I-1661J-1458D01*
G03X1133462Y1462151I150J-132D01*
G01Y1460212D01*
G03X1133512Y1460080I200J0D01*
G02Y1457164I-1661J-1458D01*
G03X1133462Y1457032I150J-132D01*
G01Y1456412D01*
G37*
G36*
G01X1147763Y1466154D02*
X1150583D01*
G02X1150786Y1465951I0J-203D01*
G01Y1465329D01*
G03X1150836Y1465197I200J0D01*
G02Y1462285I-1664J-1456D01*
G03X1150786Y1462153I150J-132D01*
G01Y1460210D01*
G03X1150836Y1460078I200J0D01*
G02Y1457166I-1664J-1456D01*
G03X1150786Y1457034I150J-132D01*
G01Y1456413D01*
G02X1150583Y1456210I-203J0D01*
G01X1147763D01*
G02X1147560Y1456413I0J203D01*
G01Y1457034D01*
G03X1147510Y1457166I-200J0D01*
G02Y1460078I1664J1456D01*
G03X1147560Y1460210I-150J132D01*
G01Y1462153D01*
G03X1147510Y1462285I-200J0D01*
G02Y1465197I1664J1456D01*
G03X1147560Y1465329I-150J132D01*
G01Y1465951D01*
G02X1147763Y1466154I203J0D01*
G37*
G36*
G01X1650125D02*
X1652945D01*
G02X1653148Y1465951I0J-203D01*
G01Y1465329D01*
G03X1653198Y1465197I200J0D01*
G02Y1462285I-1664J-1456D01*
G03X1653148Y1462153I150J-132D01*
G01Y1460210D01*
G03X1653198Y1460078I200J0D01*
G02Y1457166I-1664J-1456D01*
G03X1653148Y1457034I150J-132D01*
G01Y1456413D01*
G02X1652945Y1456210I-203J0D01*
G01X1650125D01*
G02X1649922Y1456413I0J203D01*
G01Y1457034D01*
G03X1649872Y1457166I-200J0D01*
G02Y1460078I1664J1456D01*
G03X1649922Y1460210I-150J132D01*
G01Y1462153D01*
G03X1649872Y1462285I-200J0D01*
G02Y1465197I1664J1456D01*
G03X1649922Y1465329I-150J132D01*
G01Y1465951D01*
G02X1650125Y1466154I203J0D01*
G37*
G36*
G01X1670470Y1456412D02*
G02X1670268Y1456210I-202J0D01*
G01X1667448D01*
G02X1667246Y1456413I1J203D01*
G01Y1457032D01*
G03X1667196Y1457164I-200J0D01*
G02Y1460080I1661J1458D01*
G03X1667246Y1460212I-150J132D01*
G01Y1462151D01*
G03X1667196Y1462283I-200J0D01*
G02Y1465199I1661J1458D01*
G03X1667246Y1465331I-150J132D01*
G01Y1465952D01*
G02X1667448Y1466154I202J0D01*
G01X1670268D01*
G02X1670470Y1465951I-1J-203D01*
G01Y1465331D01*
G03X1670520Y1465199I200J0D01*
G02Y1462283I-1661J-1458D01*
G03X1670470Y1462151I150J-132D01*
G01Y1460212D01*
G03X1670520Y1460080I200J0D01*
G02Y1457164I-1661J-1458D01*
G03X1670470Y1457032I150J-132D01*
G01Y1456412D01*
G37*
G36*
G01X117133Y1470484D02*
X119953D01*
G02X120156Y1470281I0J-203D01*
G01Y1469659D01*
G03X120206Y1469527I200J0D01*
G02Y1466615I-1664J-1456D01*
G03X120156Y1466483I150J-132D01*
G01Y1464541D01*
G03X120206Y1464409I200J0D01*
G02Y1461497I-1664J-1456D01*
G03X120156Y1461365I150J-132D01*
G01Y1460743D01*
G02X119953Y1460540I-203J0D01*
G01X117133D01*
G02X116930Y1460743I0J203D01*
G01Y1461365D01*
G03X116880Y1461497I-200J0D01*
G02Y1464409I1664J1456D01*
G03X116930Y1464541I-150J132D01*
G01Y1466483D01*
G03X116880Y1466615I-200J0D01*
G02Y1469527I1664J1456D01*
G03X116930Y1469659I-150J132D01*
G01Y1470281D01*
G02X117133Y1470484I203J0D01*
G37*
G36*
G01X310706Y1460742D02*
G02X310504Y1460540I-202J0D01*
G01X307684D01*
G02X307482Y1460743I1J203D01*
G01Y1461363D01*
G03X307432Y1461495I-200J0D01*
G02Y1464411I1661J1458D01*
G03X307482Y1464543I-150J132D01*
G01Y1466481D01*
G03X307432Y1466613I-200J0D01*
G02Y1469529I1661J1458D01*
G03X307482Y1469661I-150J132D01*
G01Y1470282D01*
G02X307684Y1470484I202J0D01*
G01X310504D01*
G02X310706Y1470281I-1J-203D01*
G01Y1469661D01*
G03X310756Y1469529I200J0D01*
G02Y1466613I-1661J-1458D01*
G03X310706Y1466481I150J-132D01*
G01Y1464543D01*
G03X310756Y1464411I200J0D01*
G02Y1461495I-1661J-1458D01*
G03X310706Y1461363I150J-132D01*
G01Y1460742D01*
G37*
G36*
G01X325007Y1470484D02*
X327827D01*
G02X328030Y1470281I0J-203D01*
G01Y1469659D01*
G03X328080Y1469527I200J0D01*
G02Y1466615I-1664J-1456D01*
G03X328030Y1466483I150J-132D01*
G01Y1464541D01*
G03X328080Y1464409I200J0D01*
G02Y1461497I-1664J-1456D01*
G03X328030Y1461365I150J-132D01*
G01Y1460743D01*
G02X327827Y1460540I-203J0D01*
G01X325007D01*
G02X324804Y1460743I0J203D01*
G01Y1461365D01*
G03X324754Y1461497I-200J0D01*
G02Y1464409I1664J1456D01*
G03X324804Y1464541I-150J132D01*
G01Y1466483D01*
G03X324754Y1466615I-200J0D01*
G02Y1469527I1664J1456D01*
G03X324804Y1469659I-150J132D01*
G01Y1470281D01*
G02X325007Y1470484I203J0D01*
G37*
G36*
G01X345352Y1460742D02*
G02X345150Y1460540I-202J0D01*
G01X342330D01*
G02X342128Y1460743I1J203D01*
G01Y1461363D01*
G03X342078Y1461495I-200J0D01*
G02Y1464411I1661J1458D01*
G03X342128Y1464543I-150J132D01*
G01Y1466481D01*
G03X342078Y1466613I-200J0D01*
G02Y1469529I1661J1458D01*
G03X342128Y1469661I-150J132D01*
G01Y1470282D01*
G02X342330Y1470484I202J0D01*
G01X345150D01*
G02X345352Y1470281I-1J-203D01*
G01Y1469661D01*
G03X345402Y1469529I200J0D01*
G02Y1466613I-1661J-1458D01*
G03X345352Y1466481I150J-132D01*
G01Y1464543D01*
G03X345402Y1464411I200J0D01*
G02Y1461495I-1661J-1458D01*
G03X345352Y1461363I150J-132D01*
G01Y1460742D01*
G37*
G36*
G01X639840D02*
G02X639638Y1460540I-202J0D01*
G01X636818D01*
G02X636616Y1460743I1J203D01*
G01Y1461363D01*
G03X636566Y1461495I-200J0D01*
G02Y1464411I1661J1458D01*
G03X636616Y1464543I-150J132D01*
G01Y1466481D01*
G03X636566Y1466613I-200J0D01*
G02Y1469529I1661J1458D01*
G03X636616Y1469661I-150J132D01*
G01Y1470282D01*
G02X636818Y1470484I202J0D01*
G01X639638D01*
G02X639840Y1470281I-1J-203D01*
G01Y1469661D01*
G03X639890Y1469529I200J0D01*
G02Y1466613I-1661J-1458D01*
G03X639840Y1466481I150J-132D01*
G01Y1464543D01*
G03X639890Y1464411I200J0D01*
G02Y1461495I-1661J-1458D01*
G03X639840Y1461363I150J-132D01*
G01Y1460742D01*
G37*
G36*
G01X1139101Y1470484D02*
X1141921D01*
G02X1142124Y1470281I0J-203D01*
G01Y1469659D01*
G03X1142174Y1469527I200J0D01*
G02Y1466615I-1664J-1456D01*
G03X1142124Y1466483I150J-132D01*
G01Y1464541D01*
G03X1142174Y1464409I200J0D01*
G02Y1461497I-1664J-1456D01*
G03X1142124Y1461365I150J-132D01*
G01Y1460743D01*
G02X1141921Y1460540I-203J0D01*
G01X1139101D01*
G02X1138898Y1460743I0J203D01*
G01Y1461365D01*
G03X1138848Y1461497I-200J0D01*
G02Y1464409I1664J1456D01*
G03X1138898Y1464541I-150J132D01*
G01Y1466483D01*
G03X1138848Y1466615I-200J0D01*
G02Y1469527I1664J1456D01*
G03X1138898Y1469659I-150J132D01*
G01Y1470281D01*
G02X1139101Y1470484I203J0D01*
G37*
G36*
G01X1159446Y1460742D02*
G02X1159244Y1460540I-202J0D01*
G01X1156424D01*
G02X1156222Y1460743I1J203D01*
G01Y1461363D01*
G03X1156172Y1461495I-200J0D01*
G02Y1464411I1661J1458D01*
G03X1156222Y1464543I-150J132D01*
G01Y1466481D01*
G03X1156172Y1466613I-200J0D01*
G02Y1469529I1661J1458D01*
G03X1156222Y1469661I-150J132D01*
G01Y1470282D01*
G02X1156424Y1470484I202J0D01*
G01X1159244D01*
G02X1159446Y1470281I-1J-203D01*
G01Y1469661D01*
G03X1159496Y1469529I200J0D01*
G02Y1466613I-1661J-1458D01*
G03X1159446Y1466481I150J-132D01*
G01Y1464543D01*
G03X1159496Y1464411I200J0D01*
G02Y1461495I-1661J-1458D01*
G03X1159446Y1461363I150J-132D01*
G01Y1460742D01*
G37*
G36*
G01X1661808D02*
G02X1661606Y1460540I-202J0D01*
G01X1658786D01*
G02X1658584Y1460743I1J203D01*
G01Y1461363D01*
G03X1658534Y1461495I-200J0D01*
G02Y1464411I1661J1458D01*
G03X1658584Y1464543I-150J132D01*
G01Y1466481D01*
G03X1658534Y1466613I-200J0D01*
G02Y1469529I1661J1458D01*
G03X1658584Y1469661I-150J132D01*
G01Y1470282D01*
G02X1658786Y1470484I202J0D01*
G01X1661606D01*
G02X1661808Y1470281I-1J-203D01*
G01Y1469661D01*
G03X1661858Y1469529I200J0D01*
G02Y1466613I-1661J-1458D01*
G03X1661808Y1466481I150J-132D01*
G01Y1464543D01*
G03X1661858Y1464411I200J0D01*
G02Y1461495I-1661J-1458D01*
G03X1661808Y1461363I150J-132D01*
G01Y1460742D01*
G37*
G36*
G01X1676109Y1470484D02*
X1678929D01*
G02X1679132Y1470281I0J-203D01*
G01Y1469659D01*
G03X1679182Y1469527I200J0D01*
G02Y1466615I-1664J-1456D01*
G03X1679132Y1466483I150J-132D01*
G01Y1464541D01*
G03X1679182Y1464409I200J0D01*
G02Y1461497I-1664J-1456D01*
G03X1679132Y1461365I150J-132D01*
G01Y1460743D01*
G02X1678929Y1460540I-203J0D01*
G01X1676109D01*
G02X1675906Y1460743I0J203D01*
G01Y1461365D01*
G03X1675856Y1461497I-200J0D01*
G02Y1464409I1664J1456D01*
G03X1675906Y1464541I-150J132D01*
G01Y1466483D01*
G03X1675856Y1466615I-200J0D01*
G02Y1469527I1664J1456D01*
G03X1675906Y1469659I-150J132D01*
G01Y1470281D01*
G02X1676109Y1470484I203J0D01*
G37*
G36*
G01X111494Y1471766D02*
G02X111292Y1471564I-202J0D01*
G01X108472D01*
G02X108270Y1471767I1J203D01*
G01Y1472387D01*
G03X108220Y1472519I-200J0D01*
G02Y1475435I1661J1458D01*
G03X108270Y1475567I-150J132D01*
G01Y1477505D01*
G03X108220Y1477637I-200J0D01*
G02Y1480553I1661J1458D01*
G03X108270Y1480685I-150J132D01*
G01Y1481306D01*
G02X108472Y1481508I202J0D01*
G01X111292D01*
G02X111494Y1481305I-1J-203D01*
G01Y1480685D01*
G03X111544Y1480553I200J0D01*
G02Y1477637I-1661J-1458D01*
G03X111494Y1477505I150J-132D01*
G01Y1475567D01*
G03X111544Y1475435I200J0D01*
G02Y1472519I-1661J-1458D01*
G03X111494Y1472387I150J-132D01*
G01Y1471766D01*
G37*
G36*
G01X319368D02*
G02X319166Y1471564I-202J0D01*
G01X316346D01*
G02X316144Y1471767I1J203D01*
G01Y1472387D01*
G03X316094Y1472519I-200J0D01*
G02Y1475435I1661J1458D01*
G03X316144Y1475567I-150J132D01*
G01Y1477505D01*
G03X316094Y1477637I-200J0D01*
G02Y1480553I1661J1458D01*
G03X316144Y1480685I-150J132D01*
G01Y1481306D01*
G02X316346Y1481508I202J0D01*
G01X319166D01*
G02X319368Y1481305I-1J-203D01*
G01Y1480685D01*
G03X319418Y1480553I200J0D01*
G02Y1477637I-1661J-1458D01*
G03X319368Y1477505I150J-132D01*
G01Y1475567D01*
G03X319418Y1475435I200J0D01*
G02Y1472519I-1661J-1458D01*
G03X319368Y1472387I150J-132D01*
G01Y1471766D01*
G37*
G36*
G01X336690D02*
G02X336488Y1471564I-202J0D01*
G01X333668D01*
G02X333466Y1471767I1J203D01*
G01Y1472387D01*
G03X333416Y1472519I-200J0D01*
G02Y1475435I1661J1458D01*
G03X333466Y1475567I-150J132D01*
G01Y1477505D01*
G03X333416Y1477637I-200J0D01*
G02Y1480553I1661J1458D01*
G03X333466Y1480685I-150J132D01*
G01Y1481306D01*
G02X333668Y1481508I202J0D01*
G01X336488D01*
G02X336690Y1481305I-1J-203D01*
G01Y1480685D01*
G03X336740Y1480553I200J0D01*
G02Y1477637I-1661J-1458D01*
G03X336690Y1477505I150J-132D01*
G01Y1475567D01*
G03X336740Y1475435I200J0D01*
G02Y1472519I-1661J-1458D01*
G03X336690Y1472387I150J-132D01*
G01Y1471766D01*
G37*
G36*
G01X628157Y1481508D02*
X630977D01*
G02X631180Y1481305I0J-203D01*
G01Y1480683D01*
G03X631230Y1480551I200J0D01*
G02Y1477639I-1664J-1456D01*
G03X631180Y1477507I150J-132D01*
G01Y1475565D01*
G03X631230Y1475433I200J0D01*
G02Y1472521I-1664J-1456D01*
G03X631180Y1472389I150J-132D01*
G01Y1471767D01*
G02X630977Y1471564I-203J0D01*
G01X628157D01*
G02X627954Y1471767I0J203D01*
G01Y1472389D01*
G03X627904Y1472521I-200J0D01*
G02Y1475433I1664J1456D01*
G03X627954Y1475565I-150J132D01*
G01Y1477507D01*
G03X627904Y1477639I-200J0D01*
G02Y1480551I1664J1456D01*
G03X627954Y1480683I-150J132D01*
G01Y1481305D01*
G02X628157Y1481508I203J0D01*
G37*
G36*
G01X1133462Y1471766D02*
G02X1133260Y1471564I-202J0D01*
G01X1130440D01*
G02X1130238Y1471767I1J203D01*
G01Y1472387D01*
G03X1130188Y1472519I-200J0D01*
G02Y1475435I1661J1458D01*
G03X1130238Y1475567I-150J132D01*
G01Y1477505D01*
G03X1130188Y1477637I-200J0D01*
G02Y1480553I1661J1458D01*
G03X1130238Y1480685I-150J132D01*
G01Y1481306D01*
G02X1130440Y1481508I202J0D01*
G01X1133260D01*
G02X1133462Y1481305I-1J-203D01*
G01Y1480685D01*
G03X1133512Y1480553I200J0D01*
G02Y1477637I-1661J-1458D01*
G03X1133462Y1477505I150J-132D01*
G01Y1475567D01*
G03X1133512Y1475435I200J0D01*
G02Y1472519I-1661J-1458D01*
G03X1133462Y1472387I150J-132D01*
G01Y1471766D01*
G37*
G36*
G01X1147763Y1481508D02*
X1150583D01*
G02X1150786Y1481305I0J-203D01*
G01Y1480683D01*
G03X1150836Y1480551I200J0D01*
G02Y1477639I-1664J-1456D01*
G03X1150786Y1477507I150J-132D01*
G01Y1475565D01*
G03X1150836Y1475433I200J0D01*
G02Y1472521I-1664J-1456D01*
G03X1150786Y1472389I150J-132D01*
G01Y1471767D01*
G02X1150583Y1471564I-203J0D01*
G01X1147763D01*
G02X1147560Y1471767I0J203D01*
G01Y1472389D01*
G03X1147510Y1472521I-200J0D01*
G02Y1475433I1664J1456D01*
G03X1147560Y1475565I-150J132D01*
G01Y1477507D01*
G03X1147510Y1477639I-200J0D01*
G02Y1480551I1664J1456D01*
G03X1147560Y1480683I-150J132D01*
G01Y1481305D01*
G02X1147763Y1481508I203J0D01*
G37*
G36*
G01X1650125D02*
X1652945D01*
G02X1653148Y1481305I0J-203D01*
G01Y1480683D01*
G03X1653198Y1480551I200J0D01*
G02Y1477639I-1664J-1456D01*
G03X1653148Y1477507I150J-132D01*
G01Y1475565D01*
G03X1653198Y1475433I200J0D01*
G02Y1472521I-1664J-1456D01*
G03X1653148Y1472389I150J-132D01*
G01Y1471767D01*
G02X1652945Y1471564I-203J0D01*
G01X1650125D01*
G02X1649922Y1471767I0J203D01*
G01Y1472389D01*
G03X1649872Y1472521I-200J0D01*
G02Y1475433I1664J1456D01*
G03X1649922Y1475565I-150J132D01*
G01Y1477507D01*
G03X1649872Y1477639I-200J0D01*
G02Y1480551I1664J1456D01*
G03X1649922Y1480683I-150J132D01*
G01Y1481305D01*
G02X1650125Y1481508I203J0D01*
G37*
G36*
G01X1670470Y1471766D02*
G02X1670268Y1471564I-202J0D01*
G01X1667448D01*
G02X1667246Y1471767I1J203D01*
G01Y1472387D01*
G03X1667196Y1472519I-200J0D01*
G02Y1475435I1661J1458D01*
G03X1667246Y1475567I-150J132D01*
G01Y1477505D01*
G03X1667196Y1477637I-200J0D01*
G02Y1480553I1661J1458D01*
G03X1667246Y1480685I-150J132D01*
G01Y1481306D01*
G02X1667448Y1481508I202J0D01*
G01X1670268D01*
G02X1670470Y1481305I-1J-203D01*
G01Y1480685D01*
G03X1670520Y1480553I200J0D01*
G02Y1477637I-1661J-1458D01*
G03X1670470Y1477505I150J-132D01*
G01Y1475567D01*
G03X1670520Y1475435I200J0D01*
G02Y1472519I-1661J-1458D01*
G03X1670470Y1472387I150J-132D01*
G01Y1471766D01*
G37*
G36*
G01X117133Y1485838D02*
X119953D01*
G02X120156Y1485635I0J-203D01*
G01Y1485014D01*
G03X120206Y1484882I200J0D01*
G02Y1481970I-1664J-1456D01*
G03X120156Y1481838I150J-132D01*
G01Y1479896D01*
G03X120206Y1479764I200J0D01*
G02Y1476852I-1664J-1456D01*
G03X120156Y1476720I150J-132D01*
G01Y1476097D01*
G02X119953Y1475894I-203J0D01*
G01X117133D01*
G02X116930Y1476097I0J203D01*
G01Y1476720D01*
G03X116880Y1476852I-200J0D01*
G02Y1479764I1664J1456D01*
G03X116930Y1479896I-150J132D01*
G01Y1481838D01*
G03X116880Y1481970I-200J0D01*
G02Y1484882I1664J1456D01*
G03X116930Y1485014I-150J132D01*
G01Y1485635D01*
G02X117133Y1485838I203J0D01*
G37*
G36*
G01X310706Y1476096D02*
G02X310504Y1475894I-202J0D01*
G01X307684D01*
G02X307482Y1476097I1J203D01*
G01Y1476718D01*
G03X307432Y1476850I-200J0D01*
G02Y1479766I1661J1458D01*
G03X307482Y1479898I-150J132D01*
G01Y1481836D01*
G03X307432Y1481968I-200J0D01*
G02Y1484884I1661J1458D01*
G03X307482Y1485016I-150J132D01*
G01Y1485636D01*
G02X307684Y1485838I202J0D01*
G01X310504D01*
G02X310706Y1485635I-1J-203D01*
G01Y1485016D01*
G03X310756Y1484884I200J0D01*
G02Y1481968I-1661J-1458D01*
G03X310706Y1481836I150J-132D01*
G01Y1479898D01*
G03X310756Y1479766I200J0D01*
G02Y1476850I-1661J-1458D01*
G03X310706Y1476718I150J-132D01*
G01Y1476096D01*
G37*
G36*
G01X325007Y1485838D02*
X327827D01*
G02X328030Y1485635I0J-203D01*
G01Y1485014D01*
G03X328080Y1484882I200J0D01*
G02Y1481970I-1664J-1456D01*
G03X328030Y1481838I150J-132D01*
G01Y1479896D01*
G03X328080Y1479764I200J0D01*
G02Y1476852I-1664J-1456D01*
G03X328030Y1476720I150J-132D01*
G01Y1476097D01*
G02X327827Y1475894I-203J0D01*
G01X325007D01*
G02X324804Y1476097I0J203D01*
G01Y1476720D01*
G03X324754Y1476852I-200J0D01*
G02Y1479764I1664J1456D01*
G03X324804Y1479896I-150J132D01*
G01Y1481838D01*
G03X324754Y1481970I-200J0D01*
G02Y1484882I1664J1456D01*
G03X324804Y1485014I-150J132D01*
G01Y1485635D01*
G02X325007Y1485838I203J0D01*
G37*
G36*
G01X345352Y1476096D02*
G02X345150Y1475894I-202J0D01*
G01X342330D01*
G02X342128Y1476097I1J203D01*
G01Y1476718D01*
G03X342078Y1476850I-200J0D01*
G02Y1479766I1661J1458D01*
G03X342128Y1479898I-150J132D01*
G01Y1481836D01*
G03X342078Y1481968I-200J0D01*
G02Y1484884I1661J1458D01*
G03X342128Y1485016I-150J132D01*
G01Y1485636D01*
G02X342330Y1485838I202J0D01*
G01X345150D01*
G02X345352Y1485635I-1J-203D01*
G01Y1485016D01*
G03X345402Y1484884I200J0D01*
G02Y1481968I-1661J-1458D01*
G03X345352Y1481836I150J-132D01*
G01Y1479898D01*
G03X345402Y1479766I200J0D01*
G02Y1476850I-1661J-1458D01*
G03X345352Y1476718I150J-132D01*
G01Y1476096D01*
G37*
G36*
G01X639840D02*
G02X639638Y1475894I-202J0D01*
G01X636818D01*
G02X636616Y1476097I1J203D01*
G01Y1476718D01*
G03X636566Y1476850I-200J0D01*
G02Y1479766I1661J1458D01*
G03X636616Y1479898I-150J132D01*
G01Y1481836D01*
G03X636566Y1481968I-200J0D01*
G02Y1484884I1661J1458D01*
G03X636616Y1485016I-150J132D01*
G01Y1485636D01*
G02X636818Y1485838I202J0D01*
G01X639638D01*
G02X639840Y1485635I-1J-203D01*
G01Y1485016D01*
G03X639890Y1484884I200J0D01*
G02Y1481968I-1661J-1458D01*
G03X639840Y1481836I150J-132D01*
G01Y1479898D01*
G03X639890Y1479766I200J0D01*
G02Y1476850I-1661J-1458D01*
G03X639840Y1476718I150J-132D01*
G01Y1476096D01*
G37*
G36*
G01X1139101Y1485838D02*
X1141921D01*
G02X1142124Y1485635I0J-203D01*
G01Y1485014D01*
G03X1142174Y1484882I200J0D01*
G02Y1481970I-1664J-1456D01*
G03X1142124Y1481838I150J-132D01*
G01Y1479896D01*
G03X1142174Y1479764I200J0D01*
G02Y1476852I-1664J-1456D01*
G03X1142124Y1476720I150J-132D01*
G01Y1476097D01*
G02X1141921Y1475894I-203J0D01*
G01X1139101D01*
G02X1138898Y1476097I0J203D01*
G01Y1476720D01*
G03X1138848Y1476852I-200J0D01*
G02Y1479764I1664J1456D01*
G03X1138898Y1479896I-150J132D01*
G01Y1481838D01*
G03X1138848Y1481970I-200J0D01*
G02Y1484882I1664J1456D01*
G03X1138898Y1485014I-150J132D01*
G01Y1485635D01*
G02X1139101Y1485838I203J0D01*
G37*
G36*
G01X1159446Y1476096D02*
G02X1159244Y1475894I-202J0D01*
G01X1156424D01*
G02X1156222Y1476097I1J203D01*
G01Y1476718D01*
G03X1156172Y1476850I-200J0D01*
G02Y1479766I1661J1458D01*
G03X1156222Y1479898I-150J132D01*
G01Y1481836D01*
G03X1156172Y1481968I-200J0D01*
G02Y1484884I1661J1458D01*
G03X1156222Y1485016I-150J132D01*
G01Y1485636D01*
G02X1156424Y1485838I202J0D01*
G01X1159244D01*
G02X1159446Y1485635I-1J-203D01*
G01Y1485016D01*
G03X1159496Y1484884I200J0D01*
G02Y1481968I-1661J-1458D01*
G03X1159446Y1481836I150J-132D01*
G01Y1479898D01*
G03X1159496Y1479766I200J0D01*
G02Y1476850I-1661J-1458D01*
G03X1159446Y1476718I150J-132D01*
G01Y1476096D01*
G37*
G36*
G01X1661808D02*
G02X1661606Y1475894I-202J0D01*
G01X1658786D01*
G02X1658584Y1476097I1J203D01*
G01Y1476718D01*
G03X1658534Y1476850I-200J0D01*
G02Y1479766I1661J1458D01*
G03X1658584Y1479898I-150J132D01*
G01Y1481836D01*
G03X1658534Y1481968I-200J0D01*
G02Y1484884I1661J1458D01*
G03X1658584Y1485016I-150J132D01*
G01Y1485636D01*
G02X1658786Y1485838I202J0D01*
G01X1661606D01*
G02X1661808Y1485635I-1J-203D01*
G01Y1485016D01*
G03X1661858Y1484884I200J0D01*
G02Y1481968I-1661J-1458D01*
G03X1661808Y1481836I150J-132D01*
G01Y1479898D01*
G03X1661858Y1479766I200J0D01*
G02Y1476850I-1661J-1458D01*
G03X1661808Y1476718I150J-132D01*
G01Y1476096D01*
G37*
G36*
G01X1676109Y1485838D02*
X1678929D01*
G02X1679132Y1485635I0J-203D01*
G01Y1485014D01*
G03X1679182Y1484882I200J0D01*
G02Y1481970I-1664J-1456D01*
G03X1679132Y1481838I150J-132D01*
G01Y1479896D01*
G03X1679182Y1479764I200J0D01*
G02Y1476852I-1664J-1456D01*
G03X1679132Y1476720I150J-132D01*
G01Y1476097D01*
G02X1678929Y1475894I-203J0D01*
G01X1676109D01*
G02X1675906Y1476097I0J203D01*
G01Y1476720D01*
G03X1675856Y1476852I-200J0D01*
G02Y1479764I1664J1456D01*
G03X1675906Y1479896I-150J132D01*
G01Y1481838D01*
G03X1675856Y1481970I-200J0D01*
G02Y1484882I1664J1456D01*
G03X1675906Y1485014I-150J132D01*
G01Y1485635D01*
G02X1676109Y1485838I203J0D01*
G37*
G36*
G01X111494Y1487120D02*
G02X111292Y1486918I-202J0D01*
G01X108472D01*
G02X108270Y1487121I1J203D01*
G01Y1487741D01*
G03X108220Y1487873I-200J0D01*
G02Y1490789I1661J1458D01*
G03X108270Y1490921I-150J132D01*
G01Y1492859D01*
G03X108220Y1492991I-200J0D01*
G02Y1495907I1661J1458D01*
G03X108270Y1496039I-150J132D01*
G01Y1496660D01*
G02X108472Y1496862I202J0D01*
G01X111292D01*
G02X111494Y1496659I-1J-203D01*
G01Y1496039D01*
G03X111544Y1495907I200J0D01*
G02Y1492991I-1661J-1458D01*
G03X111494Y1492859I150J-132D01*
G01Y1490921D01*
G03X111544Y1490789I200J0D01*
G02Y1487873I-1661J-1458D01*
G03X111494Y1487741I150J-132D01*
G01Y1487120D01*
G37*
G36*
G01X319368D02*
G02X319166Y1486918I-202J0D01*
G01X316346D01*
G02X316144Y1487121I1J203D01*
G01Y1487741D01*
G03X316094Y1487873I-200J0D01*
G02Y1490789I1661J1458D01*
G03X316144Y1490921I-150J132D01*
G01Y1492859D01*
G03X316094Y1492991I-200J0D01*
G02Y1495907I1661J1458D01*
G03X316144Y1496039I-150J132D01*
G01Y1496660D01*
G02X316346Y1496862I202J0D01*
G01X319166D01*
G02X319368Y1496659I-1J-203D01*
G01Y1496039D01*
G03X319418Y1495907I200J0D01*
G02Y1492991I-1661J-1458D01*
G03X319368Y1492859I150J-132D01*
G01Y1490921D01*
G03X319418Y1490789I200J0D01*
G02Y1487873I-1661J-1458D01*
G03X319368Y1487741I150J-132D01*
G01Y1487120D01*
G37*
G36*
G01X336690D02*
G02X336488Y1486918I-202J0D01*
G01X333668D01*
G02X333466Y1487121I1J203D01*
G01Y1487741D01*
G03X333416Y1487873I-200J0D01*
G02Y1490789I1661J1458D01*
G03X333466Y1490921I-150J132D01*
G01Y1492859D01*
G03X333416Y1492991I-200J0D01*
G02Y1495907I1661J1458D01*
G03X333466Y1496039I-150J132D01*
G01Y1496660D01*
G02X333668Y1496862I202J0D01*
G01X336488D01*
G02X336690Y1496659I-1J-203D01*
G01Y1496039D01*
G03X336740Y1495907I200J0D01*
G02Y1492991I-1661J-1458D01*
G03X336690Y1492859I150J-132D01*
G01Y1490921D01*
G03X336740Y1490789I200J0D01*
G02Y1487873I-1661J-1458D01*
G03X336690Y1487741I150J-132D01*
G01Y1487120D01*
G37*
G36*
G01X628157Y1496862D02*
X630977D01*
G02X631180Y1496659I0J-203D01*
G01Y1496037D01*
G03X631230Y1495905I200J0D01*
G02Y1492993I-1664J-1456D01*
G03X631180Y1492861I150J-132D01*
G01Y1490919D01*
G03X631230Y1490787I200J0D01*
G02Y1487875I-1664J-1456D01*
G03X631180Y1487743I150J-132D01*
G01Y1487121D01*
G02X630977Y1486918I-203J0D01*
G01X628157D01*
G02X627954Y1487121I0J203D01*
G01Y1487743D01*
G03X627904Y1487875I-200J0D01*
G02Y1490787I1664J1456D01*
G03X627954Y1490919I-150J132D01*
G01Y1492861D01*
G03X627904Y1492993I-200J0D01*
G02Y1495905I1664J1456D01*
G03X627954Y1496037I-150J132D01*
G01Y1496659D01*
G02X628157Y1496862I203J0D01*
G37*
G36*
G01X1133462Y1487120D02*
G02X1133260Y1486918I-202J0D01*
G01X1130440D01*
G02X1130238Y1487121I1J203D01*
G01Y1487741D01*
G03X1130188Y1487873I-200J0D01*
G02Y1490789I1661J1458D01*
G03X1130238Y1490921I-150J132D01*
G01Y1492859D01*
G03X1130188Y1492991I-200J0D01*
G02Y1495907I1661J1458D01*
G03X1130238Y1496039I-150J132D01*
G01Y1496660D01*
G02X1130440Y1496862I202J0D01*
G01X1133260D01*
G02X1133462Y1496659I-1J-203D01*
G01Y1496039D01*
G03X1133512Y1495907I200J0D01*
G02Y1492991I-1661J-1458D01*
G03X1133462Y1492859I150J-132D01*
G01Y1490921D01*
G03X1133512Y1490789I200J0D01*
G02Y1487873I-1661J-1458D01*
G03X1133462Y1487741I150J-132D01*
G01Y1487120D01*
G37*
G36*
G01X1147763Y1496862D02*
X1150583D01*
G02X1150786Y1496659I0J-203D01*
G01Y1496037D01*
G03X1150836Y1495905I200J0D01*
G02Y1492993I-1664J-1456D01*
G03X1150786Y1492861I150J-132D01*
G01Y1490919D01*
G03X1150836Y1490787I200J0D01*
G02Y1487875I-1664J-1456D01*
G03X1150786Y1487743I150J-132D01*
G01Y1487121D01*
G02X1150583Y1486918I-203J0D01*
G01X1147763D01*
G02X1147560Y1487121I0J203D01*
G01Y1487743D01*
G03X1147510Y1487875I-200J0D01*
G02Y1490787I1664J1456D01*
G03X1147560Y1490919I-150J132D01*
G01Y1492861D01*
G03X1147510Y1492993I-200J0D01*
G02Y1495905I1664J1456D01*
G03X1147560Y1496037I-150J132D01*
G01Y1496659D01*
G02X1147763Y1496862I203J0D01*
G37*
G36*
G01X1650125D02*
X1652945D01*
G02X1653148Y1496659I0J-203D01*
G01Y1496037D01*
G03X1653198Y1495905I200J0D01*
G02Y1492993I-1664J-1456D01*
G03X1653148Y1492861I150J-132D01*
G01Y1490919D01*
G03X1653198Y1490787I200J0D01*
G02Y1487875I-1664J-1456D01*
G03X1653148Y1487743I150J-132D01*
G01Y1487121D01*
G02X1652945Y1486918I-203J0D01*
G01X1650125D01*
G02X1649922Y1487121I0J203D01*
G01Y1487743D01*
G03X1649872Y1487875I-200J0D01*
G02Y1490787I1664J1456D01*
G03X1649922Y1490919I-150J132D01*
G01Y1492861D01*
G03X1649872Y1492993I-200J0D01*
G02Y1495905I1664J1456D01*
G03X1649922Y1496037I-150J132D01*
G01Y1496659D01*
G02X1650125Y1496862I203J0D01*
G37*
G36*
G01X1670470Y1487120D02*
G02X1670268Y1486918I-202J0D01*
G01X1667448D01*
G02X1667246Y1487121I1J203D01*
G01Y1487741D01*
G03X1667196Y1487873I-200J0D01*
G02Y1490789I1661J1458D01*
G03X1667246Y1490921I-150J132D01*
G01Y1492859D01*
G03X1667196Y1492991I-200J0D01*
G02Y1495907I1661J1458D01*
G03X1667246Y1496039I-150J132D01*
G01Y1496660D01*
G02X1667448Y1496862I202J0D01*
G01X1670268D01*
G02X1670470Y1496659I-1J-203D01*
G01Y1496039D01*
G03X1670520Y1495907I200J0D01*
G02Y1492991I-1661J-1458D01*
G03X1670470Y1492859I150J-132D01*
G01Y1490921D01*
G03X1670520Y1490789I200J0D01*
G02Y1487873I-1661J-1458D01*
G03X1670470Y1487741I150J-132D01*
G01Y1487120D01*
G37*
G36*
G01X117133Y1501192D02*
X119953D01*
G02X120156Y1500989I0J-203D01*
G01Y1500368D01*
G03X120206Y1500236I200J0D01*
G02Y1497324I-1664J-1456D01*
G03X120156Y1497192I150J-132D01*
G01Y1495250D01*
G03X120206Y1495118I200J0D01*
G02Y1492206I-1664J-1456D01*
G03X120156Y1492074I150J-132D01*
G01Y1491451D01*
G02X119953Y1491248I-203J0D01*
G01X117133D01*
G02X116930Y1491451I0J203D01*
G01Y1492074D01*
G03X116880Y1492206I-200J0D01*
G02Y1495118I1664J1456D01*
G03X116930Y1495250I-150J132D01*
G01Y1497192D01*
G03X116880Y1497324I-200J0D01*
G02Y1500236I1664J1456D01*
G03X116930Y1500368I-150J132D01*
G01Y1500989D01*
G02X117133Y1501192I203J0D01*
G37*
G36*
G01X310706Y1491450D02*
G02X310504Y1491248I-202J0D01*
G01X307684D01*
G02X307482Y1491451I1J203D01*
G01Y1492072D01*
G03X307432Y1492204I-200J0D01*
G02Y1495120I1661J1458D01*
G03X307482Y1495252I-150J132D01*
G01Y1497190D01*
G03X307432Y1497322I-200J0D01*
G02Y1500238I1661J1458D01*
G03X307482Y1500370I-150J132D01*
G01Y1500990D01*
G02X307684Y1501192I202J0D01*
G01X310504D01*
G02X310706Y1500989I-1J-203D01*
G01Y1500370D01*
G03X310756Y1500238I200J0D01*
G02Y1497322I-1661J-1458D01*
G03X310706Y1497190I150J-132D01*
G01Y1495252D01*
G03X310756Y1495120I200J0D01*
G02Y1492204I-1661J-1458D01*
G03X310706Y1492072I150J-132D01*
G01Y1491450D01*
G37*
G36*
G01X325007Y1501192D02*
X327827D01*
G02X328030Y1500989I0J-203D01*
G01Y1500368D01*
G03X328080Y1500236I200J0D01*
G02Y1497324I-1664J-1456D01*
G03X328030Y1497192I150J-132D01*
G01Y1495250D01*
G03X328080Y1495118I200J0D01*
G02Y1492206I-1664J-1456D01*
G03X328030Y1492074I150J-132D01*
G01Y1491451D01*
G02X327827Y1491248I-203J0D01*
G01X325007D01*
G02X324804Y1491451I0J203D01*
G01Y1492074D01*
G03X324754Y1492206I-200J0D01*
G02Y1495118I1664J1456D01*
G03X324804Y1495250I-150J132D01*
G01Y1497192D01*
G03X324754Y1497324I-200J0D01*
G02Y1500236I1664J1456D01*
G03X324804Y1500368I-150J132D01*
G01Y1500989D01*
G02X325007Y1501192I203J0D01*
G37*
G36*
G01X345352Y1491450D02*
G02X345150Y1491248I-202J0D01*
G01X342330D01*
G02X342128Y1491451I1J203D01*
G01Y1492072D01*
G03X342078Y1492204I-200J0D01*
G02Y1495120I1661J1458D01*
G03X342128Y1495252I-150J132D01*
G01Y1497190D01*
G03X342078Y1497322I-200J0D01*
G02Y1500238I1661J1458D01*
G03X342128Y1500370I-150J132D01*
G01Y1500990D01*
G02X342330Y1501192I202J0D01*
G01X345150D01*
G02X345352Y1500989I-1J-203D01*
G01Y1500370D01*
G03X345402Y1500238I200J0D01*
G02Y1497322I-1661J-1458D01*
G03X345352Y1497190I150J-132D01*
G01Y1495252D01*
G03X345402Y1495120I200J0D01*
G02Y1492204I-1661J-1458D01*
G03X345352Y1492072I150J-132D01*
G01Y1491450D01*
G37*
G36*
G01X639840D02*
G02X639638Y1491248I-202J0D01*
G01X636818D01*
G02X636616Y1491451I1J203D01*
G01Y1492072D01*
G03X636566Y1492204I-200J0D01*
G02Y1495120I1661J1458D01*
G03X636616Y1495252I-150J132D01*
G01Y1497190D01*
G03X636566Y1497322I-200J0D01*
G02Y1500238I1661J1458D01*
G03X636616Y1500370I-150J132D01*
G01Y1500990D01*
G02X636818Y1501192I202J0D01*
G01X639638D01*
G02X639840Y1500989I-1J-203D01*
G01Y1500370D01*
G03X639890Y1500238I200J0D01*
G02Y1497322I-1661J-1458D01*
G03X639840Y1497190I150J-132D01*
G01Y1495252D01*
G03X639890Y1495120I200J0D01*
G02Y1492204I-1661J-1458D01*
G03X639840Y1492072I150J-132D01*
G01Y1491450D01*
G37*
G36*
G01X1139101Y1501192D02*
X1141921D01*
G02X1142124Y1500989I0J-203D01*
G01Y1500368D01*
G03X1142174Y1500236I200J0D01*
G02Y1497324I-1664J-1456D01*
G03X1142124Y1497192I150J-132D01*
G01Y1495250D01*
G03X1142174Y1495118I200J0D01*
G02Y1492206I-1664J-1456D01*
G03X1142124Y1492074I150J-132D01*
G01Y1491451D01*
G02X1141921Y1491248I-203J0D01*
G01X1139101D01*
G02X1138898Y1491451I0J203D01*
G01Y1492074D01*
G03X1138848Y1492206I-200J0D01*
G02Y1495118I1664J1456D01*
G03X1138898Y1495250I-150J132D01*
G01Y1497192D01*
G03X1138848Y1497324I-200J0D01*
G02Y1500236I1664J1456D01*
G03X1138898Y1500368I-150J132D01*
G01Y1500989D01*
G02X1139101Y1501192I203J0D01*
G37*
G36*
G01X1159446Y1491450D02*
G02X1159244Y1491248I-202J0D01*
G01X1156424D01*
G02X1156222Y1491451I1J203D01*
G01Y1492072D01*
G03X1156172Y1492204I-200J0D01*
G02Y1495120I1661J1458D01*
G03X1156222Y1495252I-150J132D01*
G01Y1497190D01*
G03X1156172Y1497322I-200J0D01*
G02Y1500238I1661J1458D01*
G03X1156222Y1500370I-150J132D01*
G01Y1500990D01*
G02X1156424Y1501192I202J0D01*
G01X1159244D01*
G02X1159446Y1500989I-1J-203D01*
G01Y1500370D01*
G03X1159496Y1500238I200J0D01*
G02Y1497322I-1661J-1458D01*
G03X1159446Y1497190I150J-132D01*
G01Y1495252D01*
G03X1159496Y1495120I200J0D01*
G02Y1492204I-1661J-1458D01*
G03X1159446Y1492072I150J-132D01*
G01Y1491450D01*
G37*
G36*
G01X1661808D02*
G02X1661606Y1491248I-202J0D01*
G01X1658786D01*
G02X1658584Y1491451I1J203D01*
G01Y1492072D01*
G03X1658534Y1492204I-200J0D01*
G02Y1495120I1661J1458D01*
G03X1658584Y1495252I-150J132D01*
G01Y1497190D01*
G03X1658534Y1497322I-200J0D01*
G02Y1500238I1661J1458D01*
G03X1658584Y1500370I-150J132D01*
G01Y1500990D01*
G02X1658786Y1501192I202J0D01*
G01X1661606D01*
G02X1661808Y1500989I-1J-203D01*
G01Y1500370D01*
G03X1661858Y1500238I200J0D01*
G02Y1497322I-1661J-1458D01*
G03X1661808Y1497190I150J-132D01*
G01Y1495252D01*
G03X1661858Y1495120I200J0D01*
G02Y1492204I-1661J-1458D01*
G03X1661808Y1492072I150J-132D01*
G01Y1491450D01*
G37*
G36*
G01X1676109Y1501192D02*
X1678929D01*
G02X1679132Y1500989I0J-203D01*
G01Y1500368D01*
G03X1679182Y1500236I200J0D01*
G02Y1497324I-1664J-1456D01*
G03X1679132Y1497192I150J-132D01*
G01Y1495250D01*
G03X1679182Y1495118I200J0D01*
G02Y1492206I-1664J-1456D01*
G03X1679132Y1492074I150J-132D01*
G01Y1491451D01*
G02X1678929Y1491248I-203J0D01*
G01X1676109D01*
G02X1675906Y1491451I0J203D01*
G01Y1492074D01*
G03X1675856Y1492206I-200J0D01*
G02Y1495118I1664J1456D01*
G03X1675906Y1495250I-150J132D01*
G01Y1497192D01*
G03X1675856Y1497324I-200J0D01*
G02Y1500236I1664J1456D01*
G03X1675906Y1500368I-150J132D01*
G01Y1500989D01*
G02X1676109Y1501192I203J0D01*
G37*
G36*
G01X108472Y1512216D02*
X111292D01*
G02X111494Y1512014I0J-202D01*
G01Y1511394D01*
G03X111544Y1511262I200J0D01*
G02Y1508346I-1661J-1458D01*
G03X111494Y1508214I150J-132D01*
G01Y1506275D01*
G03X111544Y1506143I200J0D01*
G02Y1503227I-1661J-1458D01*
G03X111494Y1503095I150J-132D01*
G01Y1502476D01*
G02X111292Y1502274I-202J0D01*
G01X108472D01*
G02X108270Y1502476I0J202D01*
G01Y1503095D01*
G03X108220Y1503227I-200J0D01*
G02Y1506143I1661J1458D01*
G03X108270Y1506275I-150J132D01*
G01Y1508214D01*
G03X108220Y1508346I-200J0D01*
G02Y1511262I1661J1458D01*
G03X108270Y1511394I-150J132D01*
G01Y1512014D01*
G02X108472Y1512216I202J0D01*
G37*
G36*
G01X316346D02*
X319166D01*
G02X319368Y1512014I0J-202D01*
G01Y1511394D01*
G03X319418Y1511262I200J0D01*
G02Y1508346I-1661J-1458D01*
G03X319368Y1508214I150J-132D01*
G01Y1506275D01*
G03X319418Y1506143I200J0D01*
G02Y1503227I-1661J-1458D01*
G03X319368Y1503095I150J-132D01*
G01Y1502476D01*
G02X319166Y1502274I-202J0D01*
G01X316346D01*
G02X316144Y1502476I0J202D01*
G01Y1503095D01*
G03X316094Y1503227I-200J0D01*
G02Y1506143I1661J1458D01*
G03X316144Y1506275I-150J132D01*
G01Y1508214D01*
G03X316094Y1508346I-200J0D01*
G02Y1511262I1661J1458D01*
G03X316144Y1511394I-150J132D01*
G01Y1512014D01*
G02X316346Y1512216I202J0D01*
G37*
G36*
G01X333668D02*
X336488D01*
G02X336690Y1512014I0J-202D01*
G01Y1511394D01*
G03X336740Y1511262I200J0D01*
G02Y1508346I-1661J-1458D01*
G03X336690Y1508214I150J-132D01*
G01Y1506275D01*
G03X336740Y1506143I200J0D01*
G02Y1503227I-1661J-1458D01*
G03X336690Y1503095I150J-132D01*
G01Y1502476D01*
G02X336488Y1502274I-202J0D01*
G01X333668D01*
G02X333466Y1502476I0J202D01*
G01Y1503095D01*
G03X333416Y1503227I-200J0D01*
G02Y1506143I1661J1458D01*
G03X333466Y1506275I-150J132D01*
G01Y1508214D01*
G03X333416Y1508346I-200J0D01*
G02Y1511262I1661J1458D01*
G03X333466Y1511394I-150J132D01*
G01Y1512014D01*
G02X333668Y1512216I202J0D01*
G37*
G36*
G01X1130440D02*
X1133260D01*
G02X1133462Y1512014I0J-202D01*
G01Y1511394D01*
G03X1133512Y1511262I200J0D01*
G02Y1508346I-1661J-1458D01*
G03X1133462Y1508214I150J-132D01*
G01Y1506275D01*
G03X1133512Y1506143I200J0D01*
G02Y1503227I-1661J-1458D01*
G03X1133462Y1503095I150J-132D01*
G01Y1502476D01*
G02X1133260Y1502274I-202J0D01*
G01X1130440D01*
G02X1130238Y1502476I0J202D01*
G01Y1503095D01*
G03X1130188Y1503227I-200J0D01*
G02Y1506143I1661J1458D01*
G03X1130238Y1506275I-150J132D01*
G01Y1508214D01*
G03X1130188Y1508346I-200J0D01*
G02Y1511262I1661J1458D01*
G03X1130238Y1511394I-150J132D01*
G01Y1512014D01*
G02X1130440Y1512216I202J0D01*
G37*
G36*
G01X1667448D02*
X1670268D01*
G02X1670470Y1512014I0J-202D01*
G01Y1511394D01*
G03X1670520Y1511262I200J0D01*
G02Y1508346I-1661J-1458D01*
G03X1670470Y1508214I150J-132D01*
G01Y1506275D01*
G03X1670520Y1506143I200J0D01*
G02Y1503227I-1661J-1458D01*
G03X1670470Y1503095I150J-132D01*
G01Y1502476D01*
G02X1670268Y1502274I-202J0D01*
G01X1667448D01*
G02X1667246Y1502476I0J202D01*
G01Y1503095D01*
G03X1667196Y1503227I-200J0D01*
G02Y1506143I1661J1458D01*
G03X1667246Y1506275I-150J132D01*
G01Y1508214D01*
G03X1667196Y1508346I-200J0D01*
G02Y1511262I1661J1458D01*
G03X1667246Y1511394I-150J132D01*
G01Y1512014D01*
G02X1667448Y1512216I202J0D01*
G37*
G36*
G01X628156Y1502274D02*
G02X627954Y1502476I0J202D01*
G01Y1503097D01*
G03X627904Y1503229I-200J0D01*
G02Y1506141I1664J1456D01*
G03X627954Y1506273I-150J132D01*
G01Y1508216D01*
G03X627904Y1508348I-200J0D01*
G02Y1511260I1664J1456D01*
G03X627954Y1511392I-150J132D01*
G01Y1512014D01*
G02X628157Y1512216I203J-1D01*
G01X630978D01*
G02X631180Y1512014I0J-202D01*
G01Y1511392D01*
G03X631230Y1511260I200J0D01*
G02Y1508348I-1664J-1456D01*
G03X631180Y1508216I150J-132D01*
G01Y1506273D01*
G03X631230Y1506141I200J0D01*
G02Y1503229I-1664J-1456D01*
G03X631180Y1503097I150J-132D01*
G01Y1502476D01*
G02X630977Y1502274I-203J1D01*
G01X628156D01*
G37*
G36*
G01X1147762D02*
G02X1147560Y1502476I0J202D01*
G01Y1503097D01*
G03X1147510Y1503229I-200J0D01*
G02Y1506141I1664J1456D01*
G03X1147560Y1506273I-150J132D01*
G01Y1508216D01*
G03X1147510Y1508348I-200J0D01*
G02Y1511260I1664J1456D01*
G03X1147560Y1511392I-150J132D01*
G01Y1512014D01*
G02X1147763Y1512216I203J-1D01*
G01X1150584D01*
G02X1150786Y1512014I0J-202D01*
G01Y1511392D01*
G03X1150836Y1511260I200J0D01*
G02Y1508348I-1664J-1456D01*
G03X1150786Y1508216I150J-132D01*
G01Y1506273D01*
G03X1150836Y1506141I200J0D01*
G02Y1503229I-1664J-1456D01*
G03X1150786Y1503097I150J-132D01*
G01Y1502476D01*
G02X1150583Y1502274I-203J1D01*
G01X1147762D01*
G37*
G36*
G01X1650124D02*
G02X1649922Y1502476I0J202D01*
G01Y1503097D01*
G03X1649872Y1503229I-200J0D01*
G02Y1506141I1664J1456D01*
G03X1649922Y1506273I-150J132D01*
G01Y1508216D01*
G03X1649872Y1508348I-200J0D01*
G02Y1511260I1664J1456D01*
G03X1649922Y1511392I-150J132D01*
G01Y1512014D01*
G02X1650125Y1512216I203J-1D01*
G01X1652946D01*
G02X1653148Y1512014I0J-202D01*
G01Y1511392D01*
G03X1653198Y1511260I200J0D01*
G02Y1508348I-1664J-1456D01*
G03X1653148Y1508216I150J-132D01*
G01Y1506273D01*
G03X1653198Y1506141I200J0D01*
G02Y1503229I-1664J-1456D01*
G03X1653148Y1503097I150J-132D01*
G01Y1502476D01*
G02X1652945Y1502274I-203J1D01*
G01X1650124D01*
G37*
G36*
G01X307684Y1516546D02*
X310504D01*
G02X310706Y1516344I0J-202D01*
G01Y1515724D01*
G03X310756Y1515592I200J0D01*
G02Y1512676I-1661J-1458D01*
G03X310706Y1512544I150J-132D01*
G01Y1510606D01*
G03X310756Y1510474I200J0D01*
G02Y1507558I-1661J-1458D01*
G03X310706Y1507426I150J-132D01*
G01Y1506806D01*
G02X310504Y1506604I-202J0D01*
G01X307684D01*
G02X307482Y1506806I0J202D01*
G01Y1507426D01*
G03X307432Y1507558I-200J0D01*
G02Y1510474I1661J1458D01*
G03X307482Y1510606I-150J132D01*
G01Y1512544D01*
G03X307432Y1512676I-200J0D01*
G02Y1515592I1661J1458D01*
G03X307482Y1515724I-150J132D01*
G01Y1516344D01*
G02X307684Y1516546I202J0D01*
G37*
G36*
G01X342330D02*
X345150D01*
G02X345352Y1516344I0J-202D01*
G01Y1515724D01*
G03X345402Y1515592I200J0D01*
G02Y1512676I-1661J-1458D01*
G03X345352Y1512544I150J-132D01*
G01Y1510606D01*
G03X345402Y1510474I200J0D01*
G02Y1507558I-1661J-1458D01*
G03X345352Y1507426I150J-132D01*
G01Y1506806D01*
G02X345150Y1506604I-202J0D01*
G01X342330D01*
G02X342128Y1506806I0J202D01*
G01Y1507426D01*
G03X342078Y1507558I-200J0D01*
G02Y1510474I1661J1458D01*
G03X342128Y1510606I-150J132D01*
G01Y1512544D01*
G03X342078Y1512676I-200J0D01*
G02Y1515592I1661J1458D01*
G03X342128Y1515724I-150J132D01*
G01Y1516344D01*
G02X342330Y1516546I202J0D01*
G37*
G36*
G01X636818D02*
X639638D01*
G02X639840Y1516344I0J-202D01*
G01Y1515724D01*
G03X639890Y1515592I200J0D01*
G02Y1512676I-1661J-1458D01*
G03X639840Y1512544I150J-132D01*
G01Y1510606D01*
G03X639890Y1510474I200J0D01*
G02Y1507558I-1661J-1458D01*
G03X639840Y1507426I150J-132D01*
G01Y1506806D01*
G02X639638Y1506604I-202J0D01*
G01X636818D01*
G02X636616Y1506806I0J202D01*
G01Y1507426D01*
G03X636566Y1507558I-200J0D01*
G02Y1510474I1661J1458D01*
G03X636616Y1510606I-150J132D01*
G01Y1512544D01*
G03X636566Y1512676I-200J0D01*
G02Y1515592I1661J1458D01*
G03X636616Y1515724I-150J132D01*
G01Y1516344D01*
G02X636818Y1516546I202J0D01*
G37*
G36*
G01X1156424D02*
X1159244D01*
G02X1159446Y1516344I0J-202D01*
G01Y1515724D01*
G03X1159496Y1515592I200J0D01*
G02Y1512676I-1661J-1458D01*
G03X1159446Y1512544I150J-132D01*
G01Y1510606D01*
G03X1159496Y1510474I200J0D01*
G02Y1507558I-1661J-1458D01*
G03X1159446Y1507426I150J-132D01*
G01Y1506806D01*
G02X1159244Y1506604I-202J0D01*
G01X1156424D01*
G02X1156222Y1506806I0J202D01*
G01Y1507426D01*
G03X1156172Y1507558I-200J0D01*
G02Y1510474I1661J1458D01*
G03X1156222Y1510606I-150J132D01*
G01Y1512544D01*
G03X1156172Y1512676I-200J0D01*
G02Y1515592I1661J1458D01*
G03X1156222Y1515724I-150J132D01*
G01Y1516344D01*
G02X1156424Y1516546I202J0D01*
G37*
G36*
G01X1658786D02*
X1661606D01*
G02X1661808Y1516344I0J-202D01*
G01Y1515724D01*
G03X1661858Y1515592I200J0D01*
G02Y1512676I-1661J-1458D01*
G03X1661808Y1512544I150J-132D01*
G01Y1510606D01*
G03X1661858Y1510474I200J0D01*
G02Y1507558I-1661J-1458D01*
G03X1661808Y1507426I150J-132D01*
G01Y1506806D01*
G02X1661606Y1506604I-202J0D01*
G01X1658786D01*
G02X1658584Y1506806I0J202D01*
G01Y1507426D01*
G03X1658534Y1507558I-200J0D01*
G02Y1510474I1661J1458D01*
G03X1658584Y1510606I-150J132D01*
G01Y1512544D01*
G03X1658534Y1512676I-200J0D01*
G02Y1515592I1661J1458D01*
G03X1658584Y1515724I-150J132D01*
G01Y1516344D01*
G02X1658786Y1516546I202J0D01*
G37*
G36*
G01X117132Y1506604D02*
G02X116930Y1506806I0J202D01*
G01Y1507428D01*
G03X116880Y1507560I-200J0D01*
G02Y1510472I1664J1456D01*
G03X116930Y1510604I-150J132D01*
G01Y1512546D01*
G03X116880Y1512678I-200J0D01*
G02Y1515590I1664J1456D01*
G03X116930Y1515722I-150J132D01*
G01Y1516344D01*
G02X117133Y1516546I203J-1D01*
G01X119954D01*
G02X120156Y1516344I0J-202D01*
G01Y1515722D01*
G03X120206Y1515590I200J0D01*
G02Y1512678I-1664J-1456D01*
G03X120156Y1512546I150J-132D01*
G01Y1510604D01*
G03X120206Y1510472I200J0D01*
G02Y1507560I-1664J-1456D01*
G03X120156Y1507428I150J-132D01*
G01Y1506806D01*
G02X119953Y1506604I-203J1D01*
G01X117132D01*
G37*
G36*
G01X325006D02*
G02X324804Y1506806I0J202D01*
G01Y1507428D01*
G03X324754Y1507560I-200J0D01*
G02Y1510472I1664J1456D01*
G03X324804Y1510604I-150J132D01*
G01Y1512546D01*
G03X324754Y1512678I-200J0D01*
G02Y1515590I1664J1456D01*
G03X324804Y1515722I-150J132D01*
G01Y1516344D01*
G02X325007Y1516546I203J-1D01*
G01X327828D01*
G02X328030Y1516344I0J-202D01*
G01Y1515722D01*
G03X328080Y1515590I200J0D01*
G02Y1512678I-1664J-1456D01*
G03X328030Y1512546I150J-132D01*
G01Y1510604D01*
G03X328080Y1510472I200J0D01*
G02Y1507560I-1664J-1456D01*
G03X328030Y1507428I150J-132D01*
G01Y1506806D01*
G02X327827Y1506604I-203J1D01*
G01X325006D01*
G37*
G36*
G01X1139100D02*
G02X1138898Y1506806I0J202D01*
G01Y1507428D01*
G03X1138848Y1507560I-200J0D01*
G02Y1510472I1664J1456D01*
G03X1138898Y1510604I-150J132D01*
G01Y1512546D01*
G03X1138848Y1512678I-200J0D01*
G02Y1515590I1664J1456D01*
G03X1138898Y1515722I-150J132D01*
G01Y1516344D01*
G02X1139101Y1516546I203J-1D01*
G01X1141922D01*
G02X1142124Y1516344I0J-202D01*
G01Y1515722D01*
G03X1142174Y1515590I200J0D01*
G02Y1512678I-1664J-1456D01*
G03X1142124Y1512546I150J-132D01*
G01Y1510604D01*
G03X1142174Y1510472I200J0D01*
G02Y1507560I-1664J-1456D01*
G03X1142124Y1507428I150J-132D01*
G01Y1506806D01*
G02X1141921Y1506604I-203J1D01*
G01X1139100D01*
G37*
G36*
G01X1676108D02*
G02X1675906Y1506806I0J202D01*
G01Y1507428D01*
G03X1675856Y1507560I-200J0D01*
G02Y1510472I1664J1456D01*
G03X1675906Y1510604I-150J132D01*
G01Y1512546D01*
G03X1675856Y1512678I-200J0D01*
G02Y1515590I1664J1456D01*
G03X1675906Y1515722I-150J132D01*
G01Y1516344D01*
G02X1676109Y1516546I203J-1D01*
G01X1678930D01*
G02X1679132Y1516344I0J-202D01*
G01Y1515722D01*
G03X1679182Y1515590I200J0D01*
G02Y1512678I-1664J-1456D01*
G03X1679132Y1512546I150J-132D01*
G01Y1510604D01*
G03X1679182Y1510472I200J0D01*
G02Y1507560I-1664J-1456D01*
G03X1679132Y1507428I150J-132D01*
G01Y1506806D01*
G02X1678929Y1506604I-203J1D01*
G01X1676108D01*
G37*
G36*
G01X454929Y1568516D02*
X457749D01*
G02X457952Y1568313I0J-203D01*
G01Y1567691D01*
G03X458002Y1567559I200J0D01*
G02Y1564647I-1664J-1456D01*
G03X457952Y1564515I150J-132D01*
G01Y1562573D01*
G03X458002Y1562441I200J0D01*
G02Y1559529I-1664J-1456D01*
G03X457952Y1559397I150J-132D01*
G01Y1558775D01*
G02X457749Y1558572I-203J0D01*
G01X454929D01*
G02X454726Y1558775I0J203D01*
G01Y1559397D01*
G03X454676Y1559529I-200J0D01*
G02Y1562441I1664J1456D01*
G03X454726Y1562573I-150J132D01*
G01Y1564515D01*
G03X454676Y1564647I-200J0D01*
G02Y1567559I1664J1456D01*
G03X454726Y1567691I-150J132D01*
G01Y1568313D01*
G02X454929Y1568516I203J0D01*
G37*
G36*
G01X475274Y1558774D02*
G02X475072Y1558572I-202J0D01*
G01X472252D01*
G02X472050Y1558775I1J203D01*
G01Y1559395D01*
G03X472000Y1559527I-200J0D01*
G02Y1562443I1661J1458D01*
G03X472050Y1562575I-150J132D01*
G01Y1564513D01*
G03X472000Y1564645I-200J0D01*
G02Y1567561I1661J1458D01*
G03X472050Y1567693I-150J132D01*
G01Y1568314D01*
G02X472252Y1568516I202J0D01*
G01X475072D01*
G02X475274Y1568313I-1J-203D01*
G01Y1567693D01*
G03X475324Y1567561I200J0D01*
G02Y1564645I-1661J-1458D01*
G03X475274Y1564513I150J-132D01*
G01Y1562575D01*
G03X475324Y1562443I200J0D01*
G02Y1559527I-1661J-1458D01*
G03X475274Y1559395I150J-132D01*
G01Y1558774D01*
G37*
G36*
G01X489575Y1568516D02*
X492395D01*
G02X492598Y1568313I0J-203D01*
G01Y1567691D01*
G03X492648Y1567559I200J0D01*
G02Y1564647I-1664J-1456D01*
G03X492598Y1564515I150J-132D01*
G01Y1562573D01*
G03X492648Y1562441I200J0D01*
G02Y1559529I-1664J-1456D01*
G03X492598Y1559397I150J-132D01*
G01Y1558775D01*
G02X492395Y1558572I-203J0D01*
G01X489575D01*
G02X489372Y1558775I0J203D01*
G01Y1559397D01*
G03X489322Y1559529I-200J0D01*
G02Y1562441I1664J1456D01*
G03X489372Y1562573I-150J132D01*
G01Y1564515D01*
G03X489322Y1564647I-200J0D01*
G02Y1567559I1664J1456D01*
G03X489372Y1567691I-150J132D01*
G01Y1568313D01*
G02X489575Y1568516I203J0D01*
G37*
G36*
G01X506897D02*
X509717D01*
G02X509920Y1568313I0J-203D01*
G01Y1567691D01*
G03X509970Y1567559I200J0D01*
G02Y1564647I-1664J-1456D01*
G03X509920Y1564515I150J-132D01*
G01Y1562573D01*
G03X509970Y1562441I200J0D01*
G02Y1559529I-1664J-1456D01*
G03X509920Y1559397I150J-132D01*
G01Y1558775D01*
G02X509717Y1558572I-203J0D01*
G01X506897D01*
G02X506694Y1558775I0J203D01*
G01Y1559397D01*
G03X506644Y1559529I-200J0D01*
G02Y1562441I1664J1456D01*
G03X506694Y1562573I-150J132D01*
G01Y1564515D01*
G03X506644Y1564647I-200J0D01*
G02Y1567559I1664J1456D01*
G03X506694Y1567691I-150J132D01*
G01Y1568313D01*
G02X506897Y1568516I203J0D01*
G37*
G36*
G01X1497242Y1558774D02*
G02X1497040Y1558572I-202J0D01*
G01X1494220D01*
G02X1494018Y1558775I1J203D01*
G01Y1559395D01*
G03X1493968Y1559527I-200J0D01*
G02Y1562443I1661J1458D01*
G03X1494018Y1562575I-150J132D01*
G01Y1564513D01*
G03X1493968Y1564645I-200J0D01*
G02Y1567561I1661J1458D01*
G03X1494018Y1567693I-150J132D01*
G01Y1568314D01*
G02X1494220Y1568516I202J0D01*
G01X1497040D01*
G02X1497242Y1568313I-1J-203D01*
G01Y1567693D01*
G03X1497292Y1567561I200J0D01*
G02Y1564645I-1661J-1458D01*
G03X1497242Y1564513I150J-132D01*
G01Y1562575D01*
G03X1497292Y1562443I200J0D01*
G02Y1559527I-1661J-1458D01*
G03X1497242Y1559395I150J-132D01*
G01Y1558774D01*
G37*
G36*
G01X1511543Y1568516D02*
X1514363D01*
G02X1514566Y1568313I0J-203D01*
G01Y1567691D01*
G03X1514616Y1567559I200J0D01*
G02Y1564647I-1664J-1456D01*
G03X1514566Y1564515I150J-132D01*
G01Y1562573D01*
G03X1514616Y1562441I200J0D01*
G02Y1559529I-1664J-1456D01*
G03X1514566Y1559397I150J-132D01*
G01Y1558775D01*
G02X1514363Y1558572I-203J0D01*
G01X1511543D01*
G02X1511340Y1558775I0J203D01*
G01Y1559397D01*
G03X1511290Y1559529I-200J0D01*
G02Y1562441I1664J1456D01*
G03X1511340Y1562573I-150J132D01*
G01Y1564515D01*
G03X1511290Y1564647I-200J0D01*
G02Y1567559I1664J1456D01*
G03X1511340Y1567691I-150J132D01*
G01Y1568313D01*
G02X1511543Y1568516I203J0D01*
G37*
G36*
G01X1528865D02*
X1531685D01*
G02X1531888Y1568313I0J-203D01*
G01Y1567691D01*
G03X1531938Y1567559I200J0D01*
G02Y1564647I-1664J-1456D01*
G03X1531888Y1564515I150J-132D01*
G01Y1562573D01*
G03X1531938Y1562441I200J0D01*
G02Y1559529I-1664J-1456D01*
G03X1531888Y1559397I150J-132D01*
G01Y1558775D01*
G02X1531685Y1558572I-203J0D01*
G01X1528865D01*
G02X1528662Y1558775I0J203D01*
G01Y1559397D01*
G03X1528612Y1559529I-200J0D01*
G02Y1562441I1664J1456D01*
G03X1528662Y1562573I-150J132D01*
G01Y1564515D01*
G03X1528612Y1564647I-200J0D01*
G02Y1567559I1664J1456D01*
G03X1528662Y1567691I-150J132D01*
G01Y1568313D01*
G02X1528865Y1568516I203J0D01*
G37*
G36*
G01X463590Y1572846D02*
X466410D01*
G02X466612Y1572644I0J-202D01*
G01Y1572024D01*
G03X466662Y1571892I200J0D01*
G02Y1568976I-1661J-1458D01*
G03X466612Y1568844I150J-132D01*
G01Y1566905D01*
G03X466662Y1566773I200J0D01*
G02Y1563857I-1661J-1458D01*
G03X466612Y1563725I150J-132D01*
G01Y1563106D01*
G02X466410Y1562904I-202J0D01*
G01X463590D01*
G02X463388Y1563106I0J202D01*
G01Y1563725D01*
G03X463338Y1563857I-200J0D01*
G02Y1566773I1661J1458D01*
G03X463388Y1566905I-150J132D01*
G01Y1568844D01*
G03X463338Y1568976I-200J0D01*
G02Y1571892I1661J1458D01*
G03X463388Y1572024I-150J132D01*
G01Y1572644D01*
G02X463590Y1572846I202J0D01*
G37*
G36*
G01X498236D02*
X501056D01*
G02X501258Y1572644I0J-202D01*
G01Y1572024D01*
G03X501308Y1571892I200J0D01*
G02Y1568976I-1661J-1458D01*
G03X501258Y1568844I150J-132D01*
G01Y1566905D01*
G03X501308Y1566773I200J0D01*
G02Y1563857I-1661J-1458D01*
G03X501258Y1563725I150J-132D01*
G01Y1563106D01*
G02X501056Y1562904I-202J0D01*
G01X498236D01*
G02X498034Y1563106I0J202D01*
G01Y1563725D01*
G03X497984Y1563857I-200J0D01*
G02Y1566773I1661J1458D01*
G03X498034Y1566905I-150J132D01*
G01Y1568844D01*
G03X497984Y1568976I-200J0D01*
G02Y1571892I1661J1458D01*
G03X498034Y1572024I-150J132D01*
G01Y1572644D01*
G02X498236Y1572846I202J0D01*
G37*
G36*
G01X1485558D02*
X1488378D01*
G02X1488580Y1572644I0J-202D01*
G01Y1572024D01*
G03X1488630Y1571892I200J0D01*
G02Y1568976I-1661J-1458D01*
G03X1488580Y1568844I150J-132D01*
G01Y1566905D01*
G03X1488630Y1566773I200J0D01*
G02Y1563857I-1661J-1458D01*
G03X1488580Y1563725I150J-132D01*
G01Y1563106D01*
G02X1488378Y1562904I-202J0D01*
G01X1485558D01*
G02X1485356Y1563106I0J202D01*
G01Y1563725D01*
G03X1485306Y1563857I-200J0D01*
G02Y1566773I1661J1458D01*
G03X1485356Y1566905I-150J132D01*
G01Y1568844D01*
G03X1485306Y1568976I-200J0D01*
G02Y1571892I1661J1458D01*
G03X1485356Y1572024I-150J132D01*
G01Y1572644D01*
G02X1485558Y1572846I202J0D01*
G37*
G36*
G01X1520204D02*
X1523024D01*
G02X1523226Y1572644I0J-202D01*
G01Y1572024D01*
G03X1523276Y1571892I200J0D01*
G02Y1568976I-1661J-1458D01*
G03X1523226Y1568844I150J-132D01*
G01Y1566905D01*
G03X1523276Y1566773I200J0D01*
G02Y1563857I-1661J-1458D01*
G03X1523226Y1563725I150J-132D01*
G01Y1563106D01*
G02X1523024Y1562904I-202J0D01*
G01X1520204D01*
G02X1520002Y1563106I0J202D01*
G01Y1563725D01*
G03X1519952Y1563857I-200J0D01*
G02Y1566773I1661J1458D01*
G03X1520002Y1566905I-150J132D01*
G01Y1568844D01*
G03X1519952Y1568976I-200J0D01*
G02Y1571892I1661J1458D01*
G03X1520002Y1572024I-150J132D01*
G01Y1572644D01*
G02X1520204Y1572846I202J0D01*
G37*
G36*
G01X480912Y1562904D02*
G02X480710Y1563106I0J202D01*
G01Y1563727D01*
G03X480660Y1563859I-200J0D01*
G02Y1566771I1664J1456D01*
G03X480710Y1566903I-150J132D01*
G01Y1568846D01*
G03X480660Y1568978I-200J0D01*
G02Y1571890I1664J1456D01*
G03X480710Y1572022I-150J132D01*
G01Y1572644D01*
G02X480913Y1572846I203J-1D01*
G01X483734D01*
G02X483936Y1572644I0J-202D01*
G01Y1572022D01*
G03X483986Y1571890I200J0D01*
G02Y1568978I-1664J-1456D01*
G03X483936Y1568846I150J-132D01*
G01Y1566903D01*
G03X483986Y1566771I200J0D01*
G02Y1563859I-1664J-1456D01*
G03X483936Y1563727I150J-132D01*
G01Y1563106D01*
G02X483733Y1562904I-203J1D01*
G01X480912D01*
G37*
G36*
G01X1502880D02*
G02X1502678Y1563106I0J202D01*
G01Y1563727D01*
G03X1502628Y1563859I-200J0D01*
G02Y1566771I1664J1456D01*
G03X1502678Y1566903I-150J132D01*
G01Y1568846D01*
G03X1502628Y1568978I-200J0D01*
G02Y1571890I1664J1456D01*
G03X1502678Y1572022I-150J132D01*
G01Y1572644D01*
G02X1502881Y1572846I203J-1D01*
G01X1505702D01*
G02X1505904Y1572644I0J-202D01*
G01Y1572022D01*
G03X1505954Y1571890I200J0D01*
G02Y1568978I-1664J-1456D01*
G03X1505904Y1568846I150J-132D01*
G01Y1566903D01*
G03X1505954Y1566771I200J0D01*
G02Y1563859I-1664J-1456D01*
G03X1505904Y1563727I150J-132D01*
G01Y1563106D01*
G02X1505701Y1562904I-203J1D01*
G01X1502880D01*
G37*
G36*
G01X1537526D02*
G02X1537324Y1563106I0J202D01*
G01Y1563727D01*
G03X1537274Y1563859I-200J0D01*
G02Y1566771I1664J1456D01*
G03X1537324Y1566903I-150J132D01*
G01Y1568846D01*
G03X1537274Y1568978I-200J0D01*
G02Y1571890I1664J1456D01*
G03X1537324Y1572022I-150J132D01*
G01Y1572644D01*
G02X1537527Y1572846I203J-1D01*
G01X1540348D01*
G02X1540550Y1572644I0J-202D01*
G01Y1572022D01*
G03X1540600Y1571890I200J0D01*
G02Y1568978I-1664J-1456D01*
G03X1540550Y1568846I150J-132D01*
G01Y1566903D01*
G03X1540600Y1566771I200J0D01*
G02Y1563859I-1664J-1456D01*
G03X1540550Y1563727I150J-132D01*
G01Y1563106D01*
G02X1540347Y1562904I-203J1D01*
G01X1537526D01*
G37*
G36*
G01X454929Y1583870D02*
X457749D01*
G02X457952Y1583667I0J-203D01*
G01Y1583045D01*
G03X458002Y1582913I200J0D01*
G02Y1580001I-1664J-1456D01*
G03X457952Y1579869I150J-132D01*
G01Y1577927D01*
G03X458002Y1577795I200J0D01*
G02Y1574883I-1664J-1456D01*
G03X457952Y1574751I150J-132D01*
G01Y1574129D01*
G02X457749Y1573926I-203J0D01*
G01X454929D01*
G02X454726Y1574129I0J203D01*
G01Y1574751D01*
G03X454676Y1574883I-200J0D01*
G02Y1577795I1664J1456D01*
G03X454726Y1577927I-150J132D01*
G01Y1579869D01*
G03X454676Y1580001I-200J0D01*
G02Y1582913I1664J1456D01*
G03X454726Y1583045I-150J132D01*
G01Y1583667D01*
G02X454929Y1583870I203J0D01*
G37*
G36*
G01X475274Y1574128D02*
G02X475072Y1573926I-202J0D01*
G01X472252D01*
G02X472050Y1574129I1J203D01*
G01Y1574749D01*
G03X472000Y1574881I-200J0D01*
G02Y1577797I1661J1458D01*
G03X472050Y1577929I-150J132D01*
G01Y1579867D01*
G03X472000Y1579999I-200J0D01*
G02Y1582915I1661J1458D01*
G03X472050Y1583047I-150J132D01*
G01Y1583668D01*
G02X472252Y1583870I202J0D01*
G01X475072D01*
G02X475274Y1583667I-1J-203D01*
G01Y1583047D01*
G03X475324Y1582915I200J0D01*
G02Y1579999I-1661J-1458D01*
G03X475274Y1579867I150J-132D01*
G01Y1577929D01*
G03X475324Y1577797I200J0D01*
G02Y1574881I-1661J-1458D01*
G03X475274Y1574749I150J-132D01*
G01Y1574128D01*
G37*
G36*
G01X489575Y1583870D02*
X492395D01*
G02X492598Y1583667I0J-203D01*
G01Y1583045D01*
G03X492648Y1582913I200J0D01*
G02Y1580001I-1664J-1456D01*
G03X492598Y1579869I150J-132D01*
G01Y1577927D01*
G03X492648Y1577795I200J0D01*
G02Y1574883I-1664J-1456D01*
G03X492598Y1574751I150J-132D01*
G01Y1574129D01*
G02X492395Y1573926I-203J0D01*
G01X489575D01*
G02X489372Y1574129I0J203D01*
G01Y1574751D01*
G03X489322Y1574883I-200J0D01*
G02Y1577795I1664J1456D01*
G03X489372Y1577927I-150J132D01*
G01Y1579869D01*
G03X489322Y1580001I-200J0D01*
G02Y1582913I1664J1456D01*
G03X489372Y1583045I-150J132D01*
G01Y1583667D01*
G02X489575Y1583870I203J0D01*
G37*
G36*
G01X506897D02*
X509717D01*
G02X509920Y1583667I0J-203D01*
G01Y1583045D01*
G03X509970Y1582913I200J0D01*
G02Y1580001I-1664J-1456D01*
G03X509920Y1579869I150J-132D01*
G01Y1577927D01*
G03X509970Y1577795I200J0D01*
G02Y1574883I-1664J-1456D01*
G03X509920Y1574751I150J-132D01*
G01Y1574129D01*
G02X509717Y1573926I-203J0D01*
G01X506897D01*
G02X506694Y1574129I0J203D01*
G01Y1574751D01*
G03X506644Y1574883I-200J0D01*
G02Y1577795I1664J1456D01*
G03X506694Y1577927I-150J132D01*
G01Y1579869D01*
G03X506644Y1580001I-200J0D01*
G02Y1582913I1664J1456D01*
G03X506694Y1583045I-150J132D01*
G01Y1583667D01*
G02X506897Y1583870I203J0D01*
G37*
G36*
G01X1497242Y1574128D02*
G02X1497040Y1573926I-202J0D01*
G01X1494220D01*
G02X1494018Y1574129I1J203D01*
G01Y1574749D01*
G03X1493968Y1574881I-200J0D01*
G02Y1577797I1661J1458D01*
G03X1494018Y1577929I-150J132D01*
G01Y1579867D01*
G03X1493968Y1579999I-200J0D01*
G02Y1582915I1661J1458D01*
G03X1494018Y1583047I-150J132D01*
G01Y1583668D01*
G02X1494220Y1583870I202J0D01*
G01X1497040D01*
G02X1497242Y1583667I-1J-203D01*
G01Y1583047D01*
G03X1497292Y1582915I200J0D01*
G02Y1579999I-1661J-1458D01*
G03X1497242Y1579867I150J-132D01*
G01Y1577929D01*
G03X1497292Y1577797I200J0D01*
G02Y1574881I-1661J-1458D01*
G03X1497242Y1574749I150J-132D01*
G01Y1574128D01*
G37*
G36*
G01X1511543Y1583870D02*
X1514363D01*
G02X1514566Y1583667I0J-203D01*
G01Y1583045D01*
G03X1514616Y1582913I200J0D01*
G02Y1580001I-1664J-1456D01*
G03X1514566Y1579869I150J-132D01*
G01Y1577927D01*
G03X1514616Y1577795I200J0D01*
G02Y1574883I-1664J-1456D01*
G03X1514566Y1574751I150J-132D01*
G01Y1574129D01*
G02X1514363Y1573926I-203J0D01*
G01X1511543D01*
G02X1511340Y1574129I0J203D01*
G01Y1574751D01*
G03X1511290Y1574883I-200J0D01*
G02Y1577795I1664J1456D01*
G03X1511340Y1577927I-150J132D01*
G01Y1579869D01*
G03X1511290Y1580001I-200J0D01*
G02Y1582913I1664J1456D01*
G03X1511340Y1583045I-150J132D01*
G01Y1583667D01*
G02X1511543Y1583870I203J0D01*
G37*
G36*
G01X1528865D02*
X1531685D01*
G02X1531888Y1583667I0J-203D01*
G01Y1583045D01*
G03X1531938Y1582913I200J0D01*
G02Y1580001I-1664J-1456D01*
G03X1531888Y1579869I150J-132D01*
G01Y1577927D01*
G03X1531938Y1577795I200J0D01*
G02Y1574883I-1664J-1456D01*
G03X1531888Y1574751I150J-132D01*
G01Y1574129D01*
G02X1531685Y1573926I-203J0D01*
G01X1528865D01*
G02X1528662Y1574129I0J203D01*
G01Y1574751D01*
G03X1528612Y1574883I-200J0D01*
G02Y1577795I1664J1456D01*
G03X1528662Y1577927I-150J132D01*
G01Y1579869D01*
G03X1528612Y1580001I-200J0D01*
G02Y1582913I1664J1456D01*
G03X1528662Y1583045I-150J132D01*
G01Y1583667D01*
G02X1528865Y1583870I203J0D01*
G37*
G36*
G01X463590Y1588200D02*
X466410D01*
G02X466612Y1587998I0J-202D01*
G01Y1587378D01*
G03X466662Y1587246I200J0D01*
G02Y1584330I-1661J-1458D01*
G03X466612Y1584198I150J-132D01*
G01Y1582260D01*
G03X466662Y1582128I200J0D01*
G02Y1579212I-1661J-1458D01*
G03X466612Y1579080I150J-132D01*
G01Y1578460D01*
G02X466410Y1578258I-202J0D01*
G01X463590D01*
G02X463388Y1578460I0J202D01*
G01Y1579080D01*
G03X463338Y1579212I-200J0D01*
G02Y1582128I1661J1458D01*
G03X463388Y1582260I-150J132D01*
G01Y1584198D01*
G03X463338Y1584330I-200J0D01*
G02Y1587246I1661J1458D01*
G03X463388Y1587378I-150J132D01*
G01Y1587998D01*
G02X463590Y1588200I202J0D01*
G37*
G36*
G01X498236D02*
X501056D01*
G02X501258Y1587998I0J-202D01*
G01Y1587378D01*
G03X501308Y1587246I200J0D01*
G02Y1584330I-1661J-1458D01*
G03X501258Y1584198I150J-132D01*
G01Y1582260D01*
G03X501308Y1582128I200J0D01*
G02Y1579212I-1661J-1458D01*
G03X501258Y1579080I150J-132D01*
G01Y1578460D01*
G02X501056Y1578258I-202J0D01*
G01X498236D01*
G02X498034Y1578460I0J202D01*
G01Y1579080D01*
G03X497984Y1579212I-200J0D01*
G02Y1582128I1661J1458D01*
G03X498034Y1582260I-150J132D01*
G01Y1584198D01*
G03X497984Y1584330I-200J0D01*
G02Y1587246I1661J1458D01*
G03X498034Y1587378I-150J132D01*
G01Y1587998D01*
G02X498236Y1588200I202J0D01*
G37*
G36*
G01X1485558D02*
X1488378D01*
G02X1488580Y1587998I0J-202D01*
G01Y1587378D01*
G03X1488630Y1587246I200J0D01*
G02Y1584330I-1661J-1458D01*
G03X1488580Y1584198I150J-132D01*
G01Y1582260D01*
G03X1488630Y1582128I200J0D01*
G02Y1579212I-1661J-1458D01*
G03X1488580Y1579080I150J-132D01*
G01Y1578460D01*
G02X1488378Y1578258I-202J0D01*
G01X1485558D01*
G02X1485356Y1578460I0J202D01*
G01Y1579080D01*
G03X1485306Y1579212I-200J0D01*
G02Y1582128I1661J1458D01*
G03X1485356Y1582260I-150J132D01*
G01Y1584198D01*
G03X1485306Y1584330I-200J0D01*
G02Y1587246I1661J1458D01*
G03X1485356Y1587378I-150J132D01*
G01Y1587998D01*
G02X1485558Y1588200I202J0D01*
G37*
G36*
G01X1520204D02*
X1523024D01*
G02X1523226Y1587998I0J-202D01*
G01Y1587378D01*
G03X1523276Y1587246I200J0D01*
G02Y1584330I-1661J-1458D01*
G03X1523226Y1584198I150J-132D01*
G01Y1582260D01*
G03X1523276Y1582128I200J0D01*
G02Y1579212I-1661J-1458D01*
G03X1523226Y1579080I150J-132D01*
G01Y1578460D01*
G02X1523024Y1578258I-202J0D01*
G01X1520204D01*
G02X1520002Y1578460I0J202D01*
G01Y1579080D01*
G03X1519952Y1579212I-200J0D01*
G02Y1582128I1661J1458D01*
G03X1520002Y1582260I-150J132D01*
G01Y1584198D01*
G03X1519952Y1584330I-200J0D01*
G02Y1587246I1661J1458D01*
G03X1520002Y1587378I-150J132D01*
G01Y1587998D01*
G02X1520204Y1588200I202J0D01*
G37*
G36*
G01X480912Y1578258D02*
G02X480710Y1578460I0J202D01*
G01Y1579082D01*
G03X480660Y1579214I-200J0D01*
G02Y1582126I1664J1456D01*
G03X480710Y1582258I-150J132D01*
G01Y1584200D01*
G03X480660Y1584332I-200J0D01*
G02Y1587244I1664J1456D01*
G03X480710Y1587376I-150J132D01*
G01Y1587998D01*
G02X480913Y1588200I203J-1D01*
G01X483734D01*
G02X483936Y1587998I0J-202D01*
G01Y1587376D01*
G03X483986Y1587244I200J0D01*
G02Y1584332I-1664J-1456D01*
G03X483936Y1584200I150J-132D01*
G01Y1582258D01*
G03X483986Y1582126I200J0D01*
G02Y1579214I-1664J-1456D01*
G03X483936Y1579082I150J-132D01*
G01Y1578460D01*
G02X483733Y1578258I-203J1D01*
G01X480912D01*
G37*
G36*
G01X1502880D02*
G02X1502678Y1578460I0J202D01*
G01Y1579082D01*
G03X1502628Y1579214I-200J0D01*
G02Y1582126I1664J1456D01*
G03X1502678Y1582258I-150J132D01*
G01Y1584200D01*
G03X1502628Y1584332I-200J0D01*
G02Y1587244I1664J1456D01*
G03X1502678Y1587376I-150J132D01*
G01Y1587998D01*
G02X1502881Y1588200I203J-1D01*
G01X1505702D01*
G02X1505904Y1587998I0J-202D01*
G01Y1587376D01*
G03X1505954Y1587244I200J0D01*
G02Y1584332I-1664J-1456D01*
G03X1505904Y1584200I150J-132D01*
G01Y1582258D01*
G03X1505954Y1582126I200J0D01*
G02Y1579214I-1664J-1456D01*
G03X1505904Y1579082I150J-132D01*
G01Y1578460D01*
G02X1505701Y1578258I-203J1D01*
G01X1502880D01*
G37*
G36*
G01X1537526D02*
G02X1537324Y1578460I0J202D01*
G01Y1579082D01*
G03X1537274Y1579214I-200J0D01*
G02Y1582126I1664J1456D01*
G03X1537324Y1582258I-150J132D01*
G01Y1584200D01*
G03X1537274Y1584332I-200J0D01*
G02Y1587244I1664J1456D01*
G03X1537324Y1587376I-150J132D01*
G01Y1587998D01*
G02X1537527Y1588200I203J-1D01*
G01X1540348D01*
G02X1540550Y1587998I0J-202D01*
G01Y1587376D01*
G03X1540600Y1587244I200J0D01*
G02Y1584332I-1664J-1456D01*
G03X1540550Y1584200I150J-132D01*
G01Y1582258D01*
G03X1540600Y1582126I200J0D01*
G02Y1579214I-1664J-1456D01*
G03X1540550Y1579082I150J-132D01*
G01Y1578460D01*
G02X1540347Y1578258I-203J1D01*
G01X1537526D01*
G37*
G36*
G01X454929Y1599224D02*
X457749D01*
G02X457952Y1599021I0J-203D01*
G01Y1598399D01*
G03X458002Y1598267I200J0D01*
G02Y1595355I-1664J-1456D01*
G03X457952Y1595223I150J-132D01*
G01Y1593281D01*
G03X458002Y1593149I200J0D01*
G02Y1590237I-1664J-1456D01*
G03X457952Y1590105I150J-132D01*
G01Y1589483D01*
G02X457749Y1589280I-203J0D01*
G01X454929D01*
G02X454726Y1589483I0J203D01*
G01Y1590105D01*
G03X454676Y1590237I-200J0D01*
G02Y1593149I1664J1456D01*
G03X454726Y1593281I-150J132D01*
G01Y1595223D01*
G03X454676Y1595355I-200J0D01*
G02Y1598267I1664J1456D01*
G03X454726Y1598399I-150J132D01*
G01Y1599021D01*
G02X454929Y1599224I203J0D01*
G37*
G36*
G01X475274Y1589482D02*
G02X475072Y1589280I-202J0D01*
G01X472252D01*
G02X472050Y1589483I1J203D01*
G01Y1590103D01*
G03X472000Y1590235I-200J0D01*
G02Y1593151I1661J1458D01*
G03X472050Y1593283I-150J132D01*
G01Y1595221D01*
G03X472000Y1595353I-200J0D01*
G02Y1598269I1661J1458D01*
G03X472050Y1598401I-150J132D01*
G01Y1599022D01*
G02X472252Y1599224I202J0D01*
G01X475072D01*
G02X475274Y1599021I-1J-203D01*
G01Y1598401D01*
G03X475324Y1598269I200J0D01*
G02Y1595353I-1661J-1458D01*
G03X475274Y1595221I150J-132D01*
G01Y1593283D01*
G03X475324Y1593151I200J0D01*
G02Y1590235I-1661J-1458D01*
G03X475274Y1590103I150J-132D01*
G01Y1589482D01*
G37*
G36*
G01X489575Y1599224D02*
X492395D01*
G02X492598Y1599021I0J-203D01*
G01Y1598399D01*
G03X492648Y1598267I200J0D01*
G02Y1595355I-1664J-1456D01*
G03X492598Y1595223I150J-132D01*
G01Y1593281D01*
G03X492648Y1593149I200J0D01*
G02Y1590237I-1664J-1456D01*
G03X492598Y1590105I150J-132D01*
G01Y1589483D01*
G02X492395Y1589280I-203J0D01*
G01X489575D01*
G02X489372Y1589483I0J203D01*
G01Y1590105D01*
G03X489322Y1590237I-200J0D01*
G02Y1593149I1664J1456D01*
G03X489372Y1593281I-150J132D01*
G01Y1595223D01*
G03X489322Y1595355I-200J0D01*
G02Y1598267I1664J1456D01*
G03X489372Y1598399I-150J132D01*
G01Y1599021D01*
G02X489575Y1599224I203J0D01*
G37*
G36*
G01X506897D02*
X509717D01*
G02X509920Y1599021I0J-203D01*
G01Y1598399D01*
G03X509970Y1598267I200J0D01*
G02Y1595355I-1664J-1456D01*
G03X509920Y1595223I150J-132D01*
G01Y1593281D01*
G03X509970Y1593149I200J0D01*
G02Y1590237I-1664J-1456D01*
G03X509920Y1590105I150J-132D01*
G01Y1589483D01*
G02X509717Y1589280I-203J0D01*
G01X506897D01*
G02X506694Y1589483I0J203D01*
G01Y1590105D01*
G03X506644Y1590237I-200J0D01*
G02Y1593149I1664J1456D01*
G03X506694Y1593281I-150J132D01*
G01Y1595223D01*
G03X506644Y1595355I-200J0D01*
G02Y1598267I1664J1456D01*
G03X506694Y1598399I-150J132D01*
G01Y1599021D01*
G02X506897Y1599224I203J0D01*
G37*
G36*
G01X1497242Y1589482D02*
G02X1497040Y1589280I-202J0D01*
G01X1494220D01*
G02X1494018Y1589483I1J203D01*
G01Y1590103D01*
G03X1493968Y1590235I-200J0D01*
G02Y1593151I1661J1458D01*
G03X1494018Y1593283I-150J132D01*
G01Y1595221D01*
G03X1493968Y1595353I-200J0D01*
G02Y1598269I1661J1458D01*
G03X1494018Y1598401I-150J132D01*
G01Y1599022D01*
G02X1494220Y1599224I202J0D01*
G01X1497040D01*
G02X1497242Y1599021I-1J-203D01*
G01Y1598401D01*
G03X1497292Y1598269I200J0D01*
G02Y1595353I-1661J-1458D01*
G03X1497242Y1595221I150J-132D01*
G01Y1593283D01*
G03X1497292Y1593151I200J0D01*
G02Y1590235I-1661J-1458D01*
G03X1497242Y1590103I150J-132D01*
G01Y1589482D01*
G37*
G36*
G01X1511543Y1599224D02*
X1514363D01*
G02X1514566Y1599021I0J-203D01*
G01Y1598399D01*
G03X1514616Y1598267I200J0D01*
G02Y1595355I-1664J-1456D01*
G03X1514566Y1595223I150J-132D01*
G01Y1593281D01*
G03X1514616Y1593149I200J0D01*
G02Y1590237I-1664J-1456D01*
G03X1514566Y1590105I150J-132D01*
G01Y1589483D01*
G02X1514363Y1589280I-203J0D01*
G01X1511543D01*
G02X1511340Y1589483I0J203D01*
G01Y1590105D01*
G03X1511290Y1590237I-200J0D01*
G02Y1593149I1664J1456D01*
G03X1511340Y1593281I-150J132D01*
G01Y1595223D01*
G03X1511290Y1595355I-200J0D01*
G02Y1598267I1664J1456D01*
G03X1511340Y1598399I-150J132D01*
G01Y1599021D01*
G02X1511543Y1599224I203J0D01*
G37*
G36*
G01X1528865D02*
X1531685D01*
G02X1531888Y1599021I0J-203D01*
G01Y1598399D01*
G03X1531938Y1598267I200J0D01*
G02Y1595355I-1664J-1456D01*
G03X1531888Y1595223I150J-132D01*
G01Y1593281D01*
G03X1531938Y1593149I200J0D01*
G02Y1590237I-1664J-1456D01*
G03X1531888Y1590105I150J-132D01*
G01Y1589483D01*
G02X1531685Y1589280I-203J0D01*
G01X1528865D01*
G02X1528662Y1589483I0J203D01*
G01Y1590105D01*
G03X1528612Y1590237I-200J0D01*
G02Y1593149I1664J1456D01*
G03X1528662Y1593281I-150J132D01*
G01Y1595223D01*
G03X1528612Y1595355I-200J0D01*
G02Y1598267I1664J1456D01*
G03X1528662Y1598399I-150J132D01*
G01Y1599021D01*
G02X1528865Y1599224I203J0D01*
G37*
G36*
G01X463590Y1603554D02*
X466410D01*
G02X466612Y1603352I0J-202D01*
G01Y1602732D01*
G03X466662Y1602600I200J0D01*
G02Y1599684I-1661J-1458D01*
G03X466612Y1599552I150J-132D01*
G01Y1597614D01*
G03X466662Y1597482I200J0D01*
G02Y1594566I-1661J-1458D01*
G03X466612Y1594434I150J-132D01*
G01Y1593814D01*
G02X466410Y1593612I-202J0D01*
G01X463590D01*
G02X463388Y1593814I0J202D01*
G01Y1594434D01*
G03X463338Y1594566I-200J0D01*
G02Y1597482I1661J1458D01*
G03X463388Y1597614I-150J132D01*
G01Y1599552D01*
G03X463338Y1599684I-200J0D01*
G02Y1602600I1661J1458D01*
G03X463388Y1602732I-150J132D01*
G01Y1603352D01*
G02X463590Y1603554I202J0D01*
G37*
G36*
G01X498236D02*
X501056D01*
G02X501258Y1603352I0J-202D01*
G01Y1602732D01*
G03X501308Y1602600I200J0D01*
G02Y1599684I-1661J-1458D01*
G03X501258Y1599552I150J-132D01*
G01Y1597614D01*
G03X501308Y1597482I200J0D01*
G02Y1594566I-1661J-1458D01*
G03X501258Y1594434I150J-132D01*
G01Y1593814D01*
G02X501056Y1593612I-202J0D01*
G01X498236D01*
G02X498034Y1593814I0J202D01*
G01Y1594434D01*
G03X497984Y1594566I-200J0D01*
G02Y1597482I1661J1458D01*
G03X498034Y1597614I-150J132D01*
G01Y1599552D01*
G03X497984Y1599684I-200J0D01*
G02Y1602600I1661J1458D01*
G03X498034Y1602732I-150J132D01*
G01Y1603352D01*
G02X498236Y1603554I202J0D01*
G37*
G36*
G01X1485558D02*
X1488378D01*
G02X1488580Y1603352I0J-202D01*
G01Y1602732D01*
G03X1488630Y1602600I200J0D01*
G02Y1599684I-1661J-1458D01*
G03X1488580Y1599552I150J-132D01*
G01Y1597614D01*
G03X1488630Y1597482I200J0D01*
G02Y1594566I-1661J-1458D01*
G03X1488580Y1594434I150J-132D01*
G01Y1593814D01*
G02X1488378Y1593612I-202J0D01*
G01X1485558D01*
G02X1485356Y1593814I0J202D01*
G01Y1594434D01*
G03X1485306Y1594566I-200J0D01*
G02Y1597482I1661J1458D01*
G03X1485356Y1597614I-150J132D01*
G01Y1599552D01*
G03X1485306Y1599684I-200J0D01*
G02Y1602600I1661J1458D01*
G03X1485356Y1602732I-150J132D01*
G01Y1603352D01*
G02X1485558Y1603554I202J0D01*
G37*
G36*
G01X1520204D02*
X1523024D01*
G02X1523226Y1603352I0J-202D01*
G01Y1602732D01*
G03X1523276Y1602600I200J0D01*
G02Y1599684I-1661J-1458D01*
G03X1523226Y1599552I150J-132D01*
G01Y1597614D01*
G03X1523276Y1597482I200J0D01*
G02Y1594566I-1661J-1458D01*
G03X1523226Y1594434I150J-132D01*
G01Y1593814D01*
G02X1523024Y1593612I-202J0D01*
G01X1520204D01*
G02X1520002Y1593814I0J202D01*
G01Y1594434D01*
G03X1519952Y1594566I-200J0D01*
G02Y1597482I1661J1458D01*
G03X1520002Y1597614I-150J132D01*
G01Y1599552D01*
G03X1519952Y1599684I-200J0D01*
G02Y1602600I1661J1458D01*
G03X1520002Y1602732I-150J132D01*
G01Y1603352D01*
G02X1520204Y1603554I202J0D01*
G37*
G36*
G01X480912Y1593612D02*
G02X480710Y1593814I0J202D01*
G01Y1594436D01*
G03X480660Y1594568I-200J0D01*
G02Y1597480I1664J1456D01*
G03X480710Y1597612I-150J132D01*
G01Y1599554D01*
G03X480660Y1599686I-200J0D01*
G02Y1602598I1664J1456D01*
G03X480710Y1602730I-150J132D01*
G01Y1603352D01*
G02X480913Y1603554I203J-1D01*
G01X483734D01*
G02X483936Y1603352I0J-202D01*
G01Y1602730D01*
G03X483986Y1602598I200J0D01*
G02Y1599686I-1664J-1456D01*
G03X483936Y1599554I150J-132D01*
G01Y1597612D01*
G03X483986Y1597480I200J0D01*
G02Y1594568I-1664J-1456D01*
G03X483936Y1594436I150J-132D01*
G01Y1593814D01*
G02X483733Y1593612I-203J1D01*
G01X480912D01*
G37*
G36*
G01X1502880D02*
G02X1502678Y1593814I0J202D01*
G01Y1594436D01*
G03X1502628Y1594568I-200J0D01*
G02Y1597480I1664J1456D01*
G03X1502678Y1597612I-150J132D01*
G01Y1599554D01*
G03X1502628Y1599686I-200J0D01*
G02Y1602598I1664J1456D01*
G03X1502678Y1602730I-150J132D01*
G01Y1603352D01*
G02X1502881Y1603554I203J-1D01*
G01X1505702D01*
G02X1505904Y1603352I0J-202D01*
G01Y1602730D01*
G03X1505954Y1602598I200J0D01*
G02Y1599686I-1664J-1456D01*
G03X1505904Y1599554I150J-132D01*
G01Y1597612D01*
G03X1505954Y1597480I200J0D01*
G02Y1594568I-1664J-1456D01*
G03X1505904Y1594436I150J-132D01*
G01Y1593814D01*
G02X1505701Y1593612I-203J1D01*
G01X1502880D01*
G37*
G36*
G01X1537526D02*
G02X1537324Y1593814I0J202D01*
G01Y1594436D01*
G03X1537274Y1594568I-200J0D01*
G02Y1597480I1664J1456D01*
G03X1537324Y1597612I-150J132D01*
G01Y1599554D01*
G03X1537274Y1599686I-200J0D01*
G02Y1602598I1664J1456D01*
G03X1537324Y1602730I-150J132D01*
G01Y1603352D01*
G02X1537527Y1603554I203J-1D01*
G01X1540348D01*
G02X1540550Y1603352I0J-202D01*
G01Y1602730D01*
G03X1540600Y1602598I200J0D01*
G02Y1599686I-1664J-1456D01*
G03X1540550Y1599554I150J-132D01*
G01Y1597612D01*
G03X1540600Y1597480I200J0D01*
G02Y1594568I-1664J-1456D01*
G03X1540550Y1594436I150J-132D01*
G01Y1593814D01*
G02X1540347Y1593612I-203J1D01*
G01X1537526D01*
G37*
G36*
G01X472252Y1614578D02*
X475072D01*
G02X475274Y1614376I0J-202D01*
G01Y1613756D01*
G03X475324Y1613624I200J0D01*
G02Y1610708I-1661J-1458D01*
G03X475274Y1610576I150J-132D01*
G01Y1608638D01*
G03X475324Y1608506I200J0D01*
G02Y1605590I-1661J-1458D01*
G03X475274Y1605458I150J-132D01*
G01Y1604838D01*
G02X475072Y1604636I-202J0D01*
G01X472252D01*
G02X472050Y1604838I0J202D01*
G01Y1605458D01*
G03X472000Y1605590I-200J0D01*
G02Y1608506I1661J1458D01*
G03X472050Y1608638I-150J132D01*
G01Y1610576D01*
G03X472000Y1610708I-200J0D01*
G02Y1613624I1661J1458D01*
G03X472050Y1613756I-150J132D01*
G01Y1614376D01*
G02X472252Y1614578I202J0D01*
G37*
G36*
G01X1494220D02*
X1497040D01*
G02X1497242Y1614376I0J-202D01*
G01Y1613756D01*
G03X1497292Y1613624I200J0D01*
G02Y1610708I-1661J-1458D01*
G03X1497242Y1610576I150J-132D01*
G01Y1608638D01*
G03X1497292Y1608506I200J0D01*
G02Y1605590I-1661J-1458D01*
G03X1497242Y1605458I150J-132D01*
G01Y1604838D01*
G02X1497040Y1604636I-202J0D01*
G01X1494220D01*
G02X1494018Y1604838I0J202D01*
G01Y1605458D01*
G03X1493968Y1605590I-200J0D01*
G02Y1608506I1661J1458D01*
G03X1494018Y1608638I-150J132D01*
G01Y1610576D01*
G03X1493968Y1610708I-200J0D01*
G02Y1613624I1661J1458D01*
G03X1494018Y1613756I-150J132D01*
G01Y1614376D01*
G02X1494220Y1614578I202J0D01*
G37*
G36*
G01X454928Y1604636D02*
G02X454726Y1604838I0J202D01*
G01Y1605460D01*
G03X454676Y1605592I-200J0D01*
G02Y1608504I1664J1456D01*
G03X454726Y1608636I-150J132D01*
G01Y1610578D01*
G03X454676Y1610710I-200J0D01*
G02Y1613622I1664J1456D01*
G03X454726Y1613754I-150J132D01*
G01Y1614376D01*
G02X454929Y1614578I203J-1D01*
G01X457750D01*
G02X457952Y1614376I0J-202D01*
G01Y1613754D01*
G03X458002Y1613622I200J0D01*
G02Y1610710I-1664J-1456D01*
G03X457952Y1610578I150J-132D01*
G01Y1608636D01*
G03X458002Y1608504I200J0D01*
G02Y1605592I-1664J-1456D01*
G03X457952Y1605460I150J-132D01*
G01Y1604838D01*
G02X457749Y1604636I-203J1D01*
G01X454928D01*
G37*
G36*
G01X489574D02*
G02X489372Y1604838I0J202D01*
G01Y1605460D01*
G03X489322Y1605592I-200J0D01*
G02Y1608504I1664J1456D01*
G03X489372Y1608636I-150J132D01*
G01Y1610578D01*
G03X489322Y1610710I-200J0D01*
G02Y1613622I1664J1456D01*
G03X489372Y1613754I-150J132D01*
G01Y1614376D01*
G02X489575Y1614578I203J-1D01*
G01X492396D01*
G02X492598Y1614376I0J-202D01*
G01Y1613754D01*
G03X492648Y1613622I200J0D01*
G02Y1610710I-1664J-1456D01*
G03X492598Y1610578I150J-132D01*
G01Y1608636D01*
G03X492648Y1608504I200J0D01*
G02Y1605592I-1664J-1456D01*
G03X492598Y1605460I150J-132D01*
G01Y1604838D01*
G02X492395Y1604636I-203J1D01*
G01X489574D01*
G37*
G36*
G01X506896D02*
G02X506694Y1604838I0J202D01*
G01Y1605460D01*
G03X506644Y1605592I-200J0D01*
G02Y1608504I1664J1456D01*
G03X506694Y1608636I-150J132D01*
G01Y1610578D01*
G03X506644Y1610710I-200J0D01*
G02Y1613622I1664J1456D01*
G03X506694Y1613754I-150J132D01*
G01Y1614376D01*
G02X506897Y1614578I203J-1D01*
G01X509718D01*
G02X509920Y1614376I0J-202D01*
G01Y1613754D01*
G03X509970Y1613622I200J0D01*
G02Y1610710I-1664J-1456D01*
G03X509920Y1610578I150J-132D01*
G01Y1608636D01*
G03X509970Y1608504I200J0D01*
G02Y1605592I-1664J-1456D01*
G03X509920Y1605460I150J-132D01*
G01Y1604838D01*
G02X509717Y1604636I-203J1D01*
G01X506896D01*
G37*
G36*
G01X1511542D02*
G02X1511340Y1604838I0J202D01*
G01Y1605460D01*
G03X1511290Y1605592I-200J0D01*
G02Y1608504I1664J1456D01*
G03X1511340Y1608636I-150J132D01*
G01Y1610578D01*
G03X1511290Y1610710I-200J0D01*
G02Y1613622I1664J1456D01*
G03X1511340Y1613754I-150J132D01*
G01Y1614376D01*
G02X1511543Y1614578I203J-1D01*
G01X1514364D01*
G02X1514566Y1614376I0J-202D01*
G01Y1613754D01*
G03X1514616Y1613622I200J0D01*
G02Y1610710I-1664J-1456D01*
G03X1514566Y1610578I150J-132D01*
G01Y1608636D01*
G03X1514616Y1608504I200J0D01*
G02Y1605592I-1664J-1456D01*
G03X1514566Y1605460I150J-132D01*
G01Y1604838D01*
G02X1514363Y1604636I-203J1D01*
G01X1511542D01*
G37*
G36*
G01X1528864D02*
G02X1528662Y1604838I0J202D01*
G01Y1605460D01*
G03X1528612Y1605592I-200J0D01*
G02Y1608504I1664J1456D01*
G03X1528662Y1608636I-150J132D01*
G01Y1610578D01*
G03X1528612Y1610710I-200J0D01*
G02Y1613622I1664J1456D01*
G03X1528662Y1613754I-150J132D01*
G01Y1614376D01*
G02X1528865Y1614578I203J-1D01*
G01X1531686D01*
G02X1531888Y1614376I0J-202D01*
G01Y1613754D01*
G03X1531938Y1613622I200J0D01*
G02Y1610710I-1664J-1456D01*
G03X1531888Y1610578I150J-132D01*
G01Y1608636D01*
G03X1531938Y1608504I200J0D01*
G02Y1605592I-1664J-1456D01*
G03X1531888Y1605460I150J-132D01*
G01Y1604838D01*
G02X1531685Y1604636I-203J1D01*
G01X1528864D01*
G37*
G36*
G01X463590Y1618908D02*
X466410D01*
G02X466612Y1618706I0J-202D01*
G01Y1618086D01*
G03X466662Y1617954I200J0D01*
G02Y1615038I-1661J-1458D01*
G03X466612Y1614906I150J-132D01*
G01Y1612968D01*
G03X466662Y1612836I200J0D01*
G02Y1609920I-1661J-1458D01*
G03X466612Y1609788I150J-132D01*
G01Y1609168D01*
G02X466410Y1608966I-202J0D01*
G01X463590D01*
G02X463388Y1609168I0J202D01*
G01Y1609788D01*
G03X463338Y1609920I-200J0D01*
G02Y1612836I1661J1458D01*
G03X463388Y1612968I-150J132D01*
G01Y1614906D01*
G03X463338Y1615038I-200J0D01*
G02Y1617954I1661J1458D01*
G03X463388Y1618086I-150J132D01*
G01Y1618706D01*
G02X463590Y1618908I202J0D01*
G37*
G36*
G01X498236D02*
X501056D01*
G02X501258Y1618706I0J-202D01*
G01Y1618086D01*
G03X501308Y1617954I200J0D01*
G02Y1615038I-1661J-1458D01*
G03X501258Y1614906I150J-132D01*
G01Y1612968D01*
G03X501308Y1612836I200J0D01*
G02Y1609920I-1661J-1458D01*
G03X501258Y1609788I150J-132D01*
G01Y1609168D01*
G02X501056Y1608966I-202J0D01*
G01X498236D01*
G02X498034Y1609168I0J202D01*
G01Y1609788D01*
G03X497984Y1609920I-200J0D01*
G02Y1612836I1661J1458D01*
G03X498034Y1612968I-150J132D01*
G01Y1614906D01*
G03X497984Y1615038I-200J0D01*
G02Y1617954I1661J1458D01*
G03X498034Y1618086I-150J132D01*
G01Y1618706D01*
G02X498236Y1618908I202J0D01*
G37*
G36*
G01X1485558D02*
X1488378D01*
G02X1488580Y1618706I0J-202D01*
G01Y1618086D01*
G03X1488630Y1617954I200J0D01*
G02Y1615038I-1661J-1458D01*
G03X1488580Y1614906I150J-132D01*
G01Y1612968D01*
G03X1488630Y1612836I200J0D01*
G02Y1609920I-1661J-1458D01*
G03X1488580Y1609788I150J-132D01*
G01Y1609168D01*
G02X1488378Y1608966I-202J0D01*
G01X1485558D01*
G02X1485356Y1609168I0J202D01*
G01Y1609788D01*
G03X1485306Y1609920I-200J0D01*
G02Y1612836I1661J1458D01*
G03X1485356Y1612968I-150J132D01*
G01Y1614906D01*
G03X1485306Y1615038I-200J0D01*
G02Y1617954I1661J1458D01*
G03X1485356Y1618086I-150J132D01*
G01Y1618706D01*
G02X1485558Y1618908I202J0D01*
G37*
G36*
G01X1520204D02*
X1523024D01*
G02X1523226Y1618706I0J-202D01*
G01Y1618086D01*
G03X1523276Y1617954I200J0D01*
G02Y1615038I-1661J-1458D01*
G03X1523226Y1614906I150J-132D01*
G01Y1612968D01*
G03X1523276Y1612836I200J0D01*
G02Y1609920I-1661J-1458D01*
G03X1523226Y1609788I150J-132D01*
G01Y1609168D01*
G02X1523024Y1608966I-202J0D01*
G01X1520204D01*
G02X1520002Y1609168I0J202D01*
G01Y1609788D01*
G03X1519952Y1609920I-200J0D01*
G02Y1612836I1661J1458D01*
G03X1520002Y1612968I-150J132D01*
G01Y1614906D01*
G03X1519952Y1615038I-200J0D01*
G02Y1617954I1661J1458D01*
G03X1520002Y1618086I-150J132D01*
G01Y1618706D01*
G02X1520204Y1618908I202J0D01*
G37*
G36*
G01X480912Y1608966D02*
G02X480710Y1609168I0J202D01*
G01Y1609790D01*
G03X480660Y1609922I-200J0D01*
G02Y1612834I1664J1456D01*
G03X480710Y1612966I-150J132D01*
G01Y1614908D01*
G03X480660Y1615040I-200J0D01*
G02Y1617952I1664J1456D01*
G03X480710Y1618084I-150J132D01*
G01Y1618706D01*
G02X480913Y1618908I203J-1D01*
G01X483734D01*
G02X483936Y1618706I0J-202D01*
G01Y1618084D01*
G03X483986Y1617952I200J0D01*
G02Y1615040I-1664J-1456D01*
G03X483936Y1614908I150J-132D01*
G01Y1612966D01*
G03X483986Y1612834I200J0D01*
G02Y1609922I-1664J-1456D01*
G03X483936Y1609790I150J-132D01*
G01Y1609168D01*
G02X483733Y1608966I-203J1D01*
G01X480912D01*
G37*
G36*
G01X1502880D02*
G02X1502678Y1609168I0J202D01*
G01Y1609790D01*
G03X1502628Y1609922I-200J0D01*
G02Y1612834I1664J1456D01*
G03X1502678Y1612966I-150J132D01*
G01Y1614908D01*
G03X1502628Y1615040I-200J0D01*
G02Y1617952I1664J1456D01*
G03X1502678Y1618084I-150J132D01*
G01Y1618706D01*
G02X1502881Y1618908I203J-1D01*
G01X1505702D01*
G02X1505904Y1618706I0J-202D01*
G01Y1618084D01*
G03X1505954Y1617952I200J0D01*
G02Y1615040I-1664J-1456D01*
G03X1505904Y1614908I150J-132D01*
G01Y1612966D01*
G03X1505954Y1612834I200J0D01*
G02Y1609922I-1664J-1456D01*
G03X1505904Y1609790I150J-132D01*
G01Y1609168D01*
G02X1505701Y1608966I-203J1D01*
G01X1502880D01*
G37*
G36*
G01X1537526D02*
G02X1537324Y1609168I0J202D01*
G01Y1609790D01*
G03X1537274Y1609922I-200J0D01*
G02Y1612834I1664J1456D01*
G03X1537324Y1612966I-150J132D01*
G01Y1614908D01*
G03X1537274Y1615040I-200J0D01*
G02Y1617952I1664J1456D01*
G03X1537324Y1618084I-150J132D01*
G01Y1618706D01*
G02X1537527Y1618908I203J-1D01*
G01X1540348D01*
G02X1540550Y1618706I0J-202D01*
G01Y1618084D01*
G03X1540600Y1617952I200J0D01*
G02Y1615040I-1664J-1456D01*
G03X1540550Y1614908I150J-132D01*
G01Y1612966D01*
G03X1540600Y1612834I200J0D01*
G02Y1609922I-1664J-1456D01*
G03X1540550Y1609790I150J-132D01*
G01Y1609168D01*
G02X1540347Y1608966I-203J1D01*
G01X1537526D01*
G37*
G36*
G01X125795Y1466154D02*
X128615D01*
G02X128818Y1465951I0J-203D01*
G01Y1465329D01*
G03X128868Y1465197I200J0D01*
G02Y1462285I-1664J-1456D01*
G03X128818Y1462153I150J-132D01*
G01Y1460210D01*
G03X128868Y1460078I200J0D01*
G02Y1457166I-1664J-1456D01*
G03X128818Y1457034I150J-132D01*
G01Y1456413D01*
G02X128615Y1456210I-203J0D01*
G01X125795D01*
G02X125592Y1456413I0J203D01*
G01Y1457034D01*
G03X125542Y1457166I-200J0D01*
G02Y1460078I1664J1456D01*
G03X125592Y1460210I-150J132D01*
G01Y1462153D01*
G03X125542Y1462285I-200J0D01*
G02Y1465197I1664J1456D01*
G03X125592Y1465329I-150J132D01*
G01Y1465951D01*
G02X125795Y1466154I203J0D01*
G37*
G36*
G01X143118D02*
X145938D01*
G02X146140Y1465951I-1J-203D01*
G01Y1465331D01*
G03X146190Y1465199I200J0D01*
G02Y1462283I-1661J-1458D01*
G03X146140Y1462151I150J-132D01*
G01Y1460212D01*
G03X146190Y1460080I200J0D01*
G02Y1457164I-1661J-1458D01*
G03X146140Y1457032I150J-132D01*
G01Y1456413D01*
G02X145938Y1456210I-202J-1D01*
G01X143118D01*
G02X142916Y1456413I1J203D01*
G01Y1457032D01*
G03X142866Y1457164I-200J0D01*
G02Y1460080I1661J1458D01*
G03X142916Y1460212I-150J132D01*
G01Y1462151D01*
G03X142866Y1462283I-200J0D01*
G02Y1465199I1661J1458D01*
G03X142916Y1465331I-150J132D01*
G01Y1465951D01*
G02X143118Y1466154I202J1D01*
G37*
G36*
G01X160440D02*
X163260D01*
G02X163462Y1465951I-1J-203D01*
G01Y1465331D01*
G03X163512Y1465199I200J0D01*
G02Y1462283I-1661J-1458D01*
G03X163462Y1462151I150J-132D01*
G01Y1460212D01*
G03X163512Y1460080I200J0D01*
G02Y1457164I-1661J-1458D01*
G03X163462Y1457032I150J-132D01*
G01Y1456413D01*
G02X163260Y1456210I-202J-1D01*
G01X160440D01*
G02X160238Y1456413I1J203D01*
G01Y1457032D01*
G03X160188Y1457164I-200J0D01*
G02Y1460080I1661J1458D01*
G03X160238Y1460212I-150J132D01*
G01Y1462151D01*
G03X160188Y1462283I-200J0D01*
G02Y1465199I1661J1458D01*
G03X160238Y1465331I-150J132D01*
G01Y1465951D01*
G02X160440Y1466154I202J1D01*
G37*
G36*
G01X177763D02*
X180583D01*
G02X180786Y1465951I0J-203D01*
G01Y1465329D01*
G03X180836Y1465197I200J0D01*
G02Y1462285I-1664J-1456D01*
G03X180786Y1462153I150J-132D01*
G01Y1460210D01*
G03X180836Y1460078I200J0D01*
G02Y1457166I-1664J-1456D01*
G03X180786Y1457034I150J-132D01*
G01Y1456413D01*
G02X180583Y1456210I-203J0D01*
G01X177763D01*
G02X177560Y1456413I0J203D01*
G01Y1457034D01*
G03X177510Y1457166I-200J0D01*
G02Y1460078I1664J1456D01*
G03X177560Y1460210I-150J132D01*
G01Y1462153D01*
G03X177510Y1462285I-200J0D01*
G02Y1465197I1664J1456D01*
G03X177560Y1465329I-150J132D01*
G01Y1465951D01*
G02X177763Y1466154I203J0D01*
G37*
G36*
G01X281700D02*
X284520D01*
G02X284722Y1465951I-1J-203D01*
G01Y1465331D01*
G03X284772Y1465199I200J0D01*
G02Y1462283I-1661J-1458D01*
G03X284722Y1462151I150J-132D01*
G01Y1460212D01*
G03X284772Y1460080I200J0D01*
G02Y1457164I-1661J-1458D01*
G03X284722Y1457032I150J-132D01*
G01Y1456413D01*
G02X284520Y1456210I-202J-1D01*
G01X281700D01*
G02X281498Y1456413I1J203D01*
G01Y1457032D01*
G03X281448Y1457164I-200J0D01*
G02Y1460080I1661J1458D01*
G03X281498Y1460212I-150J132D01*
G01Y1462151D01*
G03X281448Y1462283I-200J0D01*
G02Y1465199I1661J1458D01*
G03X281498Y1465331I-150J132D01*
G01Y1465951D01*
G02X281700Y1466154I202J1D01*
G37*
G36*
G01X299023D02*
X301843D01*
G02X302046Y1465951I0J-203D01*
G01Y1465329D01*
G03X302096Y1465197I200J0D01*
G02Y1462285I-1664J-1456D01*
G03X302046Y1462153I150J-132D01*
G01Y1460210D01*
G03X302096Y1460078I200J0D01*
G02Y1457166I-1664J-1456D01*
G03X302046Y1457034I150J-132D01*
G01Y1456413D01*
G02X301843Y1456210I-203J0D01*
G01X299023D01*
G02X298820Y1456413I0J203D01*
G01Y1457034D01*
G03X298770Y1457166I-200J0D01*
G02Y1460078I1664J1456D01*
G03X298820Y1460210I-150J132D01*
G01Y1462153D01*
G03X298770Y1462285I-200J0D01*
G02Y1465197I1664J1456D01*
G03X298820Y1465329I-150J132D01*
G01Y1465951D01*
G02X299023Y1466154I203J0D01*
G37*
G36*
G01X454929D02*
X457749D01*
G02X457952Y1465951I0J-203D01*
G01Y1465329D01*
G03X458002Y1465197I200J0D01*
G02Y1462285I-1664J-1456D01*
G03X457952Y1462153I150J-132D01*
G01Y1460210D01*
G03X458002Y1460078I200J0D01*
G02Y1457166I-1664J-1456D01*
G03X457952Y1457034I150J-132D01*
G01Y1456413D01*
G02X457749Y1456210I-203J0D01*
G01X454929D01*
G02X454726Y1456413I0J203D01*
G01Y1457034D01*
G03X454676Y1457166I-200J0D01*
G02Y1460078I1664J1456D01*
G03X454726Y1460210I-150J132D01*
G01Y1462153D01*
G03X454676Y1462285I-200J0D01*
G02Y1465197I1664J1456D01*
G03X454726Y1465329I-150J132D01*
G01Y1465951D01*
G02X454929Y1466154I203J0D01*
G37*
G36*
G01X472252D02*
X475072D01*
G02X475274Y1465951I-1J-203D01*
G01Y1465331D01*
G03X475324Y1465199I200J0D01*
G02Y1462283I-1661J-1458D01*
G03X475274Y1462151I150J-132D01*
G01Y1460212D01*
G03X475324Y1460080I200J0D01*
G02Y1457164I-1661J-1458D01*
G03X475274Y1457032I150J-132D01*
G01Y1456413D01*
G02X475072Y1456210I-202J-1D01*
G01X472252D01*
G02X472050Y1456413I1J203D01*
G01Y1457032D01*
G03X472000Y1457164I-200J0D01*
G02Y1460080I1661J1458D01*
G03X472050Y1460212I-150J132D01*
G01Y1462151D01*
G03X472000Y1462283I-200J0D01*
G02Y1465199I1661J1458D01*
G03X472050Y1465331I-150J132D01*
G01Y1465951D01*
G02X472252Y1466154I202J1D01*
G37*
G36*
G01X489575D02*
X492395D01*
G02X492598Y1465951I0J-203D01*
G01Y1465329D01*
G03X492648Y1465197I200J0D01*
G02Y1462285I-1664J-1456D01*
G03X492598Y1462153I150J-132D01*
G01Y1460210D01*
G03X492648Y1460078I200J0D01*
G02Y1457166I-1664J-1456D01*
G03X492598Y1457034I150J-132D01*
G01Y1456413D01*
G02X492395Y1456210I-203J0D01*
G01X489575D01*
G02X489372Y1456413I0J203D01*
G01Y1457034D01*
G03X489322Y1457166I-200J0D01*
G02Y1460078I1664J1456D01*
G03X489372Y1460210I-150J132D01*
G01Y1462153D01*
G03X489322Y1462285I-200J0D01*
G02Y1465197I1664J1456D01*
G03X489372Y1465329I-150J132D01*
G01Y1465951D01*
G02X489575Y1466154I203J0D01*
G37*
G36*
G01X506897D02*
X509717D01*
G02X509920Y1465951I0J-203D01*
G01Y1465329D01*
G03X509970Y1465197I200J0D01*
G02Y1462285I-1664J-1456D01*
G03X509920Y1462153I150J-132D01*
G01Y1460210D01*
G03X509970Y1460078I200J0D01*
G02Y1457166I-1664J-1456D01*
G03X509920Y1457034I150J-132D01*
G01Y1456413D01*
G02X509717Y1456210I-203J0D01*
G01X506897D01*
G02X506694Y1456413I0J203D01*
G01Y1457034D01*
G03X506644Y1457166I-200J0D01*
G02Y1460078I1664J1456D01*
G03X506694Y1460210I-150J132D01*
G01Y1462153D01*
G03X506644Y1462285I-200J0D01*
G02Y1465197I1664J1456D01*
G03X506694Y1465329I-150J132D01*
G01Y1465951D01*
G02X506897Y1466154I203J0D01*
G37*
G36*
G01X645480D02*
X648300D01*
G02X648502Y1465951I-1J-203D01*
G01Y1465331D01*
G03X648552Y1465199I200J0D01*
G02Y1462283I-1661J-1458D01*
G03X648502Y1462151I150J-132D01*
G01Y1460212D01*
G03X648552Y1460080I200J0D01*
G02Y1457164I-1661J-1458D01*
G03X648502Y1457032I150J-132D01*
G01Y1456413D01*
G02X648300Y1456210I-202J-1D01*
G01X645480D01*
G02X645278Y1456413I1J203D01*
G01Y1457032D01*
G03X645228Y1457164I-200J0D01*
G02Y1460080I1661J1458D01*
G03X645278Y1460212I-150J132D01*
G01Y1462151D01*
G03X645228Y1462283I-200J0D01*
G02Y1465199I1661J1458D01*
G03X645278Y1465331I-150J132D01*
G01Y1465951D01*
G02X645480Y1466154I202J1D01*
G37*
G36*
G01X662803D02*
X665623D01*
G02X665826Y1465951I0J-203D01*
G01Y1465329D01*
G03X665876Y1465197I200J0D01*
G02Y1462285I-1664J-1456D01*
G03X665826Y1462153I150J-132D01*
G01Y1460210D01*
G03X665876Y1460078I200J0D01*
G02Y1457166I-1664J-1456D01*
G03X665826Y1457034I150J-132D01*
G01Y1456413D01*
G02X665623Y1456210I-203J0D01*
G01X662803D01*
G02X662600Y1456413I0J203D01*
G01Y1457034D01*
G03X662550Y1457166I-200J0D01*
G02Y1460078I1664J1456D01*
G03X662600Y1460210I-150J132D01*
G01Y1462153D01*
G03X662550Y1462285I-200J0D01*
G02Y1465197I1664J1456D01*
G03X662600Y1465329I-150J132D01*
G01Y1465951D01*
G02X662803Y1466154I203J0D01*
G37*
G36*
G01X680125D02*
X682945D01*
G02X683148Y1465951I0J-203D01*
G01Y1465329D01*
G03X683198Y1465197I200J0D01*
G02Y1462285I-1664J-1456D01*
G03X683148Y1462153I150J-132D01*
G01Y1460210D01*
G03X683198Y1460078I200J0D01*
G02Y1457166I-1664J-1456D01*
G03X683148Y1457034I150J-132D01*
G01Y1456413D01*
G02X682945Y1456210I-203J0D01*
G01X680125D01*
G02X679922Y1456413I0J203D01*
G01Y1457034D01*
G03X679872Y1457166I-200J0D01*
G02Y1460078I1664J1456D01*
G03X679922Y1460210I-150J132D01*
G01Y1462153D01*
G03X679872Y1462285I-200J0D01*
G02Y1465197I1664J1456D01*
G03X679922Y1465329I-150J132D01*
G01Y1465951D01*
G02X680125Y1466154I203J0D01*
G37*
G36*
G01X1165086D02*
X1167906D01*
G02X1168108Y1465951I-1J-203D01*
G01Y1465331D01*
G03X1168158Y1465199I200J0D01*
G02Y1462283I-1661J-1458D01*
G03X1168108Y1462151I150J-132D01*
G01Y1460212D01*
G03X1168158Y1460080I200J0D01*
G02Y1457164I-1661J-1458D01*
G03X1168108Y1457032I150J-132D01*
G01Y1456413D01*
G02X1167906Y1456210I-202J-1D01*
G01X1165086D01*
G02X1164884Y1456413I1J203D01*
G01Y1457032D01*
G03X1164834Y1457164I-200J0D01*
G02Y1460080I1661J1458D01*
G03X1164884Y1460212I-150J132D01*
G01Y1462151D01*
G03X1164834Y1462283I-200J0D01*
G02Y1465199I1661J1458D01*
G03X1164884Y1465331I-150J132D01*
G01Y1465951D01*
G02X1165086Y1466154I202J1D01*
G37*
G36*
G01X1182408D02*
X1185228D01*
G02X1185430Y1465951I-1J-203D01*
G01Y1465331D01*
G03X1185480Y1465199I200J0D01*
G02Y1462283I-1661J-1458D01*
G03X1185430Y1462151I150J-132D01*
G01Y1460212D01*
G03X1185480Y1460080I200J0D01*
G02Y1457164I-1661J-1458D01*
G03X1185430Y1457032I150J-132D01*
G01Y1456413D01*
G02X1185228Y1456210I-202J-1D01*
G01X1182408D01*
G02X1182206Y1456413I1J203D01*
G01Y1457032D01*
G03X1182156Y1457164I-200J0D01*
G02Y1460080I1661J1458D01*
G03X1182206Y1460212I-150J132D01*
G01Y1462151D01*
G03X1182156Y1462283I-200J0D01*
G02Y1465199I1661J1458D01*
G03X1182206Y1465331I-150J132D01*
G01Y1465951D01*
G02X1182408Y1466154I202J1D01*
G37*
G36*
G01X1303669D02*
X1306489D01*
G02X1306692Y1465951I0J-203D01*
G01Y1465329D01*
G03X1306742Y1465197I200J0D01*
G02Y1462285I-1664J-1456D01*
G03X1306692Y1462153I150J-132D01*
G01Y1460210D01*
G03X1306742Y1460078I200J0D01*
G02Y1457166I-1664J-1456D01*
G03X1306692Y1457034I150J-132D01*
G01Y1456413D01*
G02X1306489Y1456210I-203J0D01*
G01X1303669D01*
G02X1303466Y1456413I0J203D01*
G01Y1457034D01*
G03X1303416Y1457166I-200J0D01*
G02Y1460078I1664J1456D01*
G03X1303466Y1460210I-150J132D01*
G01Y1462153D01*
G03X1303416Y1462285I-200J0D01*
G02Y1465197I1664J1456D01*
G03X1303466Y1465329I-150J132D01*
G01Y1465951D01*
G02X1303669Y1466154I203J0D01*
G37*
G36*
G01X1320992D02*
X1323812D01*
G02X1324014Y1465951I-1J-203D01*
G01Y1465331D01*
G03X1324064Y1465199I200J0D01*
G02Y1462283I-1661J-1458D01*
G03X1324014Y1462151I150J-132D01*
G01Y1460212D01*
G03X1324064Y1460080I200J0D01*
G02Y1457164I-1661J-1458D01*
G03X1324014Y1457032I150J-132D01*
G01Y1456413D01*
G02X1323812Y1456210I-202J-1D01*
G01X1320992D01*
G02X1320790Y1456413I1J203D01*
G01Y1457032D01*
G03X1320740Y1457164I-200J0D01*
G02Y1460080I1661J1458D01*
G03X1320790Y1460212I-150J132D01*
G01Y1462151D01*
G03X1320740Y1462283I-200J0D01*
G02Y1465199I1661J1458D01*
G03X1320790Y1465331I-150J132D01*
G01Y1465951D01*
G02X1320992Y1466154I202J1D01*
G37*
G36*
G01X1338315D02*
X1341135D01*
G02X1341338Y1465951I0J-203D01*
G01Y1465329D01*
G03X1341388Y1465197I200J0D01*
G02Y1462285I-1664J-1456D01*
G03X1341338Y1462153I150J-132D01*
G01Y1460210D01*
G03X1341388Y1460078I200J0D01*
G02Y1457166I-1664J-1456D01*
G03X1341338Y1457034I150J-132D01*
G01Y1456413D01*
G02X1341135Y1456210I-203J0D01*
G01X1338315D01*
G02X1338112Y1456413I0J203D01*
G01Y1457034D01*
G03X1338062Y1457166I-200J0D01*
G02Y1460078I1664J1456D01*
G03X1338112Y1460210I-150J132D01*
G01Y1462153D01*
G03X1338062Y1462285I-200J0D01*
G02Y1465197I1664J1456D01*
G03X1338112Y1465329I-150J132D01*
G01Y1465951D01*
G02X1338315Y1466154I203J0D01*
G37*
G36*
G01X1355637D02*
X1358457D01*
G02X1358660Y1465951I0J-203D01*
G01Y1465329D01*
G03X1358710Y1465197I200J0D01*
G02Y1462285I-1664J-1456D01*
G03X1358660Y1462153I150J-132D01*
G01Y1460210D01*
G03X1358710Y1460078I200J0D01*
G02Y1457166I-1664J-1456D01*
G03X1358660Y1457034I150J-132D01*
G01Y1456413D01*
G02X1358457Y1456210I-203J0D01*
G01X1355637D01*
G02X1355434Y1456413I0J203D01*
G01Y1457034D01*
G03X1355384Y1457166I-200J0D01*
G02Y1460078I1664J1456D01*
G03X1355434Y1460210I-150J132D01*
G01Y1462153D01*
G03X1355384Y1462285I-200J0D01*
G02Y1465197I1664J1456D01*
G03X1355434Y1465329I-150J132D01*
G01Y1465951D01*
G02X1355637Y1466154I203J0D01*
G37*
G36*
G01X1476897D02*
X1479717D01*
G02X1479920Y1465951I0J-203D01*
G01Y1465329D01*
G03X1479970Y1465197I200J0D01*
G02Y1462285I-1664J-1456D01*
G03X1479920Y1462153I150J-132D01*
G01Y1460210D01*
G03X1479970Y1460078I200J0D01*
G02Y1457166I-1664J-1456D01*
G03X1479920Y1457034I150J-132D01*
G01Y1456413D01*
G02X1479717Y1456210I-203J0D01*
G01X1476897D01*
G02X1476694Y1456413I0J203D01*
G01Y1457034D01*
G03X1476644Y1457166I-200J0D01*
G02Y1460078I1664J1456D01*
G03X1476694Y1460210I-150J132D01*
G01Y1462153D01*
G03X1476644Y1462285I-200J0D01*
G02Y1465197I1664J1456D01*
G03X1476694Y1465329I-150J132D01*
G01Y1465951D01*
G02X1476897Y1466154I203J0D01*
G37*
G36*
G01X1494220D02*
X1497040D01*
G02X1497242Y1465951I-1J-203D01*
G01Y1465331D01*
G03X1497292Y1465199I200J0D01*
G02Y1462283I-1661J-1458D01*
G03X1497242Y1462151I150J-132D01*
G01Y1460212D01*
G03X1497292Y1460080I200J0D01*
G02Y1457164I-1661J-1458D01*
G03X1497242Y1457032I150J-132D01*
G01Y1456413D01*
G02X1497040Y1456210I-202J-1D01*
G01X1494220D01*
G02X1494018Y1456413I1J203D01*
G01Y1457032D01*
G03X1493968Y1457164I-200J0D01*
G02Y1460080I1661J1458D01*
G03X1494018Y1460212I-150J132D01*
G01Y1462151D01*
G03X1493968Y1462283I-200J0D01*
G02Y1465199I1661J1458D01*
G03X1494018Y1465331I-150J132D01*
G01Y1465951D01*
G02X1494220Y1466154I202J1D01*
G37*
G36*
G01X1511543D02*
X1514363D01*
G02X1514566Y1465951I0J-203D01*
G01Y1465329D01*
G03X1514616Y1465197I200J0D01*
G02Y1462285I-1664J-1456D01*
G03X1514566Y1462153I150J-132D01*
G01Y1460210D01*
G03X1514616Y1460078I200J0D01*
G02Y1457166I-1664J-1456D01*
G03X1514566Y1457034I150J-132D01*
G01Y1456413D01*
G02X1514363Y1456210I-203J0D01*
G01X1511543D01*
G02X1511340Y1456413I0J203D01*
G01Y1457034D01*
G03X1511290Y1457166I-200J0D01*
G02Y1460078I1664J1456D01*
G03X1511340Y1460210I-150J132D01*
G01Y1462153D01*
G03X1511290Y1462285I-200J0D01*
G02Y1465197I1664J1456D01*
G03X1511340Y1465329I-150J132D01*
G01Y1465951D01*
G02X1511543Y1466154I203J0D01*
G37*
G36*
G01X1528865D02*
X1531685D01*
G02X1531888Y1465951I0J-203D01*
G01Y1465329D01*
G03X1531938Y1465197I200J0D01*
G02Y1462285I-1664J-1456D01*
G03X1531888Y1462153I150J-132D01*
G01Y1460210D01*
G03X1531938Y1460078I200J0D01*
G02Y1457166I-1664J-1456D01*
G03X1531888Y1457034I150J-132D01*
G01Y1456413D01*
G02X1531685Y1456210I-203J0D01*
G01X1528865D01*
G02X1528662Y1456413I0J203D01*
G01Y1457034D01*
G03X1528612Y1457166I-200J0D01*
G02Y1460078I1664J1456D01*
G03X1528662Y1460210I-150J132D01*
G01Y1462153D01*
G03X1528612Y1462285I-200J0D01*
G02Y1465197I1664J1456D01*
G03X1528662Y1465329I-150J132D01*
G01Y1465951D01*
G02X1528865Y1466154I203J0D01*
G37*
G36*
G01X1684771D02*
X1687591D01*
G02X1687794Y1465951I0J-203D01*
G01Y1465329D01*
G03X1687844Y1465197I200J0D01*
G02Y1462285I-1664J-1456D01*
G03X1687794Y1462153I150J-132D01*
G01Y1460210D01*
G03X1687844Y1460078I200J0D01*
G02Y1457166I-1664J-1456D01*
G03X1687794Y1457034I150J-132D01*
G01Y1456413D01*
G02X1687591Y1456210I-203J0D01*
G01X1684771D01*
G02X1684568Y1456413I0J203D01*
G01Y1457034D01*
G03X1684518Y1457166I-200J0D01*
G02Y1460078I1664J1456D01*
G03X1684568Y1460210I-150J132D01*
G01Y1462153D01*
G03X1684518Y1462285I-200J0D01*
G02Y1465197I1664J1456D01*
G03X1684568Y1465329I-150J132D01*
G01Y1465951D01*
G02X1684771Y1466154I203J0D01*
G37*
G36*
G01X1702093D02*
X1704913D01*
G02X1705116Y1465951I0J-203D01*
G01Y1465329D01*
G03X1705166Y1465197I200J0D01*
G02Y1462285I-1664J-1456D01*
G03X1705116Y1462153I150J-132D01*
G01Y1460210D01*
G03X1705166Y1460078I200J0D01*
G02Y1457166I-1664J-1456D01*
G03X1705116Y1457034I150J-132D01*
G01Y1456413D01*
G02X1704913Y1456210I-203J0D01*
G01X1702093D01*
G02X1701890Y1456413I0J203D01*
G01Y1457034D01*
G03X1701840Y1457166I-200J0D01*
G02Y1460078I1664J1456D01*
G03X1701890Y1460210I-150J132D01*
G01Y1462153D01*
G03X1701840Y1462285I-200J0D01*
G02Y1465197I1664J1456D01*
G03X1701890Y1465329I-150J132D01*
G01Y1465951D01*
G02X1702093Y1466154I203J0D01*
G37*
G36*
G01X134456Y1470484D02*
X137276D01*
G02X137478Y1470281I-1J-203D01*
G01Y1469661D01*
G03X137528Y1469529I200J0D01*
G02Y1466613I-1661J-1458D01*
G03X137478Y1466481I150J-132D01*
G01Y1464543D01*
G03X137528Y1464411I200J0D01*
G02Y1461495I-1661J-1458D01*
G03X137478Y1461363I150J-132D01*
G01Y1460743D01*
G02X137276Y1460540I-202J-1D01*
G01X134456D01*
G02X134254Y1460743I1J203D01*
G01Y1461363D01*
G03X134204Y1461495I-200J0D01*
G02Y1464411I1661J1458D01*
G03X134254Y1464543I-150J132D01*
G01Y1466481D01*
G03X134204Y1466613I-200J0D01*
G02Y1469529I1661J1458D01*
G03X134254Y1469661I-150J132D01*
G01Y1470281D01*
G02X134456Y1470484I202J1D01*
G37*
G36*
G01X151779D02*
X154599D01*
G02X154802Y1470281I0J-203D01*
G01Y1469659D01*
G03X154852Y1469527I200J0D01*
G02Y1466615I-1664J-1456D01*
G03X154802Y1466483I150J-132D01*
G01Y1464541D01*
G03X154852Y1464409I200J0D01*
G02Y1461497I-1664J-1456D01*
G03X154802Y1461365I150J-132D01*
G01Y1460743D01*
G02X154599Y1460540I-203J0D01*
G01X151779D01*
G02X151576Y1460743I0J203D01*
G01Y1461365D01*
G03X151526Y1461497I-200J0D01*
G02Y1464409I1664J1456D01*
G03X151576Y1464541I-150J132D01*
G01Y1466483D01*
G03X151526Y1466615I-200J0D01*
G02Y1469527I1664J1456D01*
G03X151576Y1469659I-150J132D01*
G01Y1470281D01*
G02X151779Y1470484I203J0D01*
G37*
G36*
G01X169102D02*
X171922D01*
G02X172124Y1470281I-1J-203D01*
G01Y1469661D01*
G03X172174Y1469529I200J0D01*
G02Y1466613I-1661J-1458D01*
G03X172124Y1466481I150J-132D01*
G01Y1464543D01*
G03X172174Y1464411I200J0D01*
G02Y1461495I-1661J-1458D01*
G03X172124Y1461363I150J-132D01*
G01Y1460743D01*
G02X171922Y1460540I-202J-1D01*
G01X169102D01*
G02X168900Y1460743I1J203D01*
G01Y1461363D01*
G03X168850Y1461495I-200J0D01*
G02Y1464411I1661J1458D01*
G03X168900Y1464543I-150J132D01*
G01Y1466481D01*
G03X168850Y1466613I-200J0D01*
G02Y1469529I1661J1458D01*
G03X168900Y1469661I-150J132D01*
G01Y1470281D01*
G02X169102Y1470484I202J1D01*
G37*
G36*
G01X186425D02*
X189245D01*
G02X189448Y1470281I0J-203D01*
G01Y1469659D01*
G03X189498Y1469527I200J0D01*
G02Y1466615I-1664J-1456D01*
G03X189448Y1466483I150J-132D01*
G01Y1464541D01*
G03X189498Y1464409I200J0D01*
G02Y1461497I-1664J-1456D01*
G03X189448Y1461365I150J-132D01*
G01Y1460743D01*
G02X189245Y1460540I-203J0D01*
G01X186425D01*
G02X186222Y1460743I0J203D01*
G01Y1461365D01*
G03X186172Y1461497I-200J0D01*
G02Y1464409I1664J1456D01*
G03X186222Y1464541I-150J132D01*
G01Y1466483D01*
G03X186172Y1466615I-200J0D01*
G02Y1469527I1664J1456D01*
G03X186222Y1469659I-150J132D01*
G01Y1470281D01*
G02X186425Y1470484I203J0D01*
G37*
G36*
G01X290361D02*
X293181D01*
G02X293384Y1470281I0J-203D01*
G01Y1469659D01*
G03X293434Y1469527I200J0D01*
G02Y1466615I-1664J-1456D01*
G03X293384Y1466483I150J-132D01*
G01Y1464541D01*
G03X293434Y1464409I200J0D01*
G02Y1461497I-1664J-1456D01*
G03X293384Y1461365I150J-132D01*
G01Y1460743D01*
G02X293181Y1460540I-203J0D01*
G01X290361D01*
G02X290158Y1460743I0J203D01*
G01Y1461365D01*
G03X290108Y1461497I-200J0D01*
G02Y1464409I1664J1456D01*
G03X290158Y1464541I-150J132D01*
G01Y1466483D01*
G03X290108Y1466615I-200J0D01*
G02Y1469527I1664J1456D01*
G03X290158Y1469659I-150J132D01*
G01Y1470281D01*
G02X290361Y1470484I203J0D01*
G37*
G36*
G01X463590D02*
X466410D01*
G02X466612Y1470281I-1J-203D01*
G01Y1469661D01*
G03X466662Y1469529I200J0D01*
G02Y1466613I-1661J-1458D01*
G03X466612Y1466481I150J-132D01*
G01Y1464543D01*
G03X466662Y1464411I200J0D01*
G02Y1461495I-1661J-1458D01*
G03X466612Y1461363I150J-132D01*
G01Y1460743D01*
G02X466410Y1460540I-202J-1D01*
G01X463590D01*
G02X463388Y1460743I1J203D01*
G01Y1461363D01*
G03X463338Y1461495I-200J0D01*
G02Y1464411I1661J1458D01*
G03X463388Y1464543I-150J132D01*
G01Y1466481D01*
G03X463338Y1466613I-200J0D01*
G02Y1469529I1661J1458D01*
G03X463388Y1469661I-150J132D01*
G01Y1470281D01*
G02X463590Y1470484I202J1D01*
G37*
G36*
G01X480913D02*
X483733D01*
G02X483936Y1470281I0J-203D01*
G01Y1469659D01*
G03X483986Y1469527I200J0D01*
G02Y1466615I-1664J-1456D01*
G03X483936Y1466483I150J-132D01*
G01Y1464541D01*
G03X483986Y1464409I200J0D01*
G02Y1461497I-1664J-1456D01*
G03X483936Y1461365I150J-132D01*
G01Y1460743D01*
G02X483733Y1460540I-203J0D01*
G01X480913D01*
G02X480710Y1460743I0J203D01*
G01Y1461365D01*
G03X480660Y1461497I-200J0D01*
G02Y1464409I1664J1456D01*
G03X480710Y1464541I-150J132D01*
G01Y1466483D01*
G03X480660Y1466615I-200J0D01*
G02Y1469527I1664J1456D01*
G03X480710Y1469659I-150J132D01*
G01Y1470281D01*
G02X480913Y1470484I203J0D01*
G37*
G36*
G01X498236D02*
X501056D01*
G02X501258Y1470281I-1J-203D01*
G01Y1469661D01*
G03X501308Y1469529I200J0D01*
G02Y1466613I-1661J-1458D01*
G03X501258Y1466481I150J-132D01*
G01Y1464543D01*
G03X501308Y1464411I200J0D01*
G02Y1461495I-1661J-1458D01*
G03X501258Y1461363I150J-132D01*
G01Y1460743D01*
G02X501056Y1460540I-202J-1D01*
G01X498236D01*
G02X498034Y1460743I1J203D01*
G01Y1461363D01*
G03X497984Y1461495I-200J0D01*
G02Y1464411I1661J1458D01*
G03X498034Y1464543I-150J132D01*
G01Y1466481D01*
G03X497984Y1466613I-200J0D01*
G02Y1469529I1661J1458D01*
G03X498034Y1469661I-150J132D01*
G01Y1470281D01*
G02X498236Y1470484I202J1D01*
G37*
G36*
G01X515559D02*
X518379D01*
G02X518582Y1470281I0J-203D01*
G01Y1469659D01*
G03X518632Y1469527I200J0D01*
G02Y1466615I-1664J-1456D01*
G03X518582Y1466483I150J-132D01*
G01Y1464541D01*
G03X518632Y1464409I200J0D01*
G02Y1461497I-1664J-1456D01*
G03X518582Y1461365I150J-132D01*
G01Y1460743D01*
G02X518379Y1460540I-203J0D01*
G01X515559D01*
G02X515356Y1460743I0J203D01*
G01Y1461365D01*
G03X515306Y1461497I-200J0D01*
G02Y1464409I1664J1456D01*
G03X515356Y1464541I-150J132D01*
G01Y1466483D01*
G03X515306Y1466615I-200J0D01*
G02Y1469527I1664J1456D01*
G03X515356Y1469659I-150J132D01*
G01Y1470281D01*
G02X515559Y1470484I203J0D01*
G37*
G36*
G01X654141D02*
X656961D01*
G02X657164Y1470281I0J-203D01*
G01Y1469659D01*
G03X657214Y1469527I200J0D01*
G02Y1466615I-1664J-1456D01*
G03X657164Y1466483I150J-132D01*
G01Y1464541D01*
G03X657214Y1464409I200J0D01*
G02Y1461497I-1664J-1456D01*
G03X657164Y1461365I150J-132D01*
G01Y1460743D01*
G02X656961Y1460540I-203J0D01*
G01X654141D01*
G02X653938Y1460743I0J203D01*
G01Y1461365D01*
G03X653888Y1461497I-200J0D01*
G02Y1464409I1664J1456D01*
G03X653938Y1464541I-150J132D01*
G01Y1466483D01*
G03X653888Y1466615I-200J0D01*
G02Y1469527I1664J1456D01*
G03X653938Y1469659I-150J132D01*
G01Y1470281D01*
G02X654141Y1470484I203J0D01*
G37*
G36*
G01X671464D02*
X674284D01*
G02X674486Y1470281I-1J-203D01*
G01Y1469661D01*
G03X674536Y1469529I200J0D01*
G02Y1466613I-1661J-1458D01*
G03X674486Y1466481I150J-132D01*
G01Y1464543D01*
G03X674536Y1464411I200J0D01*
G02Y1461495I-1661J-1458D01*
G03X674486Y1461363I150J-132D01*
G01Y1460743D01*
G02X674284Y1460540I-202J-1D01*
G01X671464D01*
G02X671262Y1460743I1J203D01*
G01Y1461363D01*
G03X671212Y1461495I-200J0D01*
G02Y1464411I1661J1458D01*
G03X671262Y1464543I-150J132D01*
G01Y1466481D01*
G03X671212Y1466613I-200J0D01*
G02Y1469529I1661J1458D01*
G03X671262Y1469661I-150J132D01*
G01Y1470281D01*
G02X671464Y1470484I202J1D01*
G37*
G36*
G01X688787D02*
X691607D01*
G02X691810Y1470281I0J-203D01*
G01Y1469659D01*
G03X691860Y1469527I200J0D01*
G02Y1466615I-1664J-1456D01*
G03X691810Y1466483I150J-132D01*
G01Y1464541D01*
G03X691860Y1464409I200J0D01*
G02Y1461497I-1664J-1456D01*
G03X691810Y1461365I150J-132D01*
G01Y1460743D01*
G02X691607Y1460540I-203J0D01*
G01X688787D01*
G02X688584Y1460743I0J203D01*
G01Y1461365D01*
G03X688534Y1461497I-200J0D01*
G02Y1464409I1664J1456D01*
G03X688584Y1464541I-150J132D01*
G01Y1466483D01*
G03X688534Y1466615I-200J0D01*
G02Y1469527I1664J1456D01*
G03X688584Y1469659I-150J132D01*
G01Y1470281D01*
G02X688787Y1470484I203J0D01*
G37*
G36*
G01X1173747D02*
X1176567D01*
G02X1176770Y1470281I0J-203D01*
G01Y1469659D01*
G03X1176820Y1469527I200J0D01*
G02Y1466615I-1664J-1456D01*
G03X1176770Y1466483I150J-132D01*
G01Y1464541D01*
G03X1176820Y1464409I200J0D01*
G02Y1461497I-1664J-1456D01*
G03X1176770Y1461365I150J-132D01*
G01Y1460743D01*
G02X1176567Y1460540I-203J0D01*
G01X1173747D01*
G02X1173544Y1460743I0J203D01*
G01Y1461365D01*
G03X1173494Y1461497I-200J0D01*
G02Y1464409I1664J1456D01*
G03X1173544Y1464541I-150J132D01*
G01Y1466483D01*
G03X1173494Y1466615I-200J0D01*
G02Y1469527I1664J1456D01*
G03X1173544Y1469659I-150J132D01*
G01Y1470281D01*
G02X1173747Y1470484I203J0D01*
G37*
G36*
G01X1191070D02*
X1193890D01*
G02X1194092Y1470281I-1J-203D01*
G01Y1469661D01*
G03X1194142Y1469529I200J0D01*
G02Y1466613I-1661J-1458D01*
G03X1194092Y1466481I150J-132D01*
G01Y1464543D01*
G03X1194142Y1464411I200J0D01*
G02Y1461495I-1661J-1458D01*
G03X1194092Y1461363I150J-132D01*
G01Y1460743D01*
G02X1193890Y1460540I-202J-1D01*
G01X1191070D01*
G02X1190868Y1460743I1J203D01*
G01Y1461363D01*
G03X1190818Y1461495I-200J0D01*
G02Y1464411I1661J1458D01*
G03X1190868Y1464543I-150J132D01*
G01Y1466481D01*
G03X1190818Y1466613I-200J0D01*
G02Y1469529I1661J1458D01*
G03X1190868Y1469661I-150J132D01*
G01Y1470281D01*
G02X1191070Y1470484I202J1D01*
G37*
G36*
G01X1312330D02*
X1315150D01*
G02X1315352Y1470281I-1J-203D01*
G01Y1469661D01*
G03X1315402Y1469529I200J0D01*
G02Y1466613I-1661J-1458D01*
G03X1315352Y1466481I150J-132D01*
G01Y1464543D01*
G03X1315402Y1464411I200J0D01*
G02Y1461495I-1661J-1458D01*
G03X1315352Y1461363I150J-132D01*
G01Y1460743D01*
G02X1315150Y1460540I-202J-1D01*
G01X1312330D01*
G02X1312128Y1460743I1J203D01*
G01Y1461363D01*
G03X1312078Y1461495I-200J0D01*
G02Y1464411I1661J1458D01*
G03X1312128Y1464543I-150J132D01*
G01Y1466481D01*
G03X1312078Y1466613I-200J0D01*
G02Y1469529I1661J1458D01*
G03X1312128Y1469661I-150J132D01*
G01Y1470281D01*
G02X1312330Y1470484I202J1D01*
G37*
G36*
G01X1329653D02*
X1332473D01*
G02X1332676Y1470281I0J-203D01*
G01Y1469659D01*
G03X1332726Y1469527I200J0D01*
G02Y1466615I-1664J-1456D01*
G03X1332676Y1466483I150J-132D01*
G01Y1464541D01*
G03X1332726Y1464409I200J0D01*
G02Y1461497I-1664J-1456D01*
G03X1332676Y1461365I150J-132D01*
G01Y1460743D01*
G02X1332473Y1460540I-203J0D01*
G01X1329653D01*
G02X1329450Y1460743I0J203D01*
G01Y1461365D01*
G03X1329400Y1461497I-200J0D01*
G02Y1464409I1664J1456D01*
G03X1329450Y1464541I-150J132D01*
G01Y1466483D01*
G03X1329400Y1466615I-200J0D01*
G02Y1469527I1664J1456D01*
G03X1329450Y1469659I-150J132D01*
G01Y1470281D01*
G02X1329653Y1470484I203J0D01*
G37*
G36*
G01X1346976D02*
X1349796D01*
G02X1349998Y1470281I-1J-203D01*
G01Y1469661D01*
G03X1350048Y1469529I200J0D01*
G02Y1466613I-1661J-1458D01*
G03X1349998Y1466481I150J-132D01*
G01Y1464543D01*
G03X1350048Y1464411I200J0D01*
G02Y1461495I-1661J-1458D01*
G03X1349998Y1461363I150J-132D01*
G01Y1460743D01*
G02X1349796Y1460540I-202J-1D01*
G01X1346976D01*
G02X1346774Y1460743I1J203D01*
G01Y1461363D01*
G03X1346724Y1461495I-200J0D01*
G02Y1464411I1661J1458D01*
G03X1346774Y1464543I-150J132D01*
G01Y1466481D01*
G03X1346724Y1466613I-200J0D01*
G02Y1469529I1661J1458D01*
G03X1346774Y1469661I-150J132D01*
G01Y1470281D01*
G02X1346976Y1470484I202J1D01*
G37*
G36*
G01X1364299D02*
X1367119D01*
G02X1367322Y1470281I0J-203D01*
G01Y1469659D01*
G03X1367372Y1469527I200J0D01*
G02Y1466615I-1664J-1456D01*
G03X1367322Y1466483I150J-132D01*
G01Y1464541D01*
G03X1367372Y1464409I200J0D01*
G02Y1461497I-1664J-1456D01*
G03X1367322Y1461365I150J-132D01*
G01Y1460743D01*
G02X1367119Y1460540I-203J0D01*
G01X1364299D01*
G02X1364096Y1460743I0J203D01*
G01Y1461365D01*
G03X1364046Y1461497I-200J0D01*
G02Y1464409I1664J1456D01*
G03X1364096Y1464541I-150J132D01*
G01Y1466483D01*
G03X1364046Y1466615I-200J0D01*
G02Y1469527I1664J1456D01*
G03X1364096Y1469659I-150J132D01*
G01Y1470281D01*
G02X1364299Y1470484I203J0D01*
G37*
G36*
G01X1485558D02*
X1488378D01*
G02X1488580Y1470281I-1J-203D01*
G01Y1469661D01*
G03X1488630Y1469529I200J0D01*
G02Y1466613I-1661J-1458D01*
G03X1488580Y1466481I150J-132D01*
G01Y1464543D01*
G03X1488630Y1464411I200J0D01*
G02Y1461495I-1661J-1458D01*
G03X1488580Y1461363I150J-132D01*
G01Y1460743D01*
G02X1488378Y1460540I-202J-1D01*
G01X1485558D01*
G02X1485356Y1460743I1J203D01*
G01Y1461363D01*
G03X1485306Y1461495I-200J0D01*
G02Y1464411I1661J1458D01*
G03X1485356Y1464543I-150J132D01*
G01Y1466481D01*
G03X1485306Y1466613I-200J0D01*
G02Y1469529I1661J1458D01*
G03X1485356Y1469661I-150J132D01*
G01Y1470281D01*
G02X1485558Y1470484I202J1D01*
G37*
G36*
G01X1502881D02*
X1505701D01*
G02X1505904Y1470281I0J-203D01*
G01Y1469659D01*
G03X1505954Y1469527I200J0D01*
G02Y1466615I-1664J-1456D01*
G03X1505904Y1466483I150J-132D01*
G01Y1464541D01*
G03X1505954Y1464409I200J0D01*
G02Y1461497I-1664J-1456D01*
G03X1505904Y1461365I150J-132D01*
G01Y1460743D01*
G02X1505701Y1460540I-203J0D01*
G01X1502881D01*
G02X1502678Y1460743I0J203D01*
G01Y1461365D01*
G03X1502628Y1461497I-200J0D01*
G02Y1464409I1664J1456D01*
G03X1502678Y1464541I-150J132D01*
G01Y1466483D01*
G03X1502628Y1466615I-200J0D01*
G02Y1469527I1664J1456D01*
G03X1502678Y1469659I-150J132D01*
G01Y1470281D01*
G02X1502881Y1470484I203J0D01*
G37*
G36*
G01X1520204D02*
X1523024D01*
G02X1523226Y1470281I-1J-203D01*
G01Y1469661D01*
G03X1523276Y1469529I200J0D01*
G02Y1466613I-1661J-1458D01*
G03X1523226Y1466481I150J-132D01*
G01Y1464543D01*
G03X1523276Y1464411I200J0D01*
G02Y1461495I-1661J-1458D01*
G03X1523226Y1461363I150J-132D01*
G01Y1460743D01*
G02X1523024Y1460540I-202J-1D01*
G01X1520204D01*
G02X1520002Y1460743I1J203D01*
G01Y1461363D01*
G03X1519952Y1461495I-200J0D01*
G02Y1464411I1661J1458D01*
G03X1520002Y1464543I-150J132D01*
G01Y1466481D01*
G03X1519952Y1466613I-200J0D01*
G02Y1469529I1661J1458D01*
G03X1520002Y1469661I-150J132D01*
G01Y1470281D01*
G02X1520204Y1470484I202J1D01*
G37*
G36*
G01X1537527D02*
X1540347D01*
G02X1540550Y1470281I0J-203D01*
G01Y1469659D01*
G03X1540600Y1469527I200J0D01*
G02Y1466615I-1664J-1456D01*
G03X1540550Y1466483I150J-132D01*
G01Y1464541D01*
G03X1540600Y1464409I200J0D01*
G02Y1461497I-1664J-1456D01*
G03X1540550Y1461365I150J-132D01*
G01Y1460743D01*
G02X1540347Y1460540I-203J0D01*
G01X1537527D01*
G02X1537324Y1460743I0J203D01*
G01Y1461365D01*
G03X1537274Y1461497I-200J0D01*
G02Y1464409I1664J1456D01*
G03X1537324Y1464541I-150J132D01*
G01Y1466483D01*
G03X1537274Y1466615I-200J0D01*
G02Y1469527I1664J1456D01*
G03X1537324Y1469659I-150J132D01*
G01Y1470281D01*
G02X1537527Y1470484I203J0D01*
G37*
G36*
G01X1693432D02*
X1696252D01*
G02X1696454Y1470281I-1J-203D01*
G01Y1469661D01*
G03X1696504Y1469529I200J0D01*
G02Y1466613I-1661J-1458D01*
G03X1696454Y1466481I150J-132D01*
G01Y1464543D01*
G03X1696504Y1464411I200J0D01*
G02Y1461495I-1661J-1458D01*
G03X1696454Y1461363I150J-132D01*
G01Y1460743D01*
G02X1696252Y1460540I-202J-1D01*
G01X1693432D01*
G02X1693230Y1460743I1J203D01*
G01Y1461363D01*
G03X1693180Y1461495I-200J0D01*
G02Y1464411I1661J1458D01*
G03X1693230Y1464543I-150J132D01*
G01Y1466481D01*
G03X1693180Y1466613I-200J0D01*
G02Y1469529I1661J1458D01*
G03X1693230Y1469661I-150J132D01*
G01Y1470281D01*
G02X1693432Y1470484I202J1D01*
G37*
G36*
G01X1710755D02*
X1713575D01*
G02X1713778Y1470281I0J-203D01*
G01Y1469659D01*
G03X1713828Y1469527I200J0D01*
G02Y1466615I-1664J-1456D01*
G03X1713778Y1466483I150J-132D01*
G01Y1464541D01*
G03X1713828Y1464409I200J0D01*
G02Y1461497I-1664J-1456D01*
G03X1713778Y1461365I150J-132D01*
G01Y1460743D01*
G02X1713575Y1460540I-203J0D01*
G01X1710755D01*
G02X1710552Y1460743I0J203D01*
G01Y1461365D01*
G03X1710502Y1461497I-200J0D01*
G02Y1464409I1664J1456D01*
G03X1710552Y1464541I-150J132D01*
G01Y1466483D01*
G03X1710502Y1466615I-200J0D01*
G02Y1469527I1664J1456D01*
G03X1710552Y1469659I-150J132D01*
G01Y1470281D01*
G02X1710755Y1470484I203J0D01*
G37*
G36*
G01X125795Y1481508D02*
X128615D01*
G02X128818Y1481305I0J-203D01*
G01Y1480683D01*
G03X128868Y1480551I200J0D01*
G02Y1477639I-1664J-1456D01*
G03X128818Y1477507I150J-132D01*
G01Y1475565D01*
G03X128868Y1475433I200J0D01*
G02Y1472521I-1664J-1456D01*
G03X128818Y1472389I150J-132D01*
G01Y1471767D01*
G02X128615Y1471564I-203J0D01*
G01X125795D01*
G02X125592Y1471767I0J203D01*
G01Y1472389D01*
G03X125542Y1472521I-200J0D01*
G02Y1475433I1664J1456D01*
G03X125592Y1475565I-150J132D01*
G01Y1477507D01*
G03X125542Y1477639I-200J0D01*
G02Y1480551I1664J1456D01*
G03X125592Y1480683I-150J132D01*
G01Y1481305D01*
G02X125795Y1481508I203J0D01*
G37*
G36*
G01X143118D02*
X145938D01*
G02X146140Y1481305I-1J-203D01*
G01Y1480685D01*
G03X146190Y1480553I200J0D01*
G02Y1477637I-1661J-1458D01*
G03X146140Y1477505I150J-132D01*
G01Y1475567D01*
G03X146190Y1475435I200J0D01*
G02Y1472519I-1661J-1458D01*
G03X146140Y1472387I150J-132D01*
G01Y1471767D01*
G02X145938Y1471564I-202J-1D01*
G01X143118D01*
G02X142916Y1471767I1J203D01*
G01Y1472387D01*
G03X142866Y1472519I-200J0D01*
G02Y1475435I1661J1458D01*
G03X142916Y1475567I-150J132D01*
G01Y1477505D01*
G03X142866Y1477637I-200J0D01*
G02Y1480553I1661J1458D01*
G03X142916Y1480685I-150J132D01*
G01Y1481305D01*
G02X143118Y1481508I202J1D01*
G37*
G36*
G01X160440D02*
X163260D01*
G02X163462Y1481305I-1J-203D01*
G01Y1480685D01*
G03X163512Y1480553I200J0D01*
G02Y1477637I-1661J-1458D01*
G03X163462Y1477505I150J-132D01*
G01Y1475567D01*
G03X163512Y1475435I200J0D01*
G02Y1472519I-1661J-1458D01*
G03X163462Y1472387I150J-132D01*
G01Y1471767D01*
G02X163260Y1471564I-202J-1D01*
G01X160440D01*
G02X160238Y1471767I1J203D01*
G01Y1472387D01*
G03X160188Y1472519I-200J0D01*
G02Y1475435I1661J1458D01*
G03X160238Y1475567I-150J132D01*
G01Y1477505D01*
G03X160188Y1477637I-200J0D01*
G02Y1480553I1661J1458D01*
G03X160238Y1480685I-150J132D01*
G01Y1481305D01*
G02X160440Y1481508I202J1D01*
G37*
G36*
G01X177763D02*
X180583D01*
G02X180786Y1481305I0J-203D01*
G01Y1480683D01*
G03X180836Y1480551I200J0D01*
G02Y1477639I-1664J-1456D01*
G03X180786Y1477507I150J-132D01*
G01Y1475565D01*
G03X180836Y1475433I200J0D01*
G02Y1472521I-1664J-1456D01*
G03X180786Y1472389I150J-132D01*
G01Y1471767D01*
G02X180583Y1471564I-203J0D01*
G01X177763D01*
G02X177560Y1471767I0J203D01*
G01Y1472389D01*
G03X177510Y1472521I-200J0D01*
G02Y1475433I1664J1456D01*
G03X177560Y1475565I-150J132D01*
G01Y1477507D01*
G03X177510Y1477639I-200J0D01*
G02Y1480551I1664J1456D01*
G03X177560Y1480683I-150J132D01*
G01Y1481305D01*
G02X177763Y1481508I203J0D01*
G37*
G36*
G01X281700D02*
X284520D01*
G02X284722Y1481305I-1J-203D01*
G01Y1480685D01*
G03X284772Y1480553I200J0D01*
G02Y1477637I-1661J-1458D01*
G03X284722Y1477505I150J-132D01*
G01Y1475567D01*
G03X284772Y1475435I200J0D01*
G02Y1472519I-1661J-1458D01*
G03X284722Y1472387I150J-132D01*
G01Y1471767D01*
G02X284520Y1471564I-202J-1D01*
G01X281700D01*
G02X281498Y1471767I1J203D01*
G01Y1472387D01*
G03X281448Y1472519I-200J0D01*
G02Y1475435I1661J1458D01*
G03X281498Y1475567I-150J132D01*
G01Y1477505D01*
G03X281448Y1477637I-200J0D01*
G02Y1480553I1661J1458D01*
G03X281498Y1480685I-150J132D01*
G01Y1481305D01*
G02X281700Y1481508I202J1D01*
G37*
G36*
G01X299023D02*
X301843D01*
G02X302046Y1481305I0J-203D01*
G01Y1480683D01*
G03X302096Y1480551I200J0D01*
G02Y1477639I-1664J-1456D01*
G03X302046Y1477507I150J-132D01*
G01Y1475565D01*
G03X302096Y1475433I200J0D01*
G02Y1472521I-1664J-1456D01*
G03X302046Y1472389I150J-132D01*
G01Y1471767D01*
G02X301843Y1471564I-203J0D01*
G01X299023D01*
G02X298820Y1471767I0J203D01*
G01Y1472389D01*
G03X298770Y1472521I-200J0D01*
G02Y1475433I1664J1456D01*
G03X298820Y1475565I-150J132D01*
G01Y1477507D01*
G03X298770Y1477639I-200J0D01*
G02Y1480551I1664J1456D01*
G03X298820Y1480683I-150J132D01*
G01Y1481305D01*
G02X299023Y1481508I203J0D01*
G37*
G36*
G01X454929D02*
X457749D01*
G02X457952Y1481305I0J-203D01*
G01Y1480683D01*
G03X458002Y1480551I200J0D01*
G02Y1477639I-1664J-1456D01*
G03X457952Y1477507I150J-132D01*
G01Y1475565D01*
G03X458002Y1475433I200J0D01*
G02Y1472521I-1664J-1456D01*
G03X457952Y1472389I150J-132D01*
G01Y1471767D01*
G02X457749Y1471564I-203J0D01*
G01X454929D01*
G02X454726Y1471767I0J203D01*
G01Y1472389D01*
G03X454676Y1472521I-200J0D01*
G02Y1475433I1664J1456D01*
G03X454726Y1475565I-150J132D01*
G01Y1477507D01*
G03X454676Y1477639I-200J0D01*
G02Y1480551I1664J1456D01*
G03X454726Y1480683I-150J132D01*
G01Y1481305D01*
G02X454929Y1481508I203J0D01*
G37*
G36*
G01X472252D02*
X475072D01*
G02X475274Y1481305I-1J-203D01*
G01Y1480685D01*
G03X475324Y1480553I200J0D01*
G02Y1477637I-1661J-1458D01*
G03X475274Y1477505I150J-132D01*
G01Y1475567D01*
G03X475324Y1475435I200J0D01*
G02Y1472519I-1661J-1458D01*
G03X475274Y1472387I150J-132D01*
G01Y1471767D01*
G02X475072Y1471564I-202J-1D01*
G01X472252D01*
G02X472050Y1471767I1J203D01*
G01Y1472387D01*
G03X472000Y1472519I-200J0D01*
G02Y1475435I1661J1458D01*
G03X472050Y1475567I-150J132D01*
G01Y1477505D01*
G03X472000Y1477637I-200J0D01*
G02Y1480553I1661J1458D01*
G03X472050Y1480685I-150J132D01*
G01Y1481305D01*
G02X472252Y1481508I202J1D01*
G37*
G36*
G01X489575D02*
X492395D01*
G02X492598Y1481305I0J-203D01*
G01Y1480683D01*
G03X492648Y1480551I200J0D01*
G02Y1477639I-1664J-1456D01*
G03X492598Y1477507I150J-132D01*
G01Y1475565D01*
G03X492648Y1475433I200J0D01*
G02Y1472521I-1664J-1456D01*
G03X492598Y1472389I150J-132D01*
G01Y1471767D01*
G02X492395Y1471564I-203J0D01*
G01X489575D01*
G02X489372Y1471767I0J203D01*
G01Y1472389D01*
G03X489322Y1472521I-200J0D01*
G02Y1475433I1664J1456D01*
G03X489372Y1475565I-150J132D01*
G01Y1477507D01*
G03X489322Y1477639I-200J0D01*
G02Y1480551I1664J1456D01*
G03X489372Y1480683I-150J132D01*
G01Y1481305D01*
G02X489575Y1481508I203J0D01*
G37*
G36*
G01X506897D02*
X509717D01*
G02X509920Y1481305I0J-203D01*
G01Y1480683D01*
G03X509970Y1480551I200J0D01*
G02Y1477639I-1664J-1456D01*
G03X509920Y1477507I150J-132D01*
G01Y1475565D01*
G03X509970Y1475433I200J0D01*
G02Y1472521I-1664J-1456D01*
G03X509920Y1472389I150J-132D01*
G01Y1471767D01*
G02X509717Y1471564I-203J0D01*
G01X506897D01*
G02X506694Y1471767I0J203D01*
G01Y1472389D01*
G03X506644Y1472521I-200J0D01*
G02Y1475433I1664J1456D01*
G03X506694Y1475565I-150J132D01*
G01Y1477507D01*
G03X506644Y1477639I-200J0D01*
G02Y1480551I1664J1456D01*
G03X506694Y1480683I-150J132D01*
G01Y1481305D01*
G02X506897Y1481508I203J0D01*
G37*
G36*
G01X645480D02*
X648300D01*
G02X648502Y1481305I-1J-203D01*
G01Y1480685D01*
G03X648552Y1480553I200J0D01*
G02Y1477637I-1661J-1458D01*
G03X648502Y1477505I150J-132D01*
G01Y1475567D01*
G03X648552Y1475435I200J0D01*
G02Y1472519I-1661J-1458D01*
G03X648502Y1472387I150J-132D01*
G01Y1471767D01*
G02X648300Y1471564I-202J-1D01*
G01X645480D01*
G02X645278Y1471767I1J203D01*
G01Y1472387D01*
G03X645228Y1472519I-200J0D01*
G02Y1475435I1661J1458D01*
G03X645278Y1475567I-150J132D01*
G01Y1477505D01*
G03X645228Y1477637I-200J0D01*
G02Y1480553I1661J1458D01*
G03X645278Y1480685I-150J132D01*
G01Y1481305D01*
G02X645480Y1481508I202J1D01*
G37*
G36*
G01X662803D02*
X665623D01*
G02X665826Y1481305I0J-203D01*
G01Y1480683D01*
G03X665876Y1480551I200J0D01*
G02Y1477639I-1664J-1456D01*
G03X665826Y1477507I150J-132D01*
G01Y1475565D01*
G03X665876Y1475433I200J0D01*
G02Y1472521I-1664J-1456D01*
G03X665826Y1472389I150J-132D01*
G01Y1471767D01*
G02X665623Y1471564I-203J0D01*
G01X662803D01*
G02X662600Y1471767I0J203D01*
G01Y1472389D01*
G03X662550Y1472521I-200J0D01*
G02Y1475433I1664J1456D01*
G03X662600Y1475565I-150J132D01*
G01Y1477507D01*
G03X662550Y1477639I-200J0D01*
G02Y1480551I1664J1456D01*
G03X662600Y1480683I-150J132D01*
G01Y1481305D01*
G02X662803Y1481508I203J0D01*
G37*
G36*
G01X680125D02*
X682945D01*
G02X683148Y1481305I0J-203D01*
G01Y1480683D01*
G03X683198Y1480551I200J0D01*
G02Y1477639I-1664J-1456D01*
G03X683148Y1477507I150J-132D01*
G01Y1475565D01*
G03X683198Y1475433I200J0D01*
G02Y1472521I-1664J-1456D01*
G03X683148Y1472389I150J-132D01*
G01Y1471767D01*
G02X682945Y1471564I-203J0D01*
G01X680125D01*
G02X679922Y1471767I0J203D01*
G01Y1472389D01*
G03X679872Y1472521I-200J0D01*
G02Y1475433I1664J1456D01*
G03X679922Y1475565I-150J132D01*
G01Y1477507D01*
G03X679872Y1477639I-200J0D01*
G02Y1480551I1664J1456D01*
G03X679922Y1480683I-150J132D01*
G01Y1481305D01*
G02X680125Y1481508I203J0D01*
G37*
G36*
G01X1165086D02*
X1167906D01*
G02X1168108Y1481305I-1J-203D01*
G01Y1480685D01*
G03X1168158Y1480553I200J0D01*
G02Y1477637I-1661J-1458D01*
G03X1168108Y1477505I150J-132D01*
G01Y1475567D01*
G03X1168158Y1475435I200J0D01*
G02Y1472519I-1661J-1458D01*
G03X1168108Y1472387I150J-132D01*
G01Y1471767D01*
G02X1167906Y1471564I-202J-1D01*
G01X1165086D01*
G02X1164884Y1471767I1J203D01*
G01Y1472387D01*
G03X1164834Y1472519I-200J0D01*
G02Y1475435I1661J1458D01*
G03X1164884Y1475567I-150J132D01*
G01Y1477505D01*
G03X1164834Y1477637I-200J0D01*
G02Y1480553I1661J1458D01*
G03X1164884Y1480685I-150J132D01*
G01Y1481305D01*
G02X1165086Y1481508I202J1D01*
G37*
G36*
G01X1182408D02*
X1185228D01*
G02X1185430Y1481305I-1J-203D01*
G01Y1480685D01*
G03X1185480Y1480553I200J0D01*
G02Y1477637I-1661J-1458D01*
G03X1185430Y1477505I150J-132D01*
G01Y1475567D01*
G03X1185480Y1475435I200J0D01*
G02Y1472519I-1661J-1458D01*
G03X1185430Y1472387I150J-132D01*
G01Y1471767D01*
G02X1185228Y1471564I-202J-1D01*
G01X1182408D01*
G02X1182206Y1471767I1J203D01*
G01Y1472387D01*
G03X1182156Y1472519I-200J0D01*
G02Y1475435I1661J1458D01*
G03X1182206Y1475567I-150J132D01*
G01Y1477505D01*
G03X1182156Y1477637I-200J0D01*
G02Y1480553I1661J1458D01*
G03X1182206Y1480685I-150J132D01*
G01Y1481305D01*
G02X1182408Y1481508I202J1D01*
G37*
G36*
G01X1303669D02*
X1306489D01*
G02X1306692Y1481305I0J-203D01*
G01Y1480683D01*
G03X1306742Y1480551I200J0D01*
G02Y1477639I-1664J-1456D01*
G03X1306692Y1477507I150J-132D01*
G01Y1475565D01*
G03X1306742Y1475433I200J0D01*
G02Y1472521I-1664J-1456D01*
G03X1306692Y1472389I150J-132D01*
G01Y1471767D01*
G02X1306489Y1471564I-203J0D01*
G01X1303669D01*
G02X1303466Y1471767I0J203D01*
G01Y1472389D01*
G03X1303416Y1472521I-200J0D01*
G02Y1475433I1664J1456D01*
G03X1303466Y1475565I-150J132D01*
G01Y1477507D01*
G03X1303416Y1477639I-200J0D01*
G02Y1480551I1664J1456D01*
G03X1303466Y1480683I-150J132D01*
G01Y1481305D01*
G02X1303669Y1481508I203J0D01*
G37*
G36*
G01X1320992D02*
X1323812D01*
G02X1324014Y1481305I-1J-203D01*
G01Y1480685D01*
G03X1324064Y1480553I200J0D01*
G02Y1477637I-1661J-1458D01*
G03X1324014Y1477505I150J-132D01*
G01Y1475567D01*
G03X1324064Y1475435I200J0D01*
G02Y1472519I-1661J-1458D01*
G03X1324014Y1472387I150J-132D01*
G01Y1471767D01*
G02X1323812Y1471564I-202J-1D01*
G01X1320992D01*
G02X1320790Y1471767I1J203D01*
G01Y1472387D01*
G03X1320740Y1472519I-200J0D01*
G02Y1475435I1661J1458D01*
G03X1320790Y1475567I-150J132D01*
G01Y1477505D01*
G03X1320740Y1477637I-200J0D01*
G02Y1480553I1661J1458D01*
G03X1320790Y1480685I-150J132D01*
G01Y1481305D01*
G02X1320992Y1481508I202J1D01*
G37*
G36*
G01X1338315D02*
X1341135D01*
G02X1341338Y1481305I0J-203D01*
G01Y1480683D01*
G03X1341388Y1480551I200J0D01*
G02Y1477639I-1664J-1456D01*
G03X1341338Y1477507I150J-132D01*
G01Y1475565D01*
G03X1341388Y1475433I200J0D01*
G02Y1472521I-1664J-1456D01*
G03X1341338Y1472389I150J-132D01*
G01Y1471767D01*
G02X1341135Y1471564I-203J0D01*
G01X1338315D01*
G02X1338112Y1471767I0J203D01*
G01Y1472389D01*
G03X1338062Y1472521I-200J0D01*
G02Y1475433I1664J1456D01*
G03X1338112Y1475565I-150J132D01*
G01Y1477507D01*
G03X1338062Y1477639I-200J0D01*
G02Y1480551I1664J1456D01*
G03X1338112Y1480683I-150J132D01*
G01Y1481305D01*
G02X1338315Y1481508I203J0D01*
G37*
G36*
G01X1355637D02*
X1358457D01*
G02X1358660Y1481305I0J-203D01*
G01Y1480683D01*
G03X1358710Y1480551I200J0D01*
G02Y1477639I-1664J-1456D01*
G03X1358660Y1477507I150J-132D01*
G01Y1475565D01*
G03X1358710Y1475433I200J0D01*
G02Y1472521I-1664J-1456D01*
G03X1358660Y1472389I150J-132D01*
G01Y1471767D01*
G02X1358457Y1471564I-203J0D01*
G01X1355637D01*
G02X1355434Y1471767I0J203D01*
G01Y1472389D01*
G03X1355384Y1472521I-200J0D01*
G02Y1475433I1664J1456D01*
G03X1355434Y1475565I-150J132D01*
G01Y1477507D01*
G03X1355384Y1477639I-200J0D01*
G02Y1480551I1664J1456D01*
G03X1355434Y1480683I-150J132D01*
G01Y1481305D01*
G02X1355637Y1481508I203J0D01*
G37*
G36*
G01X1476897D02*
X1479717D01*
G02X1479920Y1481305I0J-203D01*
G01Y1480683D01*
G03X1479970Y1480551I200J0D01*
G02Y1477639I-1664J-1456D01*
G03X1479920Y1477507I150J-132D01*
G01Y1475565D01*
G03X1479970Y1475433I200J0D01*
G02Y1472521I-1664J-1456D01*
G03X1479920Y1472389I150J-132D01*
G01Y1471767D01*
G02X1479717Y1471564I-203J0D01*
G01X1476897D01*
G02X1476694Y1471767I0J203D01*
G01Y1472389D01*
G03X1476644Y1472521I-200J0D01*
G02Y1475433I1664J1456D01*
G03X1476694Y1475565I-150J132D01*
G01Y1477507D01*
G03X1476644Y1477639I-200J0D01*
G02Y1480551I1664J1456D01*
G03X1476694Y1480683I-150J132D01*
G01Y1481305D01*
G02X1476897Y1481508I203J0D01*
G37*
G36*
G01X1494220D02*
X1497040D01*
G02X1497242Y1481305I-1J-203D01*
G01Y1480685D01*
G03X1497292Y1480553I200J0D01*
G02Y1477637I-1661J-1458D01*
G03X1497242Y1477505I150J-132D01*
G01Y1475567D01*
G03X1497292Y1475435I200J0D01*
G02Y1472519I-1661J-1458D01*
G03X1497242Y1472387I150J-132D01*
G01Y1471767D01*
G02X1497040Y1471564I-202J-1D01*
G01X1494220D01*
G02X1494018Y1471767I1J203D01*
G01Y1472387D01*
G03X1493968Y1472519I-200J0D01*
G02Y1475435I1661J1458D01*
G03X1494018Y1475567I-150J132D01*
G01Y1477505D01*
G03X1493968Y1477637I-200J0D01*
G02Y1480553I1661J1458D01*
G03X1494018Y1480685I-150J132D01*
G01Y1481305D01*
G02X1494220Y1481508I202J1D01*
G37*
G36*
G01X1511543D02*
X1514363D01*
G02X1514566Y1481305I0J-203D01*
G01Y1480683D01*
G03X1514616Y1480551I200J0D01*
G02Y1477639I-1664J-1456D01*
G03X1514566Y1477507I150J-132D01*
G01Y1475565D01*
G03X1514616Y1475433I200J0D01*
G02Y1472521I-1664J-1456D01*
G03X1514566Y1472389I150J-132D01*
G01Y1471767D01*
G02X1514363Y1471564I-203J0D01*
G01X1511543D01*
G02X1511340Y1471767I0J203D01*
G01Y1472389D01*
G03X1511290Y1472521I-200J0D01*
G02Y1475433I1664J1456D01*
G03X1511340Y1475565I-150J132D01*
G01Y1477507D01*
G03X1511290Y1477639I-200J0D01*
G02Y1480551I1664J1456D01*
G03X1511340Y1480683I-150J132D01*
G01Y1481305D01*
G02X1511543Y1481508I203J0D01*
G37*
G36*
G01X1528865D02*
X1531685D01*
G02X1531888Y1481305I0J-203D01*
G01Y1480683D01*
G03X1531938Y1480551I200J0D01*
G02Y1477639I-1664J-1456D01*
G03X1531888Y1477507I150J-132D01*
G01Y1475565D01*
G03X1531938Y1475433I200J0D01*
G02Y1472521I-1664J-1456D01*
G03X1531888Y1472389I150J-132D01*
G01Y1471767D01*
G02X1531685Y1471564I-203J0D01*
G01X1528865D01*
G02X1528662Y1471767I0J203D01*
G01Y1472389D01*
G03X1528612Y1472521I-200J0D01*
G02Y1475433I1664J1456D01*
G03X1528662Y1475565I-150J132D01*
G01Y1477507D01*
G03X1528612Y1477639I-200J0D01*
G02Y1480551I1664J1456D01*
G03X1528662Y1480683I-150J132D01*
G01Y1481305D01*
G02X1528865Y1481508I203J0D01*
G37*
G36*
G01X1684771D02*
X1687591D01*
G02X1687794Y1481305I0J-203D01*
G01Y1480683D01*
G03X1687844Y1480551I200J0D01*
G02Y1477639I-1664J-1456D01*
G03X1687794Y1477507I150J-132D01*
G01Y1475565D01*
G03X1687844Y1475433I200J0D01*
G02Y1472521I-1664J-1456D01*
G03X1687794Y1472389I150J-132D01*
G01Y1471767D01*
G02X1687591Y1471564I-203J0D01*
G01X1684771D01*
G02X1684568Y1471767I0J203D01*
G01Y1472389D01*
G03X1684518Y1472521I-200J0D01*
G02Y1475433I1664J1456D01*
G03X1684568Y1475565I-150J132D01*
G01Y1477507D01*
G03X1684518Y1477639I-200J0D01*
G02Y1480551I1664J1456D01*
G03X1684568Y1480683I-150J132D01*
G01Y1481305D01*
G02X1684771Y1481508I203J0D01*
G37*
G36*
G01X1702093D02*
X1704913D01*
G02X1705116Y1481305I0J-203D01*
G01Y1480683D01*
G03X1705166Y1480551I200J0D01*
G02Y1477639I-1664J-1456D01*
G03X1705116Y1477507I150J-132D01*
G01Y1475565D01*
G03X1705166Y1475433I200J0D01*
G02Y1472521I-1664J-1456D01*
G03X1705116Y1472389I150J-132D01*
G01Y1471767D01*
G02X1704913Y1471564I-203J0D01*
G01X1702093D01*
G02X1701890Y1471767I0J203D01*
G01Y1472389D01*
G03X1701840Y1472521I-200J0D01*
G02Y1475433I1664J1456D01*
G03X1701890Y1475565I-150J132D01*
G01Y1477507D01*
G03X1701840Y1477639I-200J0D01*
G02Y1480551I1664J1456D01*
G03X1701890Y1480683I-150J132D01*
G01Y1481305D01*
G02X1702093Y1481508I203J0D01*
G37*
G36*
G01X134456Y1485838D02*
X137276D01*
G02X137478Y1485635I-1J-203D01*
G01Y1485016D01*
G03X137528Y1484884I200J0D01*
G02Y1481968I-1661J-1458D01*
G03X137478Y1481836I150J-132D01*
G01Y1479898D01*
G03X137528Y1479766I200J0D01*
G02Y1476850I-1661J-1458D01*
G03X137478Y1476718I150J-132D01*
G01Y1476097D01*
G02X137276Y1475894I-202J-1D01*
G01X134456D01*
G02X134254Y1476097I1J203D01*
G01Y1476718D01*
G03X134204Y1476850I-200J0D01*
G02Y1479766I1661J1458D01*
G03X134254Y1479898I-150J132D01*
G01Y1481836D01*
G03X134204Y1481968I-200J0D01*
G02Y1484884I1661J1458D01*
G03X134254Y1485016I-150J132D01*
G01Y1485635D01*
G02X134456Y1485838I202J1D01*
G37*
G36*
G01X151779D02*
X154599D01*
G02X154802Y1485635I0J-203D01*
G01Y1485014D01*
G03X154852Y1484882I200J0D01*
G02Y1481970I-1664J-1456D01*
G03X154802Y1481838I150J-132D01*
G01Y1479896D01*
G03X154852Y1479764I200J0D01*
G02Y1476852I-1664J-1456D01*
G03X154802Y1476720I150J-132D01*
G01Y1476097D01*
G02X154599Y1475894I-203J0D01*
G01X151779D01*
G02X151576Y1476097I0J203D01*
G01Y1476720D01*
G03X151526Y1476852I-200J0D01*
G02Y1479764I1664J1456D01*
G03X151576Y1479896I-150J132D01*
G01Y1481838D01*
G03X151526Y1481970I-200J0D01*
G02Y1484882I1664J1456D01*
G03X151576Y1485014I-150J132D01*
G01Y1485635D01*
G02X151779Y1485838I203J0D01*
G37*
G36*
G01X169102D02*
X171922D01*
G02X172124Y1485635I-1J-203D01*
G01Y1485016D01*
G03X172174Y1484884I200J0D01*
G02Y1481968I-1661J-1458D01*
G03X172124Y1481836I150J-132D01*
G01Y1479898D01*
G03X172174Y1479766I200J0D01*
G02Y1476850I-1661J-1458D01*
G03X172124Y1476718I150J-132D01*
G01Y1476097D01*
G02X171922Y1475894I-202J-1D01*
G01X169102D01*
G02X168900Y1476097I1J203D01*
G01Y1476718D01*
G03X168850Y1476850I-200J0D01*
G02Y1479766I1661J1458D01*
G03X168900Y1479898I-150J132D01*
G01Y1481836D01*
G03X168850Y1481968I-200J0D01*
G02Y1484884I1661J1458D01*
G03X168900Y1485016I-150J132D01*
G01Y1485635D01*
G02X169102Y1485838I202J1D01*
G37*
G36*
G01X290361D02*
X293181D01*
G02X293384Y1485635I0J-203D01*
G01Y1485014D01*
G03X293434Y1484882I200J0D01*
G02Y1481970I-1664J-1456D01*
G03X293384Y1481838I150J-132D01*
G01Y1479896D01*
G03X293434Y1479764I200J0D01*
G02Y1476852I-1664J-1456D01*
G03X293384Y1476720I150J-132D01*
G01Y1476097D01*
G02X293181Y1475894I-203J0D01*
G01X290361D01*
G02X290158Y1476097I0J203D01*
G01Y1476720D01*
G03X290108Y1476852I-200J0D01*
G02Y1479764I1664J1456D01*
G03X290158Y1479896I-150J132D01*
G01Y1481838D01*
G03X290108Y1481970I-200J0D01*
G02Y1484882I1664J1456D01*
G03X290158Y1485014I-150J132D01*
G01Y1485635D01*
G02X290361Y1485838I203J0D01*
G37*
G36*
G01X463590D02*
X466410D01*
G02X466612Y1485635I-1J-203D01*
G01Y1485016D01*
G03X466662Y1484884I200J0D01*
G02Y1481968I-1661J-1458D01*
G03X466612Y1481836I150J-132D01*
G01Y1479898D01*
G03X466662Y1479766I200J0D01*
G02Y1476850I-1661J-1458D01*
G03X466612Y1476718I150J-132D01*
G01Y1476097D01*
G02X466410Y1475894I-202J-1D01*
G01X463590D01*
G02X463388Y1476097I1J203D01*
G01Y1476718D01*
G03X463338Y1476850I-200J0D01*
G02Y1479766I1661J1458D01*
G03X463388Y1479898I-150J132D01*
G01Y1481836D01*
G03X463338Y1481968I-200J0D01*
G02Y1484884I1661J1458D01*
G03X463388Y1485016I-150J132D01*
G01Y1485635D01*
G02X463590Y1485838I202J1D01*
G37*
G36*
G01X480913D02*
X483733D01*
G02X483936Y1485635I0J-203D01*
G01Y1485014D01*
G03X483986Y1484882I200J0D01*
G02Y1481970I-1664J-1456D01*
G03X483936Y1481838I150J-132D01*
G01Y1479896D01*
G03X483986Y1479764I200J0D01*
G02Y1476852I-1664J-1456D01*
G03X483936Y1476720I150J-132D01*
G01Y1476097D01*
G02X483733Y1475894I-203J0D01*
G01X480913D01*
G02X480710Y1476097I0J203D01*
G01Y1476720D01*
G03X480660Y1476852I-200J0D01*
G02Y1479764I1664J1456D01*
G03X480710Y1479896I-150J132D01*
G01Y1481838D01*
G03X480660Y1481970I-200J0D01*
G02Y1484882I1664J1456D01*
G03X480710Y1485014I-150J132D01*
G01Y1485635D01*
G02X480913Y1485838I203J0D01*
G37*
G36*
G01X498236D02*
X501056D01*
G02X501258Y1485635I-1J-203D01*
G01Y1485016D01*
G03X501308Y1484884I200J0D01*
G02Y1481968I-1661J-1458D01*
G03X501258Y1481836I150J-132D01*
G01Y1479898D01*
G03X501308Y1479766I200J0D01*
G02Y1476850I-1661J-1458D01*
G03X501258Y1476718I150J-132D01*
G01Y1476097D01*
G02X501056Y1475894I-202J-1D01*
G01X498236D01*
G02X498034Y1476097I1J203D01*
G01Y1476718D01*
G03X497984Y1476850I-200J0D01*
G02Y1479766I1661J1458D01*
G03X498034Y1479898I-150J132D01*
G01Y1481836D01*
G03X497984Y1481968I-200J0D01*
G02Y1484884I1661J1458D01*
G03X498034Y1485016I-150J132D01*
G01Y1485635D01*
G02X498236Y1485838I202J1D01*
G37*
G36*
G01X515559D02*
X518379D01*
G02X518582Y1485635I0J-203D01*
G01Y1485014D01*
G03X518632Y1484882I200J0D01*
G02Y1481970I-1664J-1456D01*
G03X518582Y1481838I150J-132D01*
G01Y1479896D01*
G03X518632Y1479764I200J0D01*
G02Y1476852I-1664J-1456D01*
G03X518582Y1476720I150J-132D01*
G01Y1476097D01*
G02X518379Y1475894I-203J0D01*
G01X515559D01*
G02X515356Y1476097I0J203D01*
G01Y1476720D01*
G03X515306Y1476852I-200J0D01*
G02Y1479764I1664J1456D01*
G03X515356Y1479896I-150J132D01*
G01Y1481838D01*
G03X515306Y1481970I-200J0D01*
G02Y1484882I1664J1456D01*
G03X515356Y1485014I-150J132D01*
G01Y1485635D01*
G02X515559Y1485838I203J0D01*
G37*
G36*
G01X654141D02*
X656961D01*
G02X657164Y1485635I0J-203D01*
G01Y1485014D01*
G03X657214Y1484882I200J0D01*
G02Y1481970I-1664J-1456D01*
G03X657164Y1481838I150J-132D01*
G01Y1479896D01*
G03X657214Y1479764I200J0D01*
G02Y1476852I-1664J-1456D01*
G03X657164Y1476720I150J-132D01*
G01Y1476097D01*
G02X656961Y1475894I-203J0D01*
G01X654141D01*
G02X653938Y1476097I0J203D01*
G01Y1476720D01*
G03X653888Y1476852I-200J0D01*
G02Y1479764I1664J1456D01*
G03X653938Y1479896I-150J132D01*
G01Y1481838D01*
G03X653888Y1481970I-200J0D01*
G02Y1484882I1664J1456D01*
G03X653938Y1485014I-150J132D01*
G01Y1485635D01*
G02X654141Y1485838I203J0D01*
G37*
G36*
G01X671464D02*
X674284D01*
G02X674486Y1485635I-1J-203D01*
G01Y1485016D01*
G03X674536Y1484884I200J0D01*
G02Y1481968I-1661J-1458D01*
G03X674486Y1481836I150J-132D01*
G01Y1479898D01*
G03X674536Y1479766I200J0D01*
G02Y1476850I-1661J-1458D01*
G03X674486Y1476718I150J-132D01*
G01Y1476097D01*
G02X674284Y1475894I-202J-1D01*
G01X671464D01*
G02X671262Y1476097I1J203D01*
G01Y1476718D01*
G03X671212Y1476850I-200J0D01*
G02Y1479766I1661J1458D01*
G03X671262Y1479898I-150J132D01*
G01Y1481836D01*
G03X671212Y1481968I-200J0D01*
G02Y1484884I1661J1458D01*
G03X671262Y1485016I-150J132D01*
G01Y1485635D01*
G02X671464Y1485838I202J1D01*
G37*
G36*
G01X688787D02*
X691607D01*
G02X691810Y1485635I0J-203D01*
G01Y1485014D01*
G03X691860Y1484882I200J0D01*
G02Y1481970I-1664J-1456D01*
G03X691810Y1481838I150J-132D01*
G01Y1479896D01*
G03X691860Y1479764I200J0D01*
G02Y1476852I-1664J-1456D01*
G03X691810Y1476720I150J-132D01*
G01Y1476097D01*
G02X691607Y1475894I-203J0D01*
G01X688787D01*
G02X688584Y1476097I0J203D01*
G01Y1476720D01*
G03X688534Y1476852I-200J0D01*
G02Y1479764I1664J1456D01*
G03X688584Y1479896I-150J132D01*
G01Y1481838D01*
G03X688534Y1481970I-200J0D01*
G02Y1484882I1664J1456D01*
G03X688584Y1485014I-150J132D01*
G01Y1485635D01*
G02X688787Y1485838I203J0D01*
G37*
G36*
G01X1173747D02*
X1176567D01*
G02X1176770Y1485635I0J-203D01*
G01Y1485014D01*
G03X1176820Y1484882I200J0D01*
G02Y1481970I-1664J-1456D01*
G03X1176770Y1481838I150J-132D01*
G01Y1479896D01*
G03X1176820Y1479764I200J0D01*
G02Y1476852I-1664J-1456D01*
G03X1176770Y1476720I150J-132D01*
G01Y1476097D01*
G02X1176567Y1475894I-203J0D01*
G01X1173747D01*
G02X1173544Y1476097I0J203D01*
G01Y1476720D01*
G03X1173494Y1476852I-200J0D01*
G02Y1479764I1664J1456D01*
G03X1173544Y1479896I-150J132D01*
G01Y1481838D01*
G03X1173494Y1481970I-200J0D01*
G02Y1484882I1664J1456D01*
G03X1173544Y1485014I-150J132D01*
G01Y1485635D01*
G02X1173747Y1485838I203J0D01*
G37*
G36*
G01X1191070D02*
X1193890D01*
G02X1194092Y1485635I-1J-203D01*
G01Y1485016D01*
G03X1194142Y1484884I200J0D01*
G02Y1481968I-1661J-1458D01*
G03X1194092Y1481836I150J-132D01*
G01Y1479898D01*
G03X1194142Y1479766I200J0D01*
G02Y1476850I-1661J-1458D01*
G03X1194092Y1476718I150J-132D01*
G01Y1476097D01*
G02X1193890Y1475894I-202J-1D01*
G01X1191070D01*
G02X1190868Y1476097I1J203D01*
G01Y1476718D01*
G03X1190818Y1476850I-200J0D01*
G02Y1479766I1661J1458D01*
G03X1190868Y1479898I-150J132D01*
G01Y1481836D01*
G03X1190818Y1481968I-200J0D01*
G02Y1484884I1661J1458D01*
G03X1190868Y1485016I-150J132D01*
G01Y1485635D01*
G02X1191070Y1485838I202J1D01*
G37*
G36*
G01X1312330D02*
X1315150D01*
G02X1315352Y1485635I-1J-203D01*
G01Y1485016D01*
G03X1315402Y1484884I200J0D01*
G02Y1481968I-1661J-1458D01*
G03X1315352Y1481836I150J-132D01*
G01Y1479898D01*
G03X1315402Y1479766I200J0D01*
G02Y1476850I-1661J-1458D01*
G03X1315352Y1476718I150J-132D01*
G01Y1476097D01*
G02X1315150Y1475894I-202J-1D01*
G01X1312330D01*
G02X1312128Y1476097I1J203D01*
G01Y1476718D01*
G03X1312078Y1476850I-200J0D01*
G02Y1479766I1661J1458D01*
G03X1312128Y1479898I-150J132D01*
G01Y1481836D01*
G03X1312078Y1481968I-200J0D01*
G02Y1484884I1661J1458D01*
G03X1312128Y1485016I-150J132D01*
G01Y1485635D01*
G02X1312330Y1485838I202J1D01*
G37*
G36*
G01X1329653D02*
X1332473D01*
G02X1332676Y1485635I0J-203D01*
G01Y1485014D01*
G03X1332726Y1484882I200J0D01*
G02Y1481970I-1664J-1456D01*
G03X1332676Y1481838I150J-132D01*
G01Y1479896D01*
G03X1332726Y1479764I200J0D01*
G02Y1476852I-1664J-1456D01*
G03X1332676Y1476720I150J-132D01*
G01Y1476097D01*
G02X1332473Y1475894I-203J0D01*
G01X1329653D01*
G02X1329450Y1476097I0J203D01*
G01Y1476720D01*
G03X1329400Y1476852I-200J0D01*
G02Y1479764I1664J1456D01*
G03X1329450Y1479896I-150J132D01*
G01Y1481838D01*
G03X1329400Y1481970I-200J0D01*
G02Y1484882I1664J1456D01*
G03X1329450Y1485014I-150J132D01*
G01Y1485635D01*
G02X1329653Y1485838I203J0D01*
G37*
G36*
G01X1346976D02*
X1349796D01*
G02X1349998Y1485635I-1J-203D01*
G01Y1485016D01*
G03X1350048Y1484884I200J0D01*
G02Y1481968I-1661J-1458D01*
G03X1349998Y1481836I150J-132D01*
G01Y1479898D01*
G03X1350048Y1479766I200J0D01*
G02Y1476850I-1661J-1458D01*
G03X1349998Y1476718I150J-132D01*
G01Y1476097D01*
G02X1349796Y1475894I-202J-1D01*
G01X1346976D01*
G02X1346774Y1476097I1J203D01*
G01Y1476718D01*
G03X1346724Y1476850I-200J0D01*
G02Y1479766I1661J1458D01*
G03X1346774Y1479898I-150J132D01*
G01Y1481836D01*
G03X1346724Y1481968I-200J0D01*
G02Y1484884I1661J1458D01*
G03X1346774Y1485016I-150J132D01*
G01Y1485635D01*
G02X1346976Y1485838I202J1D01*
G37*
G36*
G01X1364299D02*
X1367119D01*
G02X1367322Y1485635I0J-203D01*
G01Y1485014D01*
G03X1367372Y1484882I200J0D01*
G02Y1481970I-1664J-1456D01*
G03X1367322Y1481838I150J-132D01*
G01Y1479896D01*
G03X1367372Y1479764I200J0D01*
G02Y1476852I-1664J-1456D01*
G03X1367322Y1476720I150J-132D01*
G01Y1476097D01*
G02X1367119Y1475894I-203J0D01*
G01X1364299D01*
G02X1364096Y1476097I0J203D01*
G01Y1476720D01*
G03X1364046Y1476852I-200J0D01*
G02Y1479764I1664J1456D01*
G03X1364096Y1479896I-150J132D01*
G01Y1481838D01*
G03X1364046Y1481970I-200J0D01*
G02Y1484882I1664J1456D01*
G03X1364096Y1485014I-150J132D01*
G01Y1485635D01*
G02X1364299Y1485838I203J0D01*
G37*
G36*
G01X1485558D02*
X1488378D01*
G02X1488580Y1485635I-1J-203D01*
G01Y1485016D01*
G03X1488630Y1484884I200J0D01*
G02Y1481968I-1661J-1458D01*
G03X1488580Y1481836I150J-132D01*
G01Y1479898D01*
G03X1488630Y1479766I200J0D01*
G02Y1476850I-1661J-1458D01*
G03X1488580Y1476718I150J-132D01*
G01Y1476097D01*
G02X1488378Y1475894I-202J-1D01*
G01X1485558D01*
G02X1485356Y1476097I1J203D01*
G01Y1476718D01*
G03X1485306Y1476850I-200J0D01*
G02Y1479766I1661J1458D01*
G03X1485356Y1479898I-150J132D01*
G01Y1481836D01*
G03X1485306Y1481968I-200J0D01*
G02Y1484884I1661J1458D01*
G03X1485356Y1485016I-150J132D01*
G01Y1485635D01*
G02X1485558Y1485838I202J1D01*
G37*
G36*
G01X1502881D02*
X1505701D01*
G02X1505904Y1485635I0J-203D01*
G01Y1485014D01*
G03X1505954Y1484882I200J0D01*
G02Y1481970I-1664J-1456D01*
G03X1505904Y1481838I150J-132D01*
G01Y1479896D01*
G03X1505954Y1479764I200J0D01*
G02Y1476852I-1664J-1456D01*
G03X1505904Y1476720I150J-132D01*
G01Y1476097D01*
G02X1505701Y1475894I-203J0D01*
G01X1502881D01*
G02X1502678Y1476097I0J203D01*
G01Y1476720D01*
G03X1502628Y1476852I-200J0D01*
G02Y1479764I1664J1456D01*
G03X1502678Y1479896I-150J132D01*
G01Y1481838D01*
G03X1502628Y1481970I-200J0D01*
G02Y1484882I1664J1456D01*
G03X1502678Y1485014I-150J132D01*
G01Y1485635D01*
G02X1502881Y1485838I203J0D01*
G37*
G36*
G01X1520204D02*
X1523024D01*
G02X1523226Y1485635I-1J-203D01*
G01Y1485016D01*
G03X1523276Y1484884I200J0D01*
G02Y1481968I-1661J-1458D01*
G03X1523226Y1481836I150J-132D01*
G01Y1479898D01*
G03X1523276Y1479766I200J0D01*
G02Y1476850I-1661J-1458D01*
G03X1523226Y1476718I150J-132D01*
G01Y1476097D01*
G02X1523024Y1475894I-202J-1D01*
G01X1520204D01*
G02X1520002Y1476097I1J203D01*
G01Y1476718D01*
G03X1519952Y1476850I-200J0D01*
G02Y1479766I1661J1458D01*
G03X1520002Y1479898I-150J132D01*
G01Y1481836D01*
G03X1519952Y1481968I-200J0D01*
G02Y1484884I1661J1458D01*
G03X1520002Y1485016I-150J132D01*
G01Y1485635D01*
G02X1520204Y1485838I202J1D01*
G37*
G36*
G01X1537527D02*
X1540347D01*
G02X1540550Y1485635I0J-203D01*
G01Y1485014D01*
G03X1540600Y1484882I200J0D01*
G02Y1481970I-1664J-1456D01*
G03X1540550Y1481838I150J-132D01*
G01Y1479896D01*
G03X1540600Y1479764I200J0D01*
G02Y1476852I-1664J-1456D01*
G03X1540550Y1476720I150J-132D01*
G01Y1476097D01*
G02X1540347Y1475894I-203J0D01*
G01X1537527D01*
G02X1537324Y1476097I0J203D01*
G01Y1476720D01*
G03X1537274Y1476852I-200J0D01*
G02Y1479764I1664J1456D01*
G03X1537324Y1479896I-150J132D01*
G01Y1481838D01*
G03X1537274Y1481970I-200J0D01*
G02Y1484882I1664J1456D01*
G03X1537324Y1485014I-150J132D01*
G01Y1485635D01*
G02X1537527Y1485838I203J0D01*
G37*
G36*
G01X1693432D02*
X1696252D01*
G02X1696454Y1485635I-1J-203D01*
G01Y1485016D01*
G03X1696504Y1484884I200J0D01*
G02Y1481968I-1661J-1458D01*
G03X1696454Y1481836I150J-132D01*
G01Y1479898D01*
G03X1696504Y1479766I200J0D01*
G02Y1476850I-1661J-1458D01*
G03X1696454Y1476718I150J-132D01*
G01Y1476097D01*
G02X1696252Y1475894I-202J-1D01*
G01X1693432D01*
G02X1693230Y1476097I1J203D01*
G01Y1476718D01*
G03X1693180Y1476850I-200J0D01*
G02Y1479766I1661J1458D01*
G03X1693230Y1479898I-150J132D01*
G01Y1481836D01*
G03X1693180Y1481968I-200J0D01*
G02Y1484884I1661J1458D01*
G03X1693230Y1485016I-150J132D01*
G01Y1485635D01*
G02X1693432Y1485838I202J1D01*
G37*
G36*
G01X1710755D02*
X1713575D01*
G02X1713778Y1485635I0J-203D01*
G01Y1485014D01*
G03X1713828Y1484882I200J0D01*
G02Y1481970I-1664J-1456D01*
G03X1713778Y1481838I150J-132D01*
G01Y1479896D01*
G03X1713828Y1479764I200J0D01*
G02Y1476852I-1664J-1456D01*
G03X1713778Y1476720I150J-132D01*
G01Y1476097D01*
G02X1713575Y1475894I-203J0D01*
G01X1710755D01*
G02X1710552Y1476097I0J203D01*
G01Y1476720D01*
G03X1710502Y1476852I-200J0D01*
G02Y1479764I1664J1456D01*
G03X1710552Y1479896I-150J132D01*
G01Y1481838D01*
G03X1710502Y1481970I-200J0D01*
G02Y1484882I1664J1456D01*
G03X1710552Y1485014I-150J132D01*
G01Y1485635D01*
G02X1710755Y1485838I203J0D01*
G37*
G36*
G01X186425D02*
X189245D01*
G02X189448Y1485636I1J-202D01*
G01Y1485014D01*
G03X189498Y1484882I200J0D01*
G02Y1481970I-1664J-1456D01*
G03X189448Y1481838I150J-132D01*
G01Y1479896D01*
G03X189498Y1479764I200J0D01*
G02Y1476852I-1664J-1456D01*
G03X189448Y1476720I150J-132D01*
G01Y1476098D01*
G02X189245Y1475896I-203J1D01*
G01X186425D01*
G02X186222Y1476098I-1J202D01*
G01Y1476720D01*
G03X186172Y1476852I-200J0D01*
G02Y1479764I1664J1456D01*
G03X186222Y1479896I-150J132D01*
G01Y1481838D01*
G03X186172Y1481970I-200J0D01*
G02Y1484882I1664J1456D01*
G03X186222Y1485014I-150J132D01*
G01Y1485636D01*
G02X186425Y1485838I203J-1D01*
G37*
G36*
G01X125795Y1496862D02*
X128615D01*
G02X128818Y1496659I0J-203D01*
G01Y1496037D01*
G03X128868Y1495905I200J0D01*
G02Y1492993I-1664J-1456D01*
G03X128818Y1492861I150J-132D01*
G01Y1490919D01*
G03X128868Y1490787I200J0D01*
G02Y1487875I-1664J-1456D01*
G03X128818Y1487743I150J-132D01*
G01Y1487121D01*
G02X128615Y1486918I-203J0D01*
G01X125795D01*
G02X125592Y1487121I0J203D01*
G01Y1487743D01*
G03X125542Y1487875I-200J0D01*
G02Y1490787I1664J1456D01*
G03X125592Y1490919I-150J132D01*
G01Y1492861D01*
G03X125542Y1492993I-200J0D01*
G02Y1495905I1664J1456D01*
G03X125592Y1496037I-150J132D01*
G01Y1496659D01*
G02X125795Y1496862I203J0D01*
G37*
G36*
G01X143118D02*
X145938D01*
G02X146140Y1496659I-1J-203D01*
G01Y1496039D01*
G03X146190Y1495907I200J0D01*
G02Y1492991I-1661J-1458D01*
G03X146140Y1492859I150J-132D01*
G01Y1490921D01*
G03X146190Y1490789I200J0D01*
G02Y1487873I-1661J-1458D01*
G03X146140Y1487741I150J-132D01*
G01Y1487121D01*
G02X145938Y1486918I-202J-1D01*
G01X143118D01*
G02X142916Y1487121I1J203D01*
G01Y1487741D01*
G03X142866Y1487873I-200J0D01*
G02Y1490789I1661J1458D01*
G03X142916Y1490921I-150J132D01*
G01Y1492859D01*
G03X142866Y1492991I-200J0D01*
G02Y1495907I1661J1458D01*
G03X142916Y1496039I-150J132D01*
G01Y1496659D01*
G02X143118Y1496862I202J1D01*
G37*
G36*
G01X160440D02*
X163260D01*
G02X163462Y1496659I-1J-203D01*
G01Y1496039D01*
G03X163512Y1495907I200J0D01*
G02Y1492991I-1661J-1458D01*
G03X163462Y1492859I150J-132D01*
G01Y1490921D01*
G03X163512Y1490789I200J0D01*
G02Y1487873I-1661J-1458D01*
G03X163462Y1487741I150J-132D01*
G01Y1487121D01*
G02X163260Y1486918I-202J-1D01*
G01X160440D01*
G02X160238Y1487121I1J203D01*
G01Y1487741D01*
G03X160188Y1487873I-200J0D01*
G02Y1490789I1661J1458D01*
G03X160238Y1490921I-150J132D01*
G01Y1492859D01*
G03X160188Y1492991I-200J0D01*
G02Y1495907I1661J1458D01*
G03X160238Y1496039I-150J132D01*
G01Y1496659D01*
G02X160440Y1496862I202J1D01*
G37*
G36*
G01X281700D02*
X284520D01*
G02X284722Y1496659I-1J-203D01*
G01Y1496039D01*
G03X284772Y1495907I200J0D01*
G02Y1492991I-1661J-1458D01*
G03X284722Y1492859I150J-132D01*
G01Y1490921D01*
G03X284772Y1490789I200J0D01*
G02Y1487873I-1661J-1458D01*
G03X284722Y1487741I150J-132D01*
G01Y1487121D01*
G02X284520Y1486918I-202J-1D01*
G01X281700D01*
G02X281498Y1487121I1J203D01*
G01Y1487741D01*
G03X281448Y1487873I-200J0D01*
G02Y1490789I1661J1458D01*
G03X281498Y1490921I-150J132D01*
G01Y1492859D01*
G03X281448Y1492991I-200J0D01*
G02Y1495907I1661J1458D01*
G03X281498Y1496039I-150J132D01*
G01Y1496659D01*
G02X281700Y1496862I202J1D01*
G37*
G36*
G01X299023D02*
X301843D01*
G02X302046Y1496659I0J-203D01*
G01Y1496037D01*
G03X302096Y1495905I200J0D01*
G02Y1492993I-1664J-1456D01*
G03X302046Y1492861I150J-132D01*
G01Y1490919D01*
G03X302096Y1490787I200J0D01*
G02Y1487875I-1664J-1456D01*
G03X302046Y1487743I150J-132D01*
G01Y1487121D01*
G02X301843Y1486918I-203J0D01*
G01X299023D01*
G02X298820Y1487121I0J203D01*
G01Y1487743D01*
G03X298770Y1487875I-200J0D01*
G02Y1490787I1664J1456D01*
G03X298820Y1490919I-150J132D01*
G01Y1492861D01*
G03X298770Y1492993I-200J0D01*
G02Y1495905I1664J1456D01*
G03X298820Y1496037I-150J132D01*
G01Y1496659D01*
G02X299023Y1496862I203J0D01*
G37*
G36*
G01X454929D02*
X457749D01*
G02X457952Y1496659I0J-203D01*
G01Y1496037D01*
G03X458002Y1495905I200J0D01*
G02Y1492993I-1664J-1456D01*
G03X457952Y1492861I150J-132D01*
G01Y1490919D01*
G03X458002Y1490787I200J0D01*
G02Y1487875I-1664J-1456D01*
G03X457952Y1487743I150J-132D01*
G01Y1487121D01*
G02X457749Y1486918I-203J0D01*
G01X454929D01*
G02X454726Y1487121I0J203D01*
G01Y1487743D01*
G03X454676Y1487875I-200J0D01*
G02Y1490787I1664J1456D01*
G03X454726Y1490919I-150J132D01*
G01Y1492861D01*
G03X454676Y1492993I-200J0D01*
G02Y1495905I1664J1456D01*
G03X454726Y1496037I-150J132D01*
G01Y1496659D01*
G02X454929Y1496862I203J0D01*
G37*
G36*
G01X472252D02*
X475072D01*
G02X475274Y1496659I-1J-203D01*
G01Y1496039D01*
G03X475324Y1495907I200J0D01*
G02Y1492991I-1661J-1458D01*
G03X475274Y1492859I150J-132D01*
G01Y1490921D01*
G03X475324Y1490789I200J0D01*
G02Y1487873I-1661J-1458D01*
G03X475274Y1487741I150J-132D01*
G01Y1487121D01*
G02X475072Y1486918I-202J-1D01*
G01X472252D01*
G02X472050Y1487121I1J203D01*
G01Y1487741D01*
G03X472000Y1487873I-200J0D01*
G02Y1490789I1661J1458D01*
G03X472050Y1490921I-150J132D01*
G01Y1492859D01*
G03X472000Y1492991I-200J0D01*
G02Y1495907I1661J1458D01*
G03X472050Y1496039I-150J132D01*
G01Y1496659D01*
G02X472252Y1496862I202J1D01*
G37*
G36*
G01X489575D02*
X492395D01*
G02X492598Y1496659I0J-203D01*
G01Y1496037D01*
G03X492648Y1495905I200J0D01*
G02Y1492993I-1664J-1456D01*
G03X492598Y1492861I150J-132D01*
G01Y1490919D01*
G03X492648Y1490787I200J0D01*
G02Y1487875I-1664J-1456D01*
G03X492598Y1487743I150J-132D01*
G01Y1487121D01*
G02X492395Y1486918I-203J0D01*
G01X489575D01*
G02X489372Y1487121I0J203D01*
G01Y1487743D01*
G03X489322Y1487875I-200J0D01*
G02Y1490787I1664J1456D01*
G03X489372Y1490919I-150J132D01*
G01Y1492861D01*
G03X489322Y1492993I-200J0D01*
G02Y1495905I1664J1456D01*
G03X489372Y1496037I-150J132D01*
G01Y1496659D01*
G02X489575Y1496862I203J0D01*
G37*
G36*
G01X506897D02*
X509717D01*
G02X509920Y1496659I0J-203D01*
G01Y1496037D01*
G03X509970Y1495905I200J0D01*
G02Y1492993I-1664J-1456D01*
G03X509920Y1492861I150J-132D01*
G01Y1490919D01*
G03X509970Y1490787I200J0D01*
G02Y1487875I-1664J-1456D01*
G03X509920Y1487743I150J-132D01*
G01Y1487121D01*
G02X509717Y1486918I-203J0D01*
G01X506897D01*
G02X506694Y1487121I0J203D01*
G01Y1487743D01*
G03X506644Y1487875I-200J0D01*
G02Y1490787I1664J1456D01*
G03X506694Y1490919I-150J132D01*
G01Y1492861D01*
G03X506644Y1492993I-200J0D01*
G02Y1495905I1664J1456D01*
G03X506694Y1496037I-150J132D01*
G01Y1496659D01*
G02X506897Y1496862I203J0D01*
G37*
G36*
G01X645480D02*
X648300D01*
G02X648502Y1496659I-1J-203D01*
G01Y1496039D01*
G03X648552Y1495907I200J0D01*
G02Y1492991I-1661J-1458D01*
G03X648502Y1492859I150J-132D01*
G01Y1490921D01*
G03X648552Y1490789I200J0D01*
G02Y1487873I-1661J-1458D01*
G03X648502Y1487741I150J-132D01*
G01Y1487121D01*
G02X648300Y1486918I-202J-1D01*
G01X645480D01*
G02X645278Y1487121I1J203D01*
G01Y1487741D01*
G03X645228Y1487873I-200J0D01*
G02Y1490789I1661J1458D01*
G03X645278Y1490921I-150J132D01*
G01Y1492859D01*
G03X645228Y1492991I-200J0D01*
G02Y1495907I1661J1458D01*
G03X645278Y1496039I-150J132D01*
G01Y1496659D01*
G02X645480Y1496862I202J1D01*
G37*
G36*
G01X662803D02*
X665623D01*
G02X665826Y1496659I0J-203D01*
G01Y1496037D01*
G03X665876Y1495905I200J0D01*
G02Y1492993I-1664J-1456D01*
G03X665826Y1492861I150J-132D01*
G01Y1490919D01*
G03X665876Y1490787I200J0D01*
G02Y1487875I-1664J-1456D01*
G03X665826Y1487743I150J-132D01*
G01Y1487121D01*
G02X665623Y1486918I-203J0D01*
G01X662803D01*
G02X662600Y1487121I0J203D01*
G01Y1487743D01*
G03X662550Y1487875I-200J0D01*
G02Y1490787I1664J1456D01*
G03X662600Y1490919I-150J132D01*
G01Y1492861D01*
G03X662550Y1492993I-200J0D01*
G02Y1495905I1664J1456D01*
G03X662600Y1496037I-150J132D01*
G01Y1496659D01*
G02X662803Y1496862I203J0D01*
G37*
G36*
G01X680125D02*
X682945D01*
G02X683148Y1496659I0J-203D01*
G01Y1496037D01*
G03X683198Y1495905I200J0D01*
G02Y1492993I-1664J-1456D01*
G03X683148Y1492861I150J-132D01*
G01Y1490919D01*
G03X683198Y1490787I200J0D01*
G02Y1487875I-1664J-1456D01*
G03X683148Y1487743I150J-132D01*
G01Y1487121D01*
G02X682945Y1486918I-203J0D01*
G01X680125D01*
G02X679922Y1487121I0J203D01*
G01Y1487743D01*
G03X679872Y1487875I-200J0D01*
G02Y1490787I1664J1456D01*
G03X679922Y1490919I-150J132D01*
G01Y1492861D01*
G03X679872Y1492993I-200J0D01*
G02Y1495905I1664J1456D01*
G03X679922Y1496037I-150J132D01*
G01Y1496659D01*
G02X680125Y1496862I203J0D01*
G37*
G36*
G01X1165086D02*
X1167906D01*
G02X1168108Y1496659I-1J-203D01*
G01Y1496039D01*
G03X1168158Y1495907I200J0D01*
G02Y1492991I-1661J-1458D01*
G03X1168108Y1492859I150J-132D01*
G01Y1490921D01*
G03X1168158Y1490789I200J0D01*
G02Y1487873I-1661J-1458D01*
G03X1168108Y1487741I150J-132D01*
G01Y1487121D01*
G02X1167906Y1486918I-202J-1D01*
G01X1165086D01*
G02X1164884Y1487121I1J203D01*
G01Y1487741D01*
G03X1164834Y1487873I-200J0D01*
G02Y1490789I1661J1458D01*
G03X1164884Y1490921I-150J132D01*
G01Y1492859D01*
G03X1164834Y1492991I-200J0D01*
G02Y1495907I1661J1458D01*
G03X1164884Y1496039I-150J132D01*
G01Y1496659D01*
G02X1165086Y1496862I202J1D01*
G37*
G36*
G01X1182408D02*
X1185228D01*
G02X1185430Y1496659I-1J-203D01*
G01Y1496039D01*
G03X1185480Y1495907I200J0D01*
G02Y1492991I-1661J-1458D01*
G03X1185430Y1492859I150J-132D01*
G01Y1490921D01*
G03X1185480Y1490789I200J0D01*
G02Y1487873I-1661J-1458D01*
G03X1185430Y1487741I150J-132D01*
G01Y1487121D01*
G02X1185228Y1486918I-202J-1D01*
G01X1182408D01*
G02X1182206Y1487121I1J203D01*
G01Y1487741D01*
G03X1182156Y1487873I-200J0D01*
G02Y1490789I1661J1458D01*
G03X1182206Y1490921I-150J132D01*
G01Y1492859D01*
G03X1182156Y1492991I-200J0D01*
G02Y1495907I1661J1458D01*
G03X1182206Y1496039I-150J132D01*
G01Y1496659D01*
G02X1182408Y1496862I202J1D01*
G37*
G36*
G01X1303669D02*
X1306489D01*
G02X1306692Y1496659I0J-203D01*
G01Y1496037D01*
G03X1306742Y1495905I200J0D01*
G02Y1492993I-1664J-1456D01*
G03X1306692Y1492861I150J-132D01*
G01Y1490919D01*
G03X1306742Y1490787I200J0D01*
G02Y1487875I-1664J-1456D01*
G03X1306692Y1487743I150J-132D01*
G01Y1487121D01*
G02X1306489Y1486918I-203J0D01*
G01X1303669D01*
G02X1303466Y1487121I0J203D01*
G01Y1487743D01*
G03X1303416Y1487875I-200J0D01*
G02Y1490787I1664J1456D01*
G03X1303466Y1490919I-150J132D01*
G01Y1492861D01*
G03X1303416Y1492993I-200J0D01*
G02Y1495905I1664J1456D01*
G03X1303466Y1496037I-150J132D01*
G01Y1496659D01*
G02X1303669Y1496862I203J0D01*
G37*
G36*
G01X1320992D02*
X1323812D01*
G02X1324014Y1496659I-1J-203D01*
G01Y1496039D01*
G03X1324064Y1495907I200J0D01*
G02Y1492991I-1661J-1458D01*
G03X1324014Y1492859I150J-132D01*
G01Y1490921D01*
G03X1324064Y1490789I200J0D01*
G02Y1487873I-1661J-1458D01*
G03X1324014Y1487741I150J-132D01*
G01Y1487121D01*
G02X1323812Y1486918I-202J-1D01*
G01X1320992D01*
G02X1320790Y1487121I1J203D01*
G01Y1487741D01*
G03X1320740Y1487873I-200J0D01*
G02Y1490789I1661J1458D01*
G03X1320790Y1490921I-150J132D01*
G01Y1492859D01*
G03X1320740Y1492991I-200J0D01*
G02Y1495907I1661J1458D01*
G03X1320790Y1496039I-150J132D01*
G01Y1496659D01*
G02X1320992Y1496862I202J1D01*
G37*
G36*
G01X1338315D02*
X1341135D01*
G02X1341338Y1496659I0J-203D01*
G01Y1496037D01*
G03X1341388Y1495905I200J0D01*
G02Y1492993I-1664J-1456D01*
G03X1341338Y1492861I150J-132D01*
G01Y1490919D01*
G03X1341388Y1490787I200J0D01*
G02Y1487875I-1664J-1456D01*
G03X1341338Y1487743I150J-132D01*
G01Y1487121D01*
G02X1341135Y1486918I-203J0D01*
G01X1338315D01*
G02X1338112Y1487121I0J203D01*
G01Y1487743D01*
G03X1338062Y1487875I-200J0D01*
G02Y1490787I1664J1456D01*
G03X1338112Y1490919I-150J132D01*
G01Y1492861D01*
G03X1338062Y1492993I-200J0D01*
G02Y1495905I1664J1456D01*
G03X1338112Y1496037I-150J132D01*
G01Y1496659D01*
G02X1338315Y1496862I203J0D01*
G37*
G36*
G01X1355637D02*
X1358457D01*
G02X1358660Y1496659I0J-203D01*
G01Y1496037D01*
G03X1358710Y1495905I200J0D01*
G02Y1492993I-1664J-1456D01*
G03X1358660Y1492861I150J-132D01*
G01Y1490919D01*
G03X1358710Y1490787I200J0D01*
G02Y1487875I-1664J-1456D01*
G03X1358660Y1487743I150J-132D01*
G01Y1487121D01*
G02X1358457Y1486918I-203J0D01*
G01X1355637D01*
G02X1355434Y1487121I0J203D01*
G01Y1487743D01*
G03X1355384Y1487875I-200J0D01*
G02Y1490787I1664J1456D01*
G03X1355434Y1490919I-150J132D01*
G01Y1492861D01*
G03X1355384Y1492993I-200J0D01*
G02Y1495905I1664J1456D01*
G03X1355434Y1496037I-150J132D01*
G01Y1496659D01*
G02X1355637Y1496862I203J0D01*
G37*
G36*
G01X1476897D02*
X1479717D01*
G02X1479920Y1496659I0J-203D01*
G01Y1496037D01*
G03X1479970Y1495905I200J0D01*
G02Y1492993I-1664J-1456D01*
G03X1479920Y1492861I150J-132D01*
G01Y1490919D01*
G03X1479970Y1490787I200J0D01*
G02Y1487875I-1664J-1456D01*
G03X1479920Y1487743I150J-132D01*
G01Y1487121D01*
G02X1479717Y1486918I-203J0D01*
G01X1476897D01*
G02X1476694Y1487121I0J203D01*
G01Y1487743D01*
G03X1476644Y1487875I-200J0D01*
G02Y1490787I1664J1456D01*
G03X1476694Y1490919I-150J132D01*
G01Y1492861D01*
G03X1476644Y1492993I-200J0D01*
G02Y1495905I1664J1456D01*
G03X1476694Y1496037I-150J132D01*
G01Y1496659D01*
G02X1476897Y1496862I203J0D01*
G37*
G36*
G01X1494220D02*
X1497040D01*
G02X1497242Y1496659I-1J-203D01*
G01Y1496039D01*
G03X1497292Y1495907I200J0D01*
G02Y1492991I-1661J-1458D01*
G03X1497242Y1492859I150J-132D01*
G01Y1490921D01*
G03X1497292Y1490789I200J0D01*
G02Y1487873I-1661J-1458D01*
G03X1497242Y1487741I150J-132D01*
G01Y1487121D01*
G02X1497040Y1486918I-202J-1D01*
G01X1494220D01*
G02X1494018Y1487121I1J203D01*
G01Y1487741D01*
G03X1493968Y1487873I-200J0D01*
G02Y1490789I1661J1458D01*
G03X1494018Y1490921I-150J132D01*
G01Y1492859D01*
G03X1493968Y1492991I-200J0D01*
G02Y1495907I1661J1458D01*
G03X1494018Y1496039I-150J132D01*
G01Y1496659D01*
G02X1494220Y1496862I202J1D01*
G37*
G36*
G01X1511543D02*
X1514363D01*
G02X1514566Y1496659I0J-203D01*
G01Y1496037D01*
G03X1514616Y1495905I200J0D01*
G02Y1492993I-1664J-1456D01*
G03X1514566Y1492861I150J-132D01*
G01Y1490919D01*
G03X1514616Y1490787I200J0D01*
G02Y1487875I-1664J-1456D01*
G03X1514566Y1487743I150J-132D01*
G01Y1487121D01*
G02X1514363Y1486918I-203J0D01*
G01X1511543D01*
G02X1511340Y1487121I0J203D01*
G01Y1487743D01*
G03X1511290Y1487875I-200J0D01*
G02Y1490787I1664J1456D01*
G03X1511340Y1490919I-150J132D01*
G01Y1492861D01*
G03X1511290Y1492993I-200J0D01*
G02Y1495905I1664J1456D01*
G03X1511340Y1496037I-150J132D01*
G01Y1496659D01*
G02X1511543Y1496862I203J0D01*
G37*
G36*
G01X1528865D02*
X1531685D01*
G02X1531888Y1496659I0J-203D01*
G01Y1496037D01*
G03X1531938Y1495905I200J0D01*
G02Y1492993I-1664J-1456D01*
G03X1531888Y1492861I150J-132D01*
G01Y1490919D01*
G03X1531938Y1490787I200J0D01*
G02Y1487875I-1664J-1456D01*
G03X1531888Y1487743I150J-132D01*
G01Y1487121D01*
G02X1531685Y1486918I-203J0D01*
G01X1528865D01*
G02X1528662Y1487121I0J203D01*
G01Y1487743D01*
G03X1528612Y1487875I-200J0D01*
G02Y1490787I1664J1456D01*
G03X1528662Y1490919I-150J132D01*
G01Y1492861D01*
G03X1528612Y1492993I-200J0D01*
G02Y1495905I1664J1456D01*
G03X1528662Y1496037I-150J132D01*
G01Y1496659D01*
G02X1528865Y1496862I203J0D01*
G37*
G36*
G01X1684771D02*
X1687591D01*
G02X1687794Y1496659I0J-203D01*
G01Y1496037D01*
G03X1687844Y1495905I200J0D01*
G02Y1492993I-1664J-1456D01*
G03X1687794Y1492861I150J-132D01*
G01Y1490919D01*
G03X1687844Y1490787I200J0D01*
G02Y1487875I-1664J-1456D01*
G03X1687794Y1487743I150J-132D01*
G01Y1487121D01*
G02X1687591Y1486918I-203J0D01*
G01X1684771D01*
G02X1684568Y1487121I0J203D01*
G01Y1487743D01*
G03X1684518Y1487875I-200J0D01*
G02Y1490787I1664J1456D01*
G03X1684568Y1490919I-150J132D01*
G01Y1492861D01*
G03X1684518Y1492993I-200J0D01*
G02Y1495905I1664J1456D01*
G03X1684568Y1496037I-150J132D01*
G01Y1496659D01*
G02X1684771Y1496862I203J0D01*
G37*
G36*
G01X1702093D02*
X1704913D01*
G02X1705116Y1496659I0J-203D01*
G01Y1496037D01*
G03X1705166Y1495905I200J0D01*
G02Y1492993I-1664J-1456D01*
G03X1705116Y1492861I150J-132D01*
G01Y1490919D01*
G03X1705166Y1490787I200J0D01*
G02Y1487875I-1664J-1456D01*
G03X1705116Y1487743I150J-132D01*
G01Y1487121D01*
G02X1704913Y1486918I-203J0D01*
G01X1702093D01*
G02X1701890Y1487121I0J203D01*
G01Y1487743D01*
G03X1701840Y1487875I-200J0D01*
G02Y1490787I1664J1456D01*
G03X1701890Y1490919I-150J132D01*
G01Y1492861D01*
G03X1701840Y1492993I-200J0D01*
G02Y1495905I1664J1456D01*
G03X1701890Y1496037I-150J132D01*
G01Y1496659D01*
G02X1702093Y1496862I203J0D01*
G37*
G36*
G01X134456Y1501192D02*
X137276D01*
G02X137478Y1500989I-1J-203D01*
G01Y1500370D01*
G03X137528Y1500238I200J0D01*
G02Y1497322I-1661J-1458D01*
G03X137478Y1497190I150J-132D01*
G01Y1495252D01*
G03X137528Y1495120I200J0D01*
G02Y1492204I-1661J-1458D01*
G03X137478Y1492072I150J-132D01*
G01Y1491451D01*
G02X137276Y1491248I-202J-1D01*
G01X134456D01*
G02X134254Y1491451I1J203D01*
G01Y1492072D01*
G03X134204Y1492204I-200J0D01*
G02Y1495120I1661J1458D01*
G03X134254Y1495252I-150J132D01*
G01Y1497190D01*
G03X134204Y1497322I-200J0D01*
G02Y1500238I1661J1458D01*
G03X134254Y1500370I-150J132D01*
G01Y1500989D01*
G02X134456Y1501192I202J1D01*
G37*
G36*
G01X151779D02*
X154599D01*
G02X154802Y1500989I0J-203D01*
G01Y1500368D01*
G03X154852Y1500236I200J0D01*
G02Y1497324I-1664J-1456D01*
G03X154802Y1497192I150J-132D01*
G01Y1495250D01*
G03X154852Y1495118I200J0D01*
G02Y1492206I-1664J-1456D01*
G03X154802Y1492074I150J-132D01*
G01Y1491451D01*
G02X154599Y1491248I-203J0D01*
G01X151779D01*
G02X151576Y1491451I0J203D01*
G01Y1492074D01*
G03X151526Y1492206I-200J0D01*
G02Y1495118I1664J1456D01*
G03X151576Y1495250I-150J132D01*
G01Y1497192D01*
G03X151526Y1497324I-200J0D01*
G02Y1500236I1664J1456D01*
G03X151576Y1500368I-150J132D01*
G01Y1500989D01*
G02X151779Y1501192I203J0D01*
G37*
G36*
G01X169102D02*
X171922D01*
G02X172124Y1500989I-1J-203D01*
G01Y1500370D01*
G03X172174Y1500238I200J0D01*
G02Y1497322I-1661J-1458D01*
G03X172124Y1497190I150J-132D01*
G01Y1495252D01*
G03X172174Y1495120I200J0D01*
G02Y1492204I-1661J-1458D01*
G03X172124Y1492072I150J-132D01*
G01Y1491451D01*
G02X171922Y1491248I-202J-1D01*
G01X169102D01*
G02X168900Y1491451I1J203D01*
G01Y1492072D01*
G03X168850Y1492204I-200J0D01*
G02Y1495120I1661J1458D01*
G03X168900Y1495252I-150J132D01*
G01Y1497190D01*
G03X168850Y1497322I-200J0D01*
G02Y1500238I1661J1458D01*
G03X168900Y1500370I-150J132D01*
G01Y1500989D01*
G02X169102Y1501192I202J1D01*
G37*
G36*
G01X290361D02*
X293181D01*
G02X293384Y1500989I0J-203D01*
G01Y1500368D01*
G03X293434Y1500236I200J0D01*
G02Y1497324I-1664J-1456D01*
G03X293384Y1497192I150J-132D01*
G01Y1495250D01*
G03X293434Y1495118I200J0D01*
G02Y1492206I-1664J-1456D01*
G03X293384Y1492074I150J-132D01*
G01Y1491451D01*
G02X293181Y1491248I-203J0D01*
G01X290361D01*
G02X290158Y1491451I0J203D01*
G01Y1492074D01*
G03X290108Y1492206I-200J0D01*
G02Y1495118I1664J1456D01*
G03X290158Y1495250I-150J132D01*
G01Y1497192D01*
G03X290108Y1497324I-200J0D01*
G02Y1500236I1664J1456D01*
G03X290158Y1500368I-150J132D01*
G01Y1500989D01*
G02X290361Y1501192I203J0D01*
G37*
G36*
G01X463590D02*
X466410D01*
G02X466612Y1500989I-1J-203D01*
G01Y1500370D01*
G03X466662Y1500238I200J0D01*
G02Y1497322I-1661J-1458D01*
G03X466612Y1497190I150J-132D01*
G01Y1495252D01*
G03X466662Y1495120I200J0D01*
G02Y1492204I-1661J-1458D01*
G03X466612Y1492072I150J-132D01*
G01Y1491451D01*
G02X466410Y1491248I-202J-1D01*
G01X463590D01*
G02X463388Y1491451I1J203D01*
G01Y1492072D01*
G03X463338Y1492204I-200J0D01*
G02Y1495120I1661J1458D01*
G03X463388Y1495252I-150J132D01*
G01Y1497190D01*
G03X463338Y1497322I-200J0D01*
G02Y1500238I1661J1458D01*
G03X463388Y1500370I-150J132D01*
G01Y1500989D01*
G02X463590Y1501192I202J1D01*
G37*
G36*
G01X480913D02*
X483733D01*
G02X483936Y1500989I0J-203D01*
G01Y1500368D01*
G03X483986Y1500236I200J0D01*
G02Y1497324I-1664J-1456D01*
G03X483936Y1497192I150J-132D01*
G01Y1495250D01*
G03X483986Y1495118I200J0D01*
G02Y1492206I-1664J-1456D01*
G03X483936Y1492074I150J-132D01*
G01Y1491451D01*
G02X483733Y1491248I-203J0D01*
G01X480913D01*
G02X480710Y1491451I0J203D01*
G01Y1492074D01*
G03X480660Y1492206I-200J0D01*
G02Y1495118I1664J1456D01*
G03X480710Y1495250I-150J132D01*
G01Y1497192D01*
G03X480660Y1497324I-200J0D01*
G02Y1500236I1664J1456D01*
G03X480710Y1500368I-150J132D01*
G01Y1500989D01*
G02X480913Y1501192I203J0D01*
G37*
G36*
G01X498236D02*
X501056D01*
G02X501258Y1500989I-1J-203D01*
G01Y1500370D01*
G03X501308Y1500238I200J0D01*
G02Y1497322I-1661J-1458D01*
G03X501258Y1497190I150J-132D01*
G01Y1495252D01*
G03X501308Y1495120I200J0D01*
G02Y1492204I-1661J-1458D01*
G03X501258Y1492072I150J-132D01*
G01Y1491451D01*
G02X501056Y1491248I-202J-1D01*
G01X498236D01*
G02X498034Y1491451I1J203D01*
G01Y1492072D01*
G03X497984Y1492204I-200J0D01*
G02Y1495120I1661J1458D01*
G03X498034Y1495252I-150J132D01*
G01Y1497190D01*
G03X497984Y1497322I-200J0D01*
G02Y1500238I1661J1458D01*
G03X498034Y1500370I-150J132D01*
G01Y1500989D01*
G02X498236Y1501192I202J1D01*
G37*
G36*
G01X515559D02*
X518379D01*
G02X518582Y1500989I0J-203D01*
G01Y1500368D01*
G03X518632Y1500236I200J0D01*
G02Y1497324I-1664J-1456D01*
G03X518582Y1497192I150J-132D01*
G01Y1495250D01*
G03X518632Y1495118I200J0D01*
G02Y1492206I-1664J-1456D01*
G03X518582Y1492074I150J-132D01*
G01Y1491451D01*
G02X518379Y1491248I-203J0D01*
G01X515559D01*
G02X515356Y1491451I0J203D01*
G01Y1492074D01*
G03X515306Y1492206I-200J0D01*
G02Y1495118I1664J1456D01*
G03X515356Y1495250I-150J132D01*
G01Y1497192D01*
G03X515306Y1497324I-200J0D01*
G02Y1500236I1664J1456D01*
G03X515356Y1500368I-150J132D01*
G01Y1500989D01*
G02X515559Y1501192I203J0D01*
G37*
G36*
G01X654141D02*
X656961D01*
G02X657164Y1500989I0J-203D01*
G01Y1500368D01*
G03X657214Y1500236I200J0D01*
G02Y1497324I-1664J-1456D01*
G03X657164Y1497192I150J-132D01*
G01Y1495250D01*
G03X657214Y1495118I200J0D01*
G02Y1492206I-1664J-1456D01*
G03X657164Y1492074I150J-132D01*
G01Y1491451D01*
G02X656961Y1491248I-203J0D01*
G01X654141D01*
G02X653938Y1491451I0J203D01*
G01Y1492074D01*
G03X653888Y1492206I-200J0D01*
G02Y1495118I1664J1456D01*
G03X653938Y1495250I-150J132D01*
G01Y1497192D01*
G03X653888Y1497324I-200J0D01*
G02Y1500236I1664J1456D01*
G03X653938Y1500368I-150J132D01*
G01Y1500989D01*
G02X654141Y1501192I203J0D01*
G37*
G36*
G01X671464D02*
X674284D01*
G02X674486Y1500989I-1J-203D01*
G01Y1500370D01*
G03X674536Y1500238I200J0D01*
G02Y1497322I-1661J-1458D01*
G03X674486Y1497190I150J-132D01*
G01Y1495252D01*
G03X674536Y1495120I200J0D01*
G02Y1492204I-1661J-1458D01*
G03X674486Y1492072I150J-132D01*
G01Y1491451D01*
G02X674284Y1491248I-202J-1D01*
G01X671464D01*
G02X671262Y1491451I1J203D01*
G01Y1492072D01*
G03X671212Y1492204I-200J0D01*
G02Y1495120I1661J1458D01*
G03X671262Y1495252I-150J132D01*
G01Y1497190D01*
G03X671212Y1497322I-200J0D01*
G02Y1500238I1661J1458D01*
G03X671262Y1500370I-150J132D01*
G01Y1500989D01*
G02X671464Y1501192I202J1D01*
G37*
G36*
G01X688787D02*
X691607D01*
G02X691810Y1500989I0J-203D01*
G01Y1500368D01*
G03X691860Y1500236I200J0D01*
G02Y1497324I-1664J-1456D01*
G03X691810Y1497192I150J-132D01*
G01Y1495250D01*
G03X691860Y1495118I200J0D01*
G02Y1492206I-1664J-1456D01*
G03X691810Y1492074I150J-132D01*
G01Y1491451D01*
G02X691607Y1491248I-203J0D01*
G01X688787D01*
G02X688584Y1491451I0J203D01*
G01Y1492074D01*
G03X688534Y1492206I-200J0D01*
G02Y1495118I1664J1456D01*
G03X688584Y1495250I-150J132D01*
G01Y1497192D01*
G03X688534Y1497324I-200J0D01*
G02Y1500236I1664J1456D01*
G03X688584Y1500368I-150J132D01*
G01Y1500989D01*
G02X688787Y1501192I203J0D01*
G37*
G36*
G01X1173747D02*
X1176567D01*
G02X1176770Y1500989I0J-203D01*
G01Y1500368D01*
G03X1176820Y1500236I200J0D01*
G02Y1497324I-1664J-1456D01*
G03X1176770Y1497192I150J-132D01*
G01Y1495250D01*
G03X1176820Y1495118I200J0D01*
G02Y1492206I-1664J-1456D01*
G03X1176770Y1492074I150J-132D01*
G01Y1491451D01*
G02X1176567Y1491248I-203J0D01*
G01X1173747D01*
G02X1173544Y1491451I0J203D01*
G01Y1492074D01*
G03X1173494Y1492206I-200J0D01*
G02Y1495118I1664J1456D01*
G03X1173544Y1495250I-150J132D01*
G01Y1497192D01*
G03X1173494Y1497324I-200J0D01*
G02Y1500236I1664J1456D01*
G03X1173544Y1500368I-150J132D01*
G01Y1500989D01*
G02X1173747Y1501192I203J0D01*
G37*
G36*
G01X1191070D02*
X1193890D01*
G02X1194092Y1500989I-1J-203D01*
G01Y1500370D01*
G03X1194142Y1500238I200J0D01*
G02Y1497322I-1661J-1458D01*
G03X1194092Y1497190I150J-132D01*
G01Y1495252D01*
G03X1194142Y1495120I200J0D01*
G02Y1492204I-1661J-1458D01*
G03X1194092Y1492072I150J-132D01*
G01Y1491451D01*
G02X1193890Y1491248I-202J-1D01*
G01X1191070D01*
G02X1190868Y1491451I1J203D01*
G01Y1492072D01*
G03X1190818Y1492204I-200J0D01*
G02Y1495120I1661J1458D01*
G03X1190868Y1495252I-150J132D01*
G01Y1497190D01*
G03X1190818Y1497322I-200J0D01*
G02Y1500238I1661J1458D01*
G03X1190868Y1500370I-150J132D01*
G01Y1500989D01*
G02X1191070Y1501192I202J1D01*
G37*
G36*
G01X1312330D02*
X1315150D01*
G02X1315352Y1500989I-1J-203D01*
G01Y1500370D01*
G03X1315402Y1500238I200J0D01*
G02Y1497322I-1661J-1458D01*
G03X1315352Y1497190I150J-132D01*
G01Y1495252D01*
G03X1315402Y1495120I200J0D01*
G02Y1492204I-1661J-1458D01*
G03X1315352Y1492072I150J-132D01*
G01Y1491451D01*
G02X1315150Y1491248I-202J-1D01*
G01X1312330D01*
G02X1312128Y1491451I1J203D01*
G01Y1492072D01*
G03X1312078Y1492204I-200J0D01*
G02Y1495120I1661J1458D01*
G03X1312128Y1495252I-150J132D01*
G01Y1497190D01*
G03X1312078Y1497322I-200J0D01*
G02Y1500238I1661J1458D01*
G03X1312128Y1500370I-150J132D01*
G01Y1500989D01*
G02X1312330Y1501192I202J1D01*
G37*
G36*
G01X1329653D02*
X1332473D01*
G02X1332676Y1500989I0J-203D01*
G01Y1500368D01*
G03X1332726Y1500236I200J0D01*
G02Y1497324I-1664J-1456D01*
G03X1332676Y1497192I150J-132D01*
G01Y1495250D01*
G03X1332726Y1495118I200J0D01*
G02Y1492206I-1664J-1456D01*
G03X1332676Y1492074I150J-132D01*
G01Y1491451D01*
G02X1332473Y1491248I-203J0D01*
G01X1329653D01*
G02X1329450Y1491451I0J203D01*
G01Y1492074D01*
G03X1329400Y1492206I-200J0D01*
G02Y1495118I1664J1456D01*
G03X1329450Y1495250I-150J132D01*
G01Y1497192D01*
G03X1329400Y1497324I-200J0D01*
G02Y1500236I1664J1456D01*
G03X1329450Y1500368I-150J132D01*
G01Y1500989D01*
G02X1329653Y1501192I203J0D01*
G37*
G36*
G01X1346976D02*
X1349796D01*
G02X1349998Y1500989I-1J-203D01*
G01Y1500370D01*
G03X1350048Y1500238I200J0D01*
G02Y1497322I-1661J-1458D01*
G03X1349998Y1497190I150J-132D01*
G01Y1495252D01*
G03X1350048Y1495120I200J0D01*
G02Y1492204I-1661J-1458D01*
G03X1349998Y1492072I150J-132D01*
G01Y1491451D01*
G02X1349796Y1491248I-202J-1D01*
G01X1346976D01*
G02X1346774Y1491451I1J203D01*
G01Y1492072D01*
G03X1346724Y1492204I-200J0D01*
G02Y1495120I1661J1458D01*
G03X1346774Y1495252I-150J132D01*
G01Y1497190D01*
G03X1346724Y1497322I-200J0D01*
G02Y1500238I1661J1458D01*
G03X1346774Y1500370I-150J132D01*
G01Y1500989D01*
G02X1346976Y1501192I202J1D01*
G37*
G36*
G01X1364299D02*
X1367119D01*
G02X1367322Y1500989I0J-203D01*
G01Y1500368D01*
G03X1367372Y1500236I200J0D01*
G02Y1497324I-1664J-1456D01*
G03X1367322Y1497192I150J-132D01*
G01Y1495250D01*
G03X1367372Y1495118I200J0D01*
G02Y1492206I-1664J-1456D01*
G03X1367322Y1492074I150J-132D01*
G01Y1491451D01*
G02X1367119Y1491248I-203J0D01*
G01X1364299D01*
G02X1364096Y1491451I0J203D01*
G01Y1492074D01*
G03X1364046Y1492206I-200J0D01*
G02Y1495118I1664J1456D01*
G03X1364096Y1495250I-150J132D01*
G01Y1497192D01*
G03X1364046Y1497324I-200J0D01*
G02Y1500236I1664J1456D01*
G03X1364096Y1500368I-150J132D01*
G01Y1500989D01*
G02X1364299Y1501192I203J0D01*
G37*
G36*
G01X1485558D02*
X1488378D01*
G02X1488580Y1500989I-1J-203D01*
G01Y1500370D01*
G03X1488630Y1500238I200J0D01*
G02Y1497322I-1661J-1458D01*
G03X1488580Y1497190I150J-132D01*
G01Y1495252D01*
G03X1488630Y1495120I200J0D01*
G02Y1492204I-1661J-1458D01*
G03X1488580Y1492072I150J-132D01*
G01Y1491451D01*
G02X1488378Y1491248I-202J-1D01*
G01X1485558D01*
G02X1485356Y1491451I1J203D01*
G01Y1492072D01*
G03X1485306Y1492204I-200J0D01*
G02Y1495120I1661J1458D01*
G03X1485356Y1495252I-150J132D01*
G01Y1497190D01*
G03X1485306Y1497322I-200J0D01*
G02Y1500238I1661J1458D01*
G03X1485356Y1500370I-150J132D01*
G01Y1500989D01*
G02X1485558Y1501192I202J1D01*
G37*
G36*
G01X1502881D02*
X1505701D01*
G02X1505904Y1500989I0J-203D01*
G01Y1500368D01*
G03X1505954Y1500236I200J0D01*
G02Y1497324I-1664J-1456D01*
G03X1505904Y1497192I150J-132D01*
G01Y1495250D01*
G03X1505954Y1495118I200J0D01*
G02Y1492206I-1664J-1456D01*
G03X1505904Y1492074I150J-132D01*
G01Y1491451D01*
G02X1505701Y1491248I-203J0D01*
G01X1502881D01*
G02X1502678Y1491451I0J203D01*
G01Y1492074D01*
G03X1502628Y1492206I-200J0D01*
G02Y1495118I1664J1456D01*
G03X1502678Y1495250I-150J132D01*
G01Y1497192D01*
G03X1502628Y1497324I-200J0D01*
G02Y1500236I1664J1456D01*
G03X1502678Y1500368I-150J132D01*
G01Y1500989D01*
G02X1502881Y1501192I203J0D01*
G37*
G36*
G01X1520204D02*
X1523024D01*
G02X1523226Y1500989I-1J-203D01*
G01Y1500370D01*
G03X1523276Y1500238I200J0D01*
G02Y1497322I-1661J-1458D01*
G03X1523226Y1497190I150J-132D01*
G01Y1495252D01*
G03X1523276Y1495120I200J0D01*
G02Y1492204I-1661J-1458D01*
G03X1523226Y1492072I150J-132D01*
G01Y1491451D01*
G02X1523024Y1491248I-202J-1D01*
G01X1520204D01*
G02X1520002Y1491451I1J203D01*
G01Y1492072D01*
G03X1519952Y1492204I-200J0D01*
G02Y1495120I1661J1458D01*
G03X1520002Y1495252I-150J132D01*
G01Y1497190D01*
G03X1519952Y1497322I-200J0D01*
G02Y1500238I1661J1458D01*
G03X1520002Y1500370I-150J132D01*
G01Y1500989D01*
G02X1520204Y1501192I202J1D01*
G37*
G36*
G01X1537527D02*
X1540347D01*
G02X1540550Y1500989I0J-203D01*
G01Y1500368D01*
G03X1540600Y1500236I200J0D01*
G02Y1497324I-1664J-1456D01*
G03X1540550Y1497192I150J-132D01*
G01Y1495250D01*
G03X1540600Y1495118I200J0D01*
G02Y1492206I-1664J-1456D01*
G03X1540550Y1492074I150J-132D01*
G01Y1491451D01*
G02X1540347Y1491248I-203J0D01*
G01X1537527D01*
G02X1537324Y1491451I0J203D01*
G01Y1492074D01*
G03X1537274Y1492206I-200J0D01*
G02Y1495118I1664J1456D01*
G03X1537324Y1495250I-150J132D01*
G01Y1497192D01*
G03X1537274Y1497324I-200J0D01*
G02Y1500236I1664J1456D01*
G03X1537324Y1500368I-150J132D01*
G01Y1500989D01*
G02X1537527Y1501192I203J0D01*
G37*
G36*
G01X1693432D02*
X1696252D01*
G02X1696454Y1500989I-1J-203D01*
G01Y1500370D01*
G03X1696504Y1500238I200J0D01*
G02Y1497322I-1661J-1458D01*
G03X1696454Y1497190I150J-132D01*
G01Y1495252D01*
G03X1696504Y1495120I200J0D01*
G02Y1492204I-1661J-1458D01*
G03X1696454Y1492072I150J-132D01*
G01Y1491451D01*
G02X1696252Y1491248I-202J-1D01*
G01X1693432D01*
G02X1693230Y1491451I1J203D01*
G01Y1492072D01*
G03X1693180Y1492204I-200J0D01*
G02Y1495120I1661J1458D01*
G03X1693230Y1495252I-150J132D01*
G01Y1497190D01*
G03X1693180Y1497322I-200J0D01*
G02Y1500238I1661J1458D01*
G03X1693230Y1500370I-150J132D01*
G01Y1500989D01*
G02X1693432Y1501192I202J1D01*
G37*
G36*
G01X1710755D02*
X1713575D01*
G02X1713778Y1500989I0J-203D01*
G01Y1500368D01*
G03X1713828Y1500236I200J0D01*
G02Y1497324I-1664J-1456D01*
G03X1713778Y1497192I150J-132D01*
G01Y1495250D01*
G03X1713828Y1495118I200J0D01*
G02Y1492206I-1664J-1456D01*
G03X1713778Y1492074I150J-132D01*
G01Y1491451D01*
G02X1713575Y1491248I-203J0D01*
G01X1710755D01*
G02X1710552Y1491451I0J203D01*
G01Y1492074D01*
G03X1710502Y1492206I-200J0D01*
G02Y1495118I1664J1456D01*
G03X1710552Y1495250I-150J132D01*
G01Y1497192D01*
G03X1710502Y1497324I-200J0D01*
G02Y1500236I1664J1456D01*
G03X1710552Y1500368I-150J132D01*
G01Y1500989D01*
G02X1710755Y1501192I203J0D01*
G37*
G36*
G01X143118Y1512216D02*
X145938D01*
G02X146140Y1512014I0J-202D01*
G01Y1511394D01*
G03X146190Y1511262I200J0D01*
G02Y1508346I-1661J-1458D01*
G03X146140Y1508214I150J-132D01*
G01Y1506275D01*
G03X146190Y1506143I200J0D01*
G02Y1503227I-1661J-1458D01*
G03X146140Y1503095I150J-132D01*
G01Y1502476D01*
G02X145938Y1502274I-202J0D01*
G01X143118D01*
G02X142916Y1502476I0J202D01*
G01Y1503095D01*
G03X142866Y1503227I-200J0D01*
G02Y1506143I1661J1458D01*
G03X142916Y1506275I-150J132D01*
G01Y1508214D01*
G03X142866Y1508346I-200J0D01*
G02Y1511262I1661J1458D01*
G03X142916Y1511394I-150J132D01*
G01Y1512014D01*
G02X143118Y1512216I202J0D01*
G37*
G36*
G01X160440D02*
X163260D01*
G02X163462Y1512014I0J-202D01*
G01Y1511394D01*
G03X163512Y1511262I200J0D01*
G02Y1508346I-1661J-1458D01*
G03X163462Y1508214I150J-132D01*
G01Y1506275D01*
G03X163512Y1506143I200J0D01*
G02Y1503227I-1661J-1458D01*
G03X163462Y1503095I150J-132D01*
G01Y1502476D01*
G02X163260Y1502274I-202J0D01*
G01X160440D01*
G02X160238Y1502476I0J202D01*
G01Y1503095D01*
G03X160188Y1503227I-200J0D01*
G02Y1506143I1661J1458D01*
G03X160238Y1506275I-150J132D01*
G01Y1508214D01*
G03X160188Y1508346I-200J0D01*
G02Y1511262I1661J1458D01*
G03X160238Y1511394I-150J132D01*
G01Y1512014D01*
G02X160440Y1512216I202J0D01*
G37*
G36*
G01X281700D02*
X284520D01*
G02X284722Y1512014I0J-202D01*
G01Y1511394D01*
G03X284772Y1511262I200J0D01*
G02Y1508346I-1661J-1458D01*
G03X284722Y1508214I150J-132D01*
G01Y1506275D01*
G03X284772Y1506143I200J0D01*
G02Y1503227I-1661J-1458D01*
G03X284722Y1503095I150J-132D01*
G01Y1502476D01*
G02X284520Y1502274I-202J0D01*
G01X281700D01*
G02X281498Y1502476I0J202D01*
G01Y1503095D01*
G03X281448Y1503227I-200J0D01*
G02Y1506143I1661J1458D01*
G03X281498Y1506275I-150J132D01*
G01Y1508214D01*
G03X281448Y1508346I-200J0D01*
G02Y1511262I1661J1458D01*
G03X281498Y1511394I-150J132D01*
G01Y1512014D01*
G02X281700Y1512216I202J0D01*
G37*
G36*
G01X472252D02*
X475072D01*
G02X475274Y1512014I0J-202D01*
G01Y1511394D01*
G03X475324Y1511262I200J0D01*
G02Y1508346I-1661J-1458D01*
G03X475274Y1508214I150J-132D01*
G01Y1506275D01*
G03X475324Y1506143I200J0D01*
G02Y1503227I-1661J-1458D01*
G03X475274Y1503095I150J-132D01*
G01Y1502476D01*
G02X475072Y1502274I-202J0D01*
G01X472252D01*
G02X472050Y1502476I0J202D01*
G01Y1503095D01*
G03X472000Y1503227I-200J0D01*
G02Y1506143I1661J1458D01*
G03X472050Y1506275I-150J132D01*
G01Y1508214D01*
G03X472000Y1508346I-200J0D01*
G02Y1511262I1661J1458D01*
G03X472050Y1511394I-150J132D01*
G01Y1512014D01*
G02X472252Y1512216I202J0D01*
G37*
G36*
G01X645480D02*
X648300D01*
G02X648502Y1512014I0J-202D01*
G01Y1511394D01*
G03X648552Y1511262I200J0D01*
G02Y1508346I-1661J-1458D01*
G03X648502Y1508214I150J-132D01*
G01Y1506275D01*
G03X648552Y1506143I200J0D01*
G02Y1503227I-1661J-1458D01*
G03X648502Y1503095I150J-132D01*
G01Y1502476D01*
G02X648300Y1502274I-202J0D01*
G01X645480D01*
G02X645278Y1502476I0J202D01*
G01Y1503095D01*
G03X645228Y1503227I-200J0D01*
G02Y1506143I1661J1458D01*
G03X645278Y1506275I-150J132D01*
G01Y1508214D01*
G03X645228Y1508346I-200J0D01*
G02Y1511262I1661J1458D01*
G03X645278Y1511394I-150J132D01*
G01Y1512014D01*
G02X645480Y1512216I202J0D01*
G37*
G36*
G01X1165086D02*
X1167906D01*
G02X1168108Y1512014I0J-202D01*
G01Y1511394D01*
G03X1168158Y1511262I200J0D01*
G02Y1508346I-1661J-1458D01*
G03X1168108Y1508214I150J-132D01*
G01Y1506275D01*
G03X1168158Y1506143I200J0D01*
G02Y1503227I-1661J-1458D01*
G03X1168108Y1503095I150J-132D01*
G01Y1502476D01*
G02X1167906Y1502274I-202J0D01*
G01X1165086D01*
G02X1164884Y1502476I0J202D01*
G01Y1503095D01*
G03X1164834Y1503227I-200J0D01*
G02Y1506143I1661J1458D01*
G03X1164884Y1506275I-150J132D01*
G01Y1508214D01*
G03X1164834Y1508346I-200J0D01*
G02Y1511262I1661J1458D01*
G03X1164884Y1511394I-150J132D01*
G01Y1512014D01*
G02X1165086Y1512216I202J0D01*
G37*
G36*
G01X1182408D02*
X1185228D01*
G02X1185430Y1512014I0J-202D01*
G01Y1511394D01*
G03X1185480Y1511262I200J0D01*
G02Y1508346I-1661J-1458D01*
G03X1185430Y1508214I150J-132D01*
G01Y1506275D01*
G03X1185480Y1506143I200J0D01*
G02Y1503227I-1661J-1458D01*
G03X1185430Y1503095I150J-132D01*
G01Y1502476D01*
G02X1185228Y1502274I-202J0D01*
G01X1182408D01*
G02X1182206Y1502476I0J202D01*
G01Y1503095D01*
G03X1182156Y1503227I-200J0D01*
G02Y1506143I1661J1458D01*
G03X1182206Y1506275I-150J132D01*
G01Y1508214D01*
G03X1182156Y1508346I-200J0D01*
G02Y1511262I1661J1458D01*
G03X1182206Y1511394I-150J132D01*
G01Y1512014D01*
G02X1182408Y1512216I202J0D01*
G37*
G36*
G01X1320992D02*
X1323812D01*
G02X1324014Y1512014I0J-202D01*
G01Y1511394D01*
G03X1324064Y1511262I200J0D01*
G02Y1508346I-1661J-1458D01*
G03X1324014Y1508214I150J-132D01*
G01Y1506275D01*
G03X1324064Y1506143I200J0D01*
G02Y1503227I-1661J-1458D01*
G03X1324014Y1503095I150J-132D01*
G01Y1502476D01*
G02X1323812Y1502274I-202J0D01*
G01X1320992D01*
G02X1320790Y1502476I0J202D01*
G01Y1503095D01*
G03X1320740Y1503227I-200J0D01*
G02Y1506143I1661J1458D01*
G03X1320790Y1506275I-150J132D01*
G01Y1508214D01*
G03X1320740Y1508346I-200J0D01*
G02Y1511262I1661J1458D01*
G03X1320790Y1511394I-150J132D01*
G01Y1512014D01*
G02X1320992Y1512216I202J0D01*
G37*
G36*
G01X1494220D02*
X1497040D01*
G02X1497242Y1512014I0J-202D01*
G01Y1511394D01*
G03X1497292Y1511262I200J0D01*
G02Y1508346I-1661J-1458D01*
G03X1497242Y1508214I150J-132D01*
G01Y1506275D01*
G03X1497292Y1506143I200J0D01*
G02Y1503227I-1661J-1458D01*
G03X1497242Y1503095I150J-132D01*
G01Y1502476D01*
G02X1497040Y1502274I-202J0D01*
G01X1494220D01*
G02X1494018Y1502476I0J202D01*
G01Y1503095D01*
G03X1493968Y1503227I-200J0D01*
G02Y1506143I1661J1458D01*
G03X1494018Y1506275I-150J132D01*
G01Y1508214D01*
G03X1493968Y1508346I-200J0D01*
G02Y1511262I1661J1458D01*
G03X1494018Y1511394I-150J132D01*
G01Y1512014D01*
G02X1494220Y1512216I202J0D01*
G37*
G36*
G01X125795D02*
X128615D01*
G02X128818Y1512014I1J-202D01*
G01Y1511392D01*
G03X128868Y1511260I200J0D01*
G02Y1508348I-1664J-1456D01*
G03X128818Y1508216I150J-132D01*
G01Y1506273D01*
G03X128868Y1506141I200J0D01*
G02Y1503229I-1664J-1456D01*
G03X128818Y1503097I150J-132D01*
G01Y1502476D01*
G02X128615Y1502274I-203J1D01*
G01X125795D01*
G02X125592Y1502476I-1J202D01*
G01Y1503097D01*
G03X125542Y1503229I-200J0D01*
G02Y1506141I1664J1456D01*
G03X125592Y1506273I-150J132D01*
G01Y1508216D01*
G03X125542Y1508348I-200J0D01*
G02Y1511260I1664J1456D01*
G03X125592Y1511392I-150J132D01*
G01Y1512014D01*
G02X125795Y1512216I203J-1D01*
G37*
G36*
G01X299023D02*
X301843D01*
G02X302046Y1512014I1J-202D01*
G01Y1511392D01*
G03X302096Y1511260I200J0D01*
G02Y1508348I-1664J-1456D01*
G03X302046Y1508216I150J-132D01*
G01Y1506273D01*
G03X302096Y1506141I200J0D01*
G02Y1503229I-1664J-1456D01*
G03X302046Y1503097I150J-132D01*
G01Y1502476D01*
G02X301843Y1502274I-203J1D01*
G01X299023D01*
G02X298820Y1502476I-1J202D01*
G01Y1503097D01*
G03X298770Y1503229I-200J0D01*
G02Y1506141I1664J1456D01*
G03X298820Y1506273I-150J132D01*
G01Y1508216D01*
G03X298770Y1508348I-200J0D01*
G02Y1511260I1664J1456D01*
G03X298820Y1511392I-150J132D01*
G01Y1512014D01*
G02X299023Y1512216I203J-1D01*
G37*
G36*
G01X454929D02*
X457749D01*
G02X457952Y1512014I1J-202D01*
G01Y1511392D01*
G03X458002Y1511260I200J0D01*
G02Y1508348I-1664J-1456D01*
G03X457952Y1508216I150J-132D01*
G01Y1506273D01*
G03X458002Y1506141I200J0D01*
G02Y1503229I-1664J-1456D01*
G03X457952Y1503097I150J-132D01*
G01Y1502476D01*
G02X457749Y1502274I-203J1D01*
G01X454929D01*
G02X454726Y1502476I-1J202D01*
G01Y1503097D01*
G03X454676Y1503229I-200J0D01*
G02Y1506141I1664J1456D01*
G03X454726Y1506273I-150J132D01*
G01Y1508216D01*
G03X454676Y1508348I-200J0D01*
G02Y1511260I1664J1456D01*
G03X454726Y1511392I-150J132D01*
G01Y1512014D01*
G02X454929Y1512216I203J-1D01*
G37*
G36*
G01X489575D02*
X492395D01*
G02X492598Y1512014I1J-202D01*
G01Y1511392D01*
G03X492648Y1511260I200J0D01*
G02Y1508348I-1664J-1456D01*
G03X492598Y1508216I150J-132D01*
G01Y1506273D01*
G03X492648Y1506141I200J0D01*
G02Y1503229I-1664J-1456D01*
G03X492598Y1503097I150J-132D01*
G01Y1502476D01*
G02X492395Y1502274I-203J1D01*
G01X489575D01*
G02X489372Y1502476I-1J202D01*
G01Y1503097D01*
G03X489322Y1503229I-200J0D01*
G02Y1506141I1664J1456D01*
G03X489372Y1506273I-150J132D01*
G01Y1508216D01*
G03X489322Y1508348I-200J0D01*
G02Y1511260I1664J1456D01*
G03X489372Y1511392I-150J132D01*
G01Y1512014D01*
G02X489575Y1512216I203J-1D01*
G37*
G36*
G01X506897D02*
X509717D01*
G02X509920Y1512014I1J-202D01*
G01Y1511392D01*
G03X509970Y1511260I200J0D01*
G02Y1508348I-1664J-1456D01*
G03X509920Y1508216I150J-132D01*
G01Y1506273D01*
G03X509970Y1506141I200J0D01*
G02Y1503229I-1664J-1456D01*
G03X509920Y1503097I150J-132D01*
G01Y1502476D01*
G02X509717Y1502274I-203J1D01*
G01X506897D01*
G02X506694Y1502476I-1J202D01*
G01Y1503097D01*
G03X506644Y1503229I-200J0D01*
G02Y1506141I1664J1456D01*
G03X506694Y1506273I-150J132D01*
G01Y1508216D01*
G03X506644Y1508348I-200J0D01*
G02Y1511260I1664J1456D01*
G03X506694Y1511392I-150J132D01*
G01Y1512014D01*
G02X506897Y1512216I203J-1D01*
G37*
G36*
G01X662803D02*
X665623D01*
G02X665826Y1512014I1J-202D01*
G01Y1511392D01*
G03X665876Y1511260I200J0D01*
G02Y1508348I-1664J-1456D01*
G03X665826Y1508216I150J-132D01*
G01Y1506273D01*
G03X665876Y1506141I200J0D01*
G02Y1503229I-1664J-1456D01*
G03X665826Y1503097I150J-132D01*
G01Y1502476D01*
G02X665623Y1502274I-203J1D01*
G01X662803D01*
G02X662600Y1502476I-1J202D01*
G01Y1503097D01*
G03X662550Y1503229I-200J0D01*
G02Y1506141I1664J1456D01*
G03X662600Y1506273I-150J132D01*
G01Y1508216D01*
G03X662550Y1508348I-200J0D01*
G02Y1511260I1664J1456D01*
G03X662600Y1511392I-150J132D01*
G01Y1512014D01*
G02X662803Y1512216I203J-1D01*
G37*
G36*
G01X680125D02*
X682945D01*
G02X683148Y1512014I1J-202D01*
G01Y1511392D01*
G03X683198Y1511260I200J0D01*
G02Y1508348I-1664J-1456D01*
G03X683148Y1508216I150J-132D01*
G01Y1506273D01*
G03X683198Y1506141I200J0D01*
G02Y1503229I-1664J-1456D01*
G03X683148Y1503097I150J-132D01*
G01Y1502476D01*
G02X682945Y1502274I-203J1D01*
G01X680125D01*
G02X679922Y1502476I-1J202D01*
G01Y1503097D01*
G03X679872Y1503229I-200J0D01*
G02Y1506141I1664J1456D01*
G03X679922Y1506273I-150J132D01*
G01Y1508216D01*
G03X679872Y1508348I-200J0D01*
G02Y1511260I1664J1456D01*
G03X679922Y1511392I-150J132D01*
G01Y1512014D01*
G02X680125Y1512216I203J-1D01*
G37*
G36*
G01X1303669D02*
X1306489D01*
G02X1306692Y1512014I1J-202D01*
G01Y1511392D01*
G03X1306742Y1511260I200J0D01*
G02Y1508348I-1664J-1456D01*
G03X1306692Y1508216I150J-132D01*
G01Y1506273D01*
G03X1306742Y1506141I200J0D01*
G02Y1503229I-1664J-1456D01*
G03X1306692Y1503097I150J-132D01*
G01Y1502476D01*
G02X1306489Y1502274I-203J1D01*
G01X1303669D01*
G02X1303466Y1502476I-1J202D01*
G01Y1503097D01*
G03X1303416Y1503229I-200J0D01*
G02Y1506141I1664J1456D01*
G03X1303466Y1506273I-150J132D01*
G01Y1508216D01*
G03X1303416Y1508348I-200J0D01*
G02Y1511260I1664J1456D01*
G03X1303466Y1511392I-150J132D01*
G01Y1512014D01*
G02X1303669Y1512216I203J-1D01*
G37*
G36*
G01X1338315D02*
X1341135D01*
G02X1341338Y1512014I1J-202D01*
G01Y1511392D01*
G03X1341388Y1511260I200J0D01*
G02Y1508348I-1664J-1456D01*
G03X1341338Y1508216I150J-132D01*
G01Y1506273D01*
G03X1341388Y1506141I200J0D01*
G02Y1503229I-1664J-1456D01*
G03X1341338Y1503097I150J-132D01*
G01Y1502476D01*
G02X1341135Y1502274I-203J1D01*
G01X1338315D01*
G02X1338112Y1502476I-1J202D01*
G01Y1503097D01*
G03X1338062Y1503229I-200J0D01*
G02Y1506141I1664J1456D01*
G03X1338112Y1506273I-150J132D01*
G01Y1508216D01*
G03X1338062Y1508348I-200J0D01*
G02Y1511260I1664J1456D01*
G03X1338112Y1511392I-150J132D01*
G01Y1512014D01*
G02X1338315Y1512216I203J-1D01*
G37*
G36*
G01X1355637D02*
X1358457D01*
G02X1358660Y1512014I1J-202D01*
G01Y1511392D01*
G03X1358710Y1511260I200J0D01*
G02Y1508348I-1664J-1456D01*
G03X1358660Y1508216I150J-132D01*
G01Y1506273D01*
G03X1358710Y1506141I200J0D01*
G02Y1503229I-1664J-1456D01*
G03X1358660Y1503097I150J-132D01*
G01Y1502476D01*
G02X1358457Y1502274I-203J1D01*
G01X1355637D01*
G02X1355434Y1502476I-1J202D01*
G01Y1503097D01*
G03X1355384Y1503229I-200J0D01*
G02Y1506141I1664J1456D01*
G03X1355434Y1506273I-150J132D01*
G01Y1508216D01*
G03X1355384Y1508348I-200J0D01*
G02Y1511260I1664J1456D01*
G03X1355434Y1511392I-150J132D01*
G01Y1512014D01*
G02X1355637Y1512216I203J-1D01*
G37*
G36*
G01X1476897D02*
X1479717D01*
G02X1479920Y1512014I1J-202D01*
G01Y1511392D01*
G03X1479970Y1511260I200J0D01*
G02Y1508348I-1664J-1456D01*
G03X1479920Y1508216I150J-132D01*
G01Y1506273D01*
G03X1479970Y1506141I200J0D01*
G02Y1503229I-1664J-1456D01*
G03X1479920Y1503097I150J-132D01*
G01Y1502476D01*
G02X1479717Y1502274I-203J1D01*
G01X1476897D01*
G02X1476694Y1502476I-1J202D01*
G01Y1503097D01*
G03X1476644Y1503229I-200J0D01*
G02Y1506141I1664J1456D01*
G03X1476694Y1506273I-150J132D01*
G01Y1508216D01*
G03X1476644Y1508348I-200J0D01*
G02Y1511260I1664J1456D01*
G03X1476694Y1511392I-150J132D01*
G01Y1512014D01*
G02X1476897Y1512216I203J-1D01*
G37*
G36*
G01X1511543D02*
X1514363D01*
G02X1514566Y1512014I1J-202D01*
G01Y1511392D01*
G03X1514616Y1511260I200J0D01*
G02Y1508348I-1664J-1456D01*
G03X1514566Y1508216I150J-132D01*
G01Y1506273D01*
G03X1514616Y1506141I200J0D01*
G02Y1503229I-1664J-1456D01*
G03X1514566Y1503097I150J-132D01*
G01Y1502476D01*
G02X1514363Y1502274I-203J1D01*
G01X1511543D01*
G02X1511340Y1502476I-1J202D01*
G01Y1503097D01*
G03X1511290Y1503229I-200J0D01*
G02Y1506141I1664J1456D01*
G03X1511340Y1506273I-150J132D01*
G01Y1508216D01*
G03X1511290Y1508348I-200J0D01*
G02Y1511260I1664J1456D01*
G03X1511340Y1511392I-150J132D01*
G01Y1512014D01*
G02X1511543Y1512216I203J-1D01*
G37*
G36*
G01X1528865D02*
X1531685D01*
G02X1531888Y1512014I1J-202D01*
G01Y1511392D01*
G03X1531938Y1511260I200J0D01*
G02Y1508348I-1664J-1456D01*
G03X1531888Y1508216I150J-132D01*
G01Y1506273D01*
G03X1531938Y1506141I200J0D01*
G02Y1503229I-1664J-1456D01*
G03X1531888Y1503097I150J-132D01*
G01Y1502476D01*
G02X1531685Y1502274I-203J1D01*
G01X1528865D01*
G02X1528662Y1502476I-1J202D01*
G01Y1503097D01*
G03X1528612Y1503229I-200J0D01*
G02Y1506141I1664J1456D01*
G03X1528662Y1506273I-150J132D01*
G01Y1508216D01*
G03X1528612Y1508348I-200J0D01*
G02Y1511260I1664J1456D01*
G03X1528662Y1511392I-150J132D01*
G01Y1512014D01*
G02X1528865Y1512216I203J-1D01*
G37*
G36*
G01X1684771D02*
X1687591D01*
G02X1687794Y1512014I1J-202D01*
G01Y1511392D01*
G03X1687844Y1511260I200J0D01*
G02Y1508348I-1664J-1456D01*
G03X1687794Y1508216I150J-132D01*
G01Y1506273D01*
G03X1687844Y1506141I200J0D01*
G02Y1503229I-1664J-1456D01*
G03X1687794Y1503097I150J-132D01*
G01Y1502476D01*
G02X1687591Y1502274I-203J1D01*
G01X1684771D01*
G02X1684568Y1502476I-1J202D01*
G01Y1503097D01*
G03X1684518Y1503229I-200J0D01*
G02Y1506141I1664J1456D01*
G03X1684568Y1506273I-150J132D01*
G01Y1508216D01*
G03X1684518Y1508348I-200J0D01*
G02Y1511260I1664J1456D01*
G03X1684568Y1511392I-150J132D01*
G01Y1512014D01*
G02X1684771Y1512216I203J-1D01*
G37*
G36*
G01X1702093D02*
X1704913D01*
G02X1705116Y1512014I1J-202D01*
G01Y1511392D01*
G03X1705166Y1511260I200J0D01*
G02Y1508348I-1664J-1456D01*
G03X1705116Y1508216I150J-132D01*
G01Y1506273D01*
G03X1705166Y1506141I200J0D01*
G02Y1503229I-1664J-1456D01*
G03X1705116Y1503097I150J-132D01*
G01Y1502476D01*
G02X1704913Y1502274I-203J1D01*
G01X1702093D01*
G02X1701890Y1502476I-1J202D01*
G01Y1503097D01*
G03X1701840Y1503229I-200J0D01*
G02Y1506141I1664J1456D01*
G03X1701890Y1506273I-150J132D01*
G01Y1508216D01*
G03X1701840Y1508348I-200J0D01*
G02Y1511260I1664J1456D01*
G03X1701890Y1511392I-150J132D01*
G01Y1512014D01*
G02X1702093Y1512216I203J-1D01*
G37*
G36*
G01X134456Y1516546D02*
X137276D01*
G02X137478Y1516344I0J-202D01*
G01Y1515724D01*
G03X137528Y1515592I200J0D01*
G02Y1512676I-1661J-1458D01*
G03X137478Y1512544I150J-132D01*
G01Y1510606D01*
G03X137528Y1510474I200J0D01*
G02Y1507558I-1661J-1458D01*
G03X137478Y1507426I150J-132D01*
G01Y1506806D01*
G02X137276Y1506604I-202J0D01*
G01X134456D01*
G02X134254Y1506806I0J202D01*
G01Y1507426D01*
G03X134204Y1507558I-200J0D01*
G02Y1510474I1661J1458D01*
G03X134254Y1510606I-150J132D01*
G01Y1512544D01*
G03X134204Y1512676I-200J0D01*
G02Y1515592I1661J1458D01*
G03X134254Y1515724I-150J132D01*
G01Y1516344D01*
G02X134456Y1516546I202J0D01*
G37*
G36*
G01X169102D02*
X171922D01*
G02X172124Y1516344I0J-202D01*
G01Y1515724D01*
G03X172174Y1515592I200J0D01*
G02Y1512676I-1661J-1458D01*
G03X172124Y1512544I150J-132D01*
G01Y1510606D01*
G03X172174Y1510474I200J0D01*
G02Y1507558I-1661J-1458D01*
G03X172124Y1507426I150J-132D01*
G01Y1506806D01*
G02X171922Y1506604I-202J0D01*
G01X169102D01*
G02X168900Y1506806I0J202D01*
G01Y1507426D01*
G03X168850Y1507558I-200J0D01*
G02Y1510474I1661J1458D01*
G03X168900Y1510606I-150J132D01*
G01Y1512544D01*
G03X168850Y1512676I-200J0D01*
G02Y1515592I1661J1458D01*
G03X168900Y1515724I-150J132D01*
G01Y1516344D01*
G02X169102Y1516546I202J0D01*
G37*
G36*
G01X463590D02*
X466410D01*
G02X466612Y1516344I0J-202D01*
G01Y1515724D01*
G03X466662Y1515592I200J0D01*
G02Y1512676I-1661J-1458D01*
G03X466612Y1512544I150J-132D01*
G01Y1510606D01*
G03X466662Y1510474I200J0D01*
G02Y1507558I-1661J-1458D01*
G03X466612Y1507426I150J-132D01*
G01Y1506806D01*
G02X466410Y1506604I-202J0D01*
G01X463590D01*
G02X463388Y1506806I0J202D01*
G01Y1507426D01*
G03X463338Y1507558I-200J0D01*
G02Y1510474I1661J1458D01*
G03X463388Y1510606I-150J132D01*
G01Y1512544D01*
G03X463338Y1512676I-200J0D01*
G02Y1515592I1661J1458D01*
G03X463388Y1515724I-150J132D01*
G01Y1516344D01*
G02X463590Y1516546I202J0D01*
G37*
G36*
G01X498236D02*
X501056D01*
G02X501258Y1516344I0J-202D01*
G01Y1515724D01*
G03X501308Y1515592I200J0D01*
G02Y1512676I-1661J-1458D01*
G03X501258Y1512544I150J-132D01*
G01Y1510606D01*
G03X501308Y1510474I200J0D01*
G02Y1507558I-1661J-1458D01*
G03X501258Y1507426I150J-132D01*
G01Y1506806D01*
G02X501056Y1506604I-202J0D01*
G01X498236D01*
G02X498034Y1506806I0J202D01*
G01Y1507426D01*
G03X497984Y1507558I-200J0D01*
G02Y1510474I1661J1458D01*
G03X498034Y1510606I-150J132D01*
G01Y1512544D01*
G03X497984Y1512676I-200J0D01*
G02Y1515592I1661J1458D01*
G03X498034Y1515724I-150J132D01*
G01Y1516344D01*
G02X498236Y1516546I202J0D01*
G37*
G36*
G01X671464D02*
X674284D01*
G02X674486Y1516344I0J-202D01*
G01Y1515724D01*
G03X674536Y1515592I200J0D01*
G02Y1512676I-1661J-1458D01*
G03X674486Y1512544I150J-132D01*
G01Y1510606D01*
G03X674536Y1510474I200J0D01*
G02Y1507558I-1661J-1458D01*
G03X674486Y1507426I150J-132D01*
G01Y1506806D01*
G02X674284Y1506604I-202J0D01*
G01X671464D01*
G02X671262Y1506806I0J202D01*
G01Y1507426D01*
G03X671212Y1507558I-200J0D01*
G02Y1510474I1661J1458D01*
G03X671262Y1510606I-150J132D01*
G01Y1512544D01*
G03X671212Y1512676I-200J0D01*
G02Y1515592I1661J1458D01*
G03X671262Y1515724I-150J132D01*
G01Y1516344D01*
G02X671464Y1516546I202J0D01*
G37*
G36*
G01X1191070D02*
X1193890D01*
G02X1194092Y1516344I0J-202D01*
G01Y1515724D01*
G03X1194142Y1515592I200J0D01*
G02Y1512676I-1661J-1458D01*
G03X1194092Y1512544I150J-132D01*
G01Y1510606D01*
G03X1194142Y1510474I200J0D01*
G02Y1507558I-1661J-1458D01*
G03X1194092Y1507426I150J-132D01*
G01Y1506806D01*
G02X1193890Y1506604I-202J0D01*
G01X1191070D01*
G02X1190868Y1506806I0J202D01*
G01Y1507426D01*
G03X1190818Y1507558I-200J0D01*
G02Y1510474I1661J1458D01*
G03X1190868Y1510606I-150J132D01*
G01Y1512544D01*
G03X1190818Y1512676I-200J0D01*
G02Y1515592I1661J1458D01*
G03X1190868Y1515724I-150J132D01*
G01Y1516344D01*
G02X1191070Y1516546I202J0D01*
G37*
G36*
G01X1312330D02*
X1315150D01*
G02X1315352Y1516344I0J-202D01*
G01Y1515724D01*
G03X1315402Y1515592I200J0D01*
G02Y1512676I-1661J-1458D01*
G03X1315352Y1512544I150J-132D01*
G01Y1510606D01*
G03X1315402Y1510474I200J0D01*
G02Y1507558I-1661J-1458D01*
G03X1315352Y1507426I150J-132D01*
G01Y1506806D01*
G02X1315150Y1506604I-202J0D01*
G01X1312330D01*
G02X1312128Y1506806I0J202D01*
G01Y1507426D01*
G03X1312078Y1507558I-200J0D01*
G02Y1510474I1661J1458D01*
G03X1312128Y1510606I-150J132D01*
G01Y1512544D01*
G03X1312078Y1512676I-200J0D01*
G02Y1515592I1661J1458D01*
G03X1312128Y1515724I-150J132D01*
G01Y1516344D01*
G02X1312330Y1516546I202J0D01*
G37*
G36*
G01X1346976D02*
X1349796D01*
G02X1349998Y1516344I0J-202D01*
G01Y1515724D01*
G03X1350048Y1515592I200J0D01*
G02Y1512676I-1661J-1458D01*
G03X1349998Y1512544I150J-132D01*
G01Y1510606D01*
G03X1350048Y1510474I200J0D01*
G02Y1507558I-1661J-1458D01*
G03X1349998Y1507426I150J-132D01*
G01Y1506806D01*
G02X1349796Y1506604I-202J0D01*
G01X1346976D01*
G02X1346774Y1506806I0J202D01*
G01Y1507426D01*
G03X1346724Y1507558I-200J0D01*
G02Y1510474I1661J1458D01*
G03X1346774Y1510606I-150J132D01*
G01Y1512544D01*
G03X1346724Y1512676I-200J0D01*
G02Y1515592I1661J1458D01*
G03X1346774Y1515724I-150J132D01*
G01Y1516344D01*
G02X1346976Y1516546I202J0D01*
G37*
G36*
G01X1485558D02*
X1488378D01*
G02X1488580Y1516344I0J-202D01*
G01Y1515724D01*
G03X1488630Y1515592I200J0D01*
G02Y1512676I-1661J-1458D01*
G03X1488580Y1512544I150J-132D01*
G01Y1510606D01*
G03X1488630Y1510474I200J0D01*
G02Y1507558I-1661J-1458D01*
G03X1488580Y1507426I150J-132D01*
G01Y1506806D01*
G02X1488378Y1506604I-202J0D01*
G01X1485558D01*
G02X1485356Y1506806I0J202D01*
G01Y1507426D01*
G03X1485306Y1507558I-200J0D01*
G02Y1510474I1661J1458D01*
G03X1485356Y1510606I-150J132D01*
G01Y1512544D01*
G03X1485306Y1512676I-200J0D01*
G02Y1515592I1661J1458D01*
G03X1485356Y1515724I-150J132D01*
G01Y1516344D01*
G02X1485558Y1516546I202J0D01*
G37*
G36*
G01X1520204D02*
X1523024D01*
G02X1523226Y1516344I0J-202D01*
G01Y1515724D01*
G03X1523276Y1515592I200J0D01*
G02Y1512676I-1661J-1458D01*
G03X1523226Y1512544I150J-132D01*
G01Y1510606D01*
G03X1523276Y1510474I200J0D01*
G02Y1507558I-1661J-1458D01*
G03X1523226Y1507426I150J-132D01*
G01Y1506806D01*
G02X1523024Y1506604I-202J0D01*
G01X1520204D01*
G02X1520002Y1506806I0J202D01*
G01Y1507426D01*
G03X1519952Y1507558I-200J0D01*
G02Y1510474I1661J1458D01*
G03X1520002Y1510606I-150J132D01*
G01Y1512544D01*
G03X1519952Y1512676I-200J0D01*
G02Y1515592I1661J1458D01*
G03X1520002Y1515724I-150J132D01*
G01Y1516344D01*
G02X1520204Y1516546I202J0D01*
G37*
G36*
G01X1693432D02*
X1696252D01*
G02X1696454Y1516344I0J-202D01*
G01Y1515724D01*
G03X1696504Y1515592I200J0D01*
G02Y1512676I-1661J-1458D01*
G03X1696454Y1512544I150J-132D01*
G01Y1510606D01*
G03X1696504Y1510474I200J0D01*
G02Y1507558I-1661J-1458D01*
G03X1696454Y1507426I150J-132D01*
G01Y1506806D01*
G02X1696252Y1506604I-202J0D01*
G01X1693432D01*
G02X1693230Y1506806I0J202D01*
G01Y1507426D01*
G03X1693180Y1507558I-200J0D01*
G02Y1510474I1661J1458D01*
G03X1693230Y1510606I-150J132D01*
G01Y1512544D01*
G03X1693180Y1512676I-200J0D01*
G02Y1515592I1661J1458D01*
G03X1693230Y1515724I-150J132D01*
G01Y1516344D01*
G02X1693432Y1516546I202J0D01*
G37*
G36*
G01X151779D02*
X154599D01*
G02X154802Y1516344I1J-202D01*
G01Y1515722D01*
G03X154852Y1515590I200J0D01*
G02Y1512678I-1664J-1456D01*
G03X154802Y1512546I150J-132D01*
G01Y1510604D01*
G03X154852Y1510472I200J0D01*
G02Y1507560I-1664J-1456D01*
G03X154802Y1507428I150J-132D01*
G01Y1506806D01*
G02X154599Y1506604I-203J1D01*
G01X151779D01*
G02X151576Y1506806I-1J202D01*
G01Y1507428D01*
G03X151526Y1507560I-200J0D01*
G02Y1510472I1664J1456D01*
G03X151576Y1510604I-150J132D01*
G01Y1512546D01*
G03X151526Y1512678I-200J0D01*
G02Y1515590I1664J1456D01*
G03X151576Y1515722I-150J132D01*
G01Y1516344D01*
G02X151779Y1516546I203J-1D01*
G37*
G36*
G01X290361D02*
X293181D01*
G02X293384Y1516344I1J-202D01*
G01Y1515722D01*
G03X293434Y1515590I200J0D01*
G02Y1512678I-1664J-1456D01*
G03X293384Y1512546I150J-132D01*
G01Y1510604D01*
G03X293434Y1510472I200J0D01*
G02Y1507560I-1664J-1456D01*
G03X293384Y1507428I150J-132D01*
G01Y1506806D01*
G02X293181Y1506604I-203J1D01*
G01X290361D01*
G02X290158Y1506806I-1J202D01*
G01Y1507428D01*
G03X290108Y1507560I-200J0D01*
G02Y1510472I1664J1456D01*
G03X290158Y1510604I-150J132D01*
G01Y1512546D01*
G03X290108Y1512678I-200J0D01*
G02Y1515590I1664J1456D01*
G03X290158Y1515722I-150J132D01*
G01Y1516344D01*
G02X290361Y1516546I203J-1D01*
G37*
G36*
G01X480913D02*
X483733D01*
G02X483936Y1516344I1J-202D01*
G01Y1515722D01*
G03X483986Y1515590I200J0D01*
G02Y1512678I-1664J-1456D01*
G03X483936Y1512546I150J-132D01*
G01Y1510604D01*
G03X483986Y1510472I200J0D01*
G02Y1507560I-1664J-1456D01*
G03X483936Y1507428I150J-132D01*
G01Y1506806D01*
G02X483733Y1506604I-203J1D01*
G01X480913D01*
G02X480710Y1506806I-1J202D01*
G01Y1507428D01*
G03X480660Y1507560I-200J0D01*
G02Y1510472I1664J1456D01*
G03X480710Y1510604I-150J132D01*
G01Y1512546D01*
G03X480660Y1512678I-200J0D01*
G02Y1515590I1664J1456D01*
G03X480710Y1515722I-150J132D01*
G01Y1516344D01*
G02X480913Y1516546I203J-1D01*
G37*
G36*
G01X515559D02*
X518379D01*
G02X518582Y1516344I1J-202D01*
G01Y1515722D01*
G03X518632Y1515590I200J0D01*
G02Y1512678I-1664J-1456D01*
G03X518582Y1512546I150J-132D01*
G01Y1510604D01*
G03X518632Y1510472I200J0D01*
G02Y1507560I-1664J-1456D01*
G03X518582Y1507428I150J-132D01*
G01Y1506806D01*
G02X518379Y1506604I-203J1D01*
G01X515559D01*
G02X515356Y1506806I-1J202D01*
G01Y1507428D01*
G03X515306Y1507560I-200J0D01*
G02Y1510472I1664J1456D01*
G03X515356Y1510604I-150J132D01*
G01Y1512546D01*
G03X515306Y1512678I-200J0D01*
G02Y1515590I1664J1456D01*
G03X515356Y1515722I-150J132D01*
G01Y1516344D01*
G02X515559Y1516546I203J-1D01*
G37*
G36*
G01X654141D02*
X656961D01*
G02X657164Y1516344I1J-202D01*
G01Y1515722D01*
G03X657214Y1515590I200J0D01*
G02Y1512678I-1664J-1456D01*
G03X657164Y1512546I150J-132D01*
G01Y1510604D01*
G03X657214Y1510472I200J0D01*
G02Y1507560I-1664J-1456D01*
G03X657164Y1507428I150J-132D01*
G01Y1506806D01*
G02X656961Y1506604I-203J1D01*
G01X654141D01*
G02X653938Y1506806I-1J202D01*
G01Y1507428D01*
G03X653888Y1507560I-200J0D01*
G02Y1510472I1664J1456D01*
G03X653938Y1510604I-150J132D01*
G01Y1512546D01*
G03X653888Y1512678I-200J0D01*
G02Y1515590I1664J1456D01*
G03X653938Y1515722I-150J132D01*
G01Y1516344D01*
G02X654141Y1516546I203J-1D01*
G37*
G36*
G01X688787D02*
X691607D01*
G02X691810Y1516344I1J-202D01*
G01Y1515722D01*
G03X691860Y1515590I200J0D01*
G02Y1512678I-1664J-1456D01*
G03X691810Y1512546I150J-132D01*
G01Y1510604D01*
G03X691860Y1510472I200J0D01*
G02Y1507560I-1664J-1456D01*
G03X691810Y1507428I150J-132D01*
G01Y1506806D01*
G02X691607Y1506604I-203J1D01*
G01X688787D01*
G02X688584Y1506806I-1J202D01*
G01Y1507428D01*
G03X688534Y1507560I-200J0D01*
G02Y1510472I1664J1456D01*
G03X688584Y1510604I-150J132D01*
G01Y1512546D01*
G03X688534Y1512678I-200J0D01*
G02Y1515590I1664J1456D01*
G03X688584Y1515722I-150J132D01*
G01Y1516344D01*
G02X688787Y1516546I203J-1D01*
G37*
G36*
G01X1173747D02*
X1176567D01*
G02X1176770Y1516344I1J-202D01*
G01Y1515722D01*
G03X1176820Y1515590I200J0D01*
G02Y1512678I-1664J-1456D01*
G03X1176770Y1512546I150J-132D01*
G01Y1510604D01*
G03X1176820Y1510472I200J0D01*
G02Y1507560I-1664J-1456D01*
G03X1176770Y1507428I150J-132D01*
G01Y1506806D01*
G02X1176567Y1506604I-203J1D01*
G01X1173747D01*
G02X1173544Y1506806I-1J202D01*
G01Y1507428D01*
G03X1173494Y1507560I-200J0D01*
G02Y1510472I1664J1456D01*
G03X1173544Y1510604I-150J132D01*
G01Y1512546D01*
G03X1173494Y1512678I-200J0D01*
G02Y1515590I1664J1456D01*
G03X1173544Y1515722I-150J132D01*
G01Y1516344D01*
G02X1173747Y1516546I203J-1D01*
G37*
G36*
G01X1329653D02*
X1332473D01*
G02X1332676Y1516344I1J-202D01*
G01Y1515722D01*
G03X1332726Y1515590I200J0D01*
G02Y1512678I-1664J-1456D01*
G03X1332676Y1512546I150J-132D01*
G01Y1510604D01*
G03X1332726Y1510472I200J0D01*
G02Y1507560I-1664J-1456D01*
G03X1332676Y1507428I150J-132D01*
G01Y1506806D01*
G02X1332473Y1506604I-203J1D01*
G01X1329653D01*
G02X1329450Y1506806I-1J202D01*
G01Y1507428D01*
G03X1329400Y1507560I-200J0D01*
G02Y1510472I1664J1456D01*
G03X1329450Y1510604I-150J132D01*
G01Y1512546D01*
G03X1329400Y1512678I-200J0D01*
G02Y1515590I1664J1456D01*
G03X1329450Y1515722I-150J132D01*
G01Y1516344D01*
G02X1329653Y1516546I203J-1D01*
G37*
G36*
G01X1364299D02*
X1367119D01*
G02X1367322Y1516344I1J-202D01*
G01Y1515722D01*
G03X1367372Y1515590I200J0D01*
G02Y1512678I-1664J-1456D01*
G03X1367322Y1512546I150J-132D01*
G01Y1510604D01*
G03X1367372Y1510472I200J0D01*
G02Y1507560I-1664J-1456D01*
G03X1367322Y1507428I150J-132D01*
G01Y1506806D01*
G02X1367119Y1506604I-203J1D01*
G01X1364299D01*
G02X1364096Y1506806I-1J202D01*
G01Y1507428D01*
G03X1364046Y1507560I-200J0D01*
G02Y1510472I1664J1456D01*
G03X1364096Y1510604I-150J132D01*
G01Y1512546D01*
G03X1364046Y1512678I-200J0D01*
G02Y1515590I1664J1456D01*
G03X1364096Y1515722I-150J132D01*
G01Y1516344D01*
G02X1364299Y1516546I203J-1D01*
G37*
G36*
G01X1502881D02*
X1505701D01*
G02X1505904Y1516344I1J-202D01*
G01Y1515722D01*
G03X1505954Y1515590I200J0D01*
G02Y1512678I-1664J-1456D01*
G03X1505904Y1512546I150J-132D01*
G01Y1510604D01*
G03X1505954Y1510472I200J0D01*
G02Y1507560I-1664J-1456D01*
G03X1505904Y1507428I150J-132D01*
G01Y1506806D01*
G02X1505701Y1506604I-203J1D01*
G01X1502881D01*
G02X1502678Y1506806I-1J202D01*
G01Y1507428D01*
G03X1502628Y1507560I-200J0D01*
G02Y1510472I1664J1456D01*
G03X1502678Y1510604I-150J132D01*
G01Y1512546D01*
G03X1502628Y1512678I-200J0D01*
G02Y1515590I1664J1456D01*
G03X1502678Y1515722I-150J132D01*
G01Y1516344D01*
G02X1502881Y1516546I203J-1D01*
G37*
G36*
G01X1537527D02*
X1540347D01*
G02X1540550Y1516344I1J-202D01*
G01Y1515722D01*
G03X1540600Y1515590I200J0D01*
G02Y1512678I-1664J-1456D01*
G03X1540550Y1512546I150J-132D01*
G01Y1510604D01*
G03X1540600Y1510472I200J0D01*
G02Y1507560I-1664J-1456D01*
G03X1540550Y1507428I150J-132D01*
G01Y1506806D01*
G02X1540347Y1506604I-203J1D01*
G01X1537527D01*
G02X1537324Y1506806I-1J202D01*
G01Y1507428D01*
G03X1537274Y1507560I-200J0D01*
G02Y1510472I1664J1456D01*
G03X1537324Y1510604I-150J132D01*
G01Y1512546D01*
G03X1537274Y1512678I-200J0D01*
G02Y1515590I1664J1456D01*
G03X1537324Y1515722I-150J132D01*
G01Y1516344D01*
G02X1537527Y1516546I203J-1D01*
G37*
G36*
G01X1710755D02*
X1713575D01*
G02X1713778Y1516344I1J-202D01*
G01Y1515722D01*
G03X1713828Y1515590I200J0D01*
G02Y1512678I-1664J-1456D01*
G03X1713778Y1512546I150J-132D01*
G01Y1510604D01*
G03X1713828Y1510472I200J0D01*
G02Y1507560I-1664J-1456D01*
G03X1713778Y1507428I150J-132D01*
G01Y1506806D01*
G02X1713575Y1506604I-203J1D01*
G01X1710755D01*
G02X1710552Y1506806I-1J202D01*
G01Y1507428D01*
G03X1710502Y1507560I-200J0D01*
G02Y1510472I1664J1456D01*
G03X1710552Y1510604I-150J132D01*
G01Y1512546D01*
G03X1710502Y1512678I-200J0D01*
G02Y1515590I1664J1456D01*
G03X1710552Y1515722I-150J132D01*
G01Y1516344D01*
G02X1710755Y1516546I203J-1D01*
G37*
G36*
G01X108472Y1568516D02*
X111292D01*
G02X111494Y1568313I-1J-203D01*
G01Y1567693D01*
G03X111544Y1567561I200J0D01*
G02Y1564645I-1661J-1458D01*
G03X111494Y1564513I150J-132D01*
G01Y1562575D01*
G03X111544Y1562443I200J0D01*
G02Y1559527I-1661J-1458D01*
G03X111494Y1559395I150J-132D01*
G01Y1558775D01*
G02X111292Y1558572I-202J-1D01*
G01X108472D01*
G02X108270Y1558775I1J203D01*
G01Y1559395D01*
G03X108220Y1559527I-200J0D01*
G02Y1562443I1661J1458D01*
G03X108270Y1562575I-150J132D01*
G01Y1564513D01*
G03X108220Y1564645I-200J0D01*
G02Y1567561I1661J1458D01*
G03X108270Y1567693I-150J132D01*
G01Y1568313D01*
G02X108472Y1568516I202J1D01*
G37*
G36*
G01X125795D02*
X128615D01*
G02X128818Y1568313I0J-203D01*
G01Y1567691D01*
G03X128868Y1567559I200J0D01*
G02Y1564647I-1664J-1456D01*
G03X128818Y1564515I150J-132D01*
G01Y1562573D01*
G03X128868Y1562441I200J0D01*
G02Y1559529I-1664J-1456D01*
G03X128818Y1559397I150J-132D01*
G01Y1558775D01*
G02X128615Y1558572I-203J0D01*
G01X125795D01*
G02X125592Y1558775I0J203D01*
G01Y1559397D01*
G03X125542Y1559529I-200J0D01*
G02Y1562441I1664J1456D01*
G03X125592Y1562573I-150J132D01*
G01Y1564515D01*
G03X125542Y1564647I-200J0D01*
G02Y1567559I1664J1456D01*
G03X125592Y1567691I-150J132D01*
G01Y1568313D01*
G02X125795Y1568516I203J0D01*
G37*
G36*
G01X143118D02*
X145938D01*
G02X146140Y1568313I-1J-203D01*
G01Y1567693D01*
G03X146190Y1567561I200J0D01*
G02Y1564645I-1661J-1458D01*
G03X146140Y1564513I150J-132D01*
G01Y1562575D01*
G03X146190Y1562443I200J0D01*
G02Y1559527I-1661J-1458D01*
G03X146140Y1559395I150J-132D01*
G01Y1558775D01*
G02X145938Y1558572I-202J-1D01*
G01X143118D01*
G02X142916Y1558775I1J203D01*
G01Y1559395D01*
G03X142866Y1559527I-200J0D01*
G02Y1562443I1661J1458D01*
G03X142916Y1562575I-150J132D01*
G01Y1564513D01*
G03X142866Y1564645I-200J0D01*
G02Y1567561I1661J1458D01*
G03X142916Y1567693I-150J132D01*
G01Y1568313D01*
G02X143118Y1568516I202J1D01*
G37*
G36*
G01X160440D02*
X163260D01*
G02X163462Y1568313I-1J-203D01*
G01Y1567693D01*
G03X163512Y1567561I200J0D01*
G02Y1564645I-1661J-1458D01*
G03X163462Y1564513I150J-132D01*
G01Y1562575D01*
G03X163512Y1562443I200J0D01*
G02Y1559527I-1661J-1458D01*
G03X163462Y1559395I150J-132D01*
G01Y1558775D01*
G02X163260Y1558572I-202J-1D01*
G01X160440D01*
G02X160238Y1558775I1J203D01*
G01Y1559395D01*
G03X160188Y1559527I-200J0D01*
G02Y1562443I1661J1458D01*
G03X160238Y1562575I-150J132D01*
G01Y1564513D01*
G03X160188Y1564645I-200J0D01*
G02Y1567561I1661J1458D01*
G03X160238Y1567693I-150J132D01*
G01Y1568313D01*
G02X160440Y1568516I202J1D01*
G37*
G36*
G01X281700D02*
X284520D01*
G02X284722Y1568313I-1J-203D01*
G01Y1567693D01*
G03X284772Y1567561I200J0D01*
G02Y1564645I-1661J-1458D01*
G03X284722Y1564513I150J-132D01*
G01Y1562575D01*
G03X284772Y1562443I200J0D01*
G02Y1559527I-1661J-1458D01*
G03X284722Y1559395I150J-132D01*
G01Y1558775D01*
G02X284520Y1558572I-202J-1D01*
G01X281700D01*
G02X281498Y1558775I1J203D01*
G01Y1559395D01*
G03X281448Y1559527I-200J0D01*
G02Y1562443I1661J1458D01*
G03X281498Y1562575I-150J132D01*
G01Y1564513D01*
G03X281448Y1564645I-200J0D01*
G02Y1567561I1661J1458D01*
G03X281498Y1567693I-150J132D01*
G01Y1568313D01*
G02X281700Y1568516I202J1D01*
G37*
G36*
G01X299023D02*
X301843D01*
G02X302046Y1568313I0J-203D01*
G01Y1567691D01*
G03X302096Y1567559I200J0D01*
G02Y1564647I-1664J-1456D01*
G03X302046Y1564515I150J-132D01*
G01Y1562573D01*
G03X302096Y1562441I200J0D01*
G02Y1559529I-1664J-1456D01*
G03X302046Y1559397I150J-132D01*
G01Y1558775D01*
G02X301843Y1558572I-203J0D01*
G01X299023D01*
G02X298820Y1558775I0J203D01*
G01Y1559397D01*
G03X298770Y1559529I-200J0D01*
G02Y1562441I1664J1456D01*
G03X298820Y1562573I-150J132D01*
G01Y1564515D01*
G03X298770Y1564647I-200J0D01*
G02Y1567559I1664J1456D01*
G03X298820Y1567691I-150J132D01*
G01Y1568313D01*
G02X299023Y1568516I203J0D01*
G37*
G36*
G01X316346D02*
X319166D01*
G02X319368Y1568313I-1J-203D01*
G01Y1567693D01*
G03X319418Y1567561I200J0D01*
G02Y1564645I-1661J-1458D01*
G03X319368Y1564513I150J-132D01*
G01Y1562575D01*
G03X319418Y1562443I200J0D01*
G02Y1559527I-1661J-1458D01*
G03X319368Y1559395I150J-132D01*
G01Y1558775D01*
G02X319166Y1558572I-202J-1D01*
G01X316346D01*
G02X316144Y1558775I1J203D01*
G01Y1559395D01*
G03X316094Y1559527I-200J0D01*
G02Y1562443I1661J1458D01*
G03X316144Y1562575I-150J132D01*
G01Y1564513D01*
G03X316094Y1564645I-200J0D01*
G02Y1567561I1661J1458D01*
G03X316144Y1567693I-150J132D01*
G01Y1568313D01*
G02X316346Y1568516I202J1D01*
G37*
G36*
G01X333668D02*
X336488D01*
G02X336690Y1568313I-1J-203D01*
G01Y1567693D01*
G03X336740Y1567561I200J0D01*
G02Y1564645I-1661J-1458D01*
G03X336690Y1564513I150J-132D01*
G01Y1562575D01*
G03X336740Y1562443I200J0D01*
G02Y1559527I-1661J-1458D01*
G03X336690Y1559395I150J-132D01*
G01Y1558775D01*
G02X336488Y1558572I-202J-1D01*
G01X333668D01*
G02X333466Y1558775I1J203D01*
G01Y1559395D01*
G03X333416Y1559527I-200J0D01*
G02Y1562443I1661J1458D01*
G03X333466Y1562575I-150J132D01*
G01Y1564513D01*
G03X333416Y1564645I-200J0D01*
G02Y1567561I1661J1458D01*
G03X333466Y1567693I-150J132D01*
G01Y1568313D01*
G02X333668Y1568516I202J1D01*
G37*
G36*
G01X628157D02*
X630977D01*
G02X631180Y1568313I0J-203D01*
G01Y1567691D01*
G03X631230Y1567559I200J0D01*
G02Y1564647I-1664J-1456D01*
G03X631180Y1564515I150J-132D01*
G01Y1562573D01*
G03X631230Y1562441I200J0D01*
G02Y1559529I-1664J-1456D01*
G03X631180Y1559397I150J-132D01*
G01Y1558775D01*
G02X630977Y1558572I-203J0D01*
G01X628157D01*
G02X627954Y1558775I0J203D01*
G01Y1559397D01*
G03X627904Y1559529I-200J0D01*
G02Y1562441I1664J1456D01*
G03X627954Y1562573I-150J132D01*
G01Y1564515D01*
G03X627904Y1564647I-200J0D01*
G02Y1567559I1664J1456D01*
G03X627954Y1567691I-150J132D01*
G01Y1568313D01*
G02X628157Y1568516I203J0D01*
G37*
G36*
G01X645480D02*
X648300D01*
G02X648502Y1568313I-1J-203D01*
G01Y1567693D01*
G03X648552Y1567561I200J0D01*
G02Y1564645I-1661J-1458D01*
G03X648502Y1564513I150J-132D01*
G01Y1562575D01*
G03X648552Y1562443I200J0D01*
G02Y1559527I-1661J-1458D01*
G03X648502Y1559395I150J-132D01*
G01Y1558775D01*
G02X648300Y1558572I-202J-1D01*
G01X645480D01*
G02X645278Y1558775I1J203D01*
G01Y1559395D01*
G03X645228Y1559527I-200J0D01*
G02Y1562443I1661J1458D01*
G03X645278Y1562575I-150J132D01*
G01Y1564513D01*
G03X645228Y1564645I-200J0D01*
G02Y1567561I1661J1458D01*
G03X645278Y1567693I-150J132D01*
G01Y1568313D01*
G02X645480Y1568516I202J1D01*
G37*
G36*
G01X662803D02*
X665623D01*
G02X665826Y1568313I0J-203D01*
G01Y1567691D01*
G03X665876Y1567559I200J0D01*
G02Y1564647I-1664J-1456D01*
G03X665826Y1564515I150J-132D01*
G01Y1562573D01*
G03X665876Y1562441I200J0D01*
G02Y1559529I-1664J-1456D01*
G03X665826Y1559397I150J-132D01*
G01Y1558775D01*
G02X665623Y1558572I-203J0D01*
G01X662803D01*
G02X662600Y1558775I0J203D01*
G01Y1559397D01*
G03X662550Y1559529I-200J0D01*
G02Y1562441I1664J1456D01*
G03X662600Y1562573I-150J132D01*
G01Y1564515D01*
G03X662550Y1564647I-200J0D01*
G02Y1567559I1664J1456D01*
G03X662600Y1567691I-150J132D01*
G01Y1568313D01*
G02X662803Y1568516I203J0D01*
G37*
G36*
G01X680125D02*
X682945D01*
G02X683148Y1568313I0J-203D01*
G01Y1567691D01*
G03X683198Y1567559I200J0D01*
G02Y1564647I-1664J-1456D01*
G03X683148Y1564515I150J-132D01*
G01Y1562573D01*
G03X683198Y1562441I200J0D01*
G02Y1559529I-1664J-1456D01*
G03X683148Y1559397I150J-132D01*
G01Y1558775D01*
G02X682945Y1558572I-203J0D01*
G01X680125D01*
G02X679922Y1558775I0J203D01*
G01Y1559397D01*
G03X679872Y1559529I-200J0D01*
G02Y1562441I1664J1456D01*
G03X679922Y1562573I-150J132D01*
G01Y1564515D01*
G03X679872Y1564647I-200J0D01*
G02Y1567559I1664J1456D01*
G03X679922Y1567691I-150J132D01*
G01Y1568313D01*
G02X680125Y1568516I203J0D01*
G37*
G36*
G01X1130440D02*
X1133260D01*
G02X1133462Y1568313I-1J-203D01*
G01Y1567693D01*
G03X1133512Y1567561I200J0D01*
G02Y1564645I-1661J-1458D01*
G03X1133462Y1564513I150J-132D01*
G01Y1562575D01*
G03X1133512Y1562443I200J0D01*
G02Y1559527I-1661J-1458D01*
G03X1133462Y1559395I150J-132D01*
G01Y1558775D01*
G02X1133260Y1558572I-202J-1D01*
G01X1130440D01*
G02X1130238Y1558775I1J203D01*
G01Y1559395D01*
G03X1130188Y1559527I-200J0D01*
G02Y1562443I1661J1458D01*
G03X1130238Y1562575I-150J132D01*
G01Y1564513D01*
G03X1130188Y1564645I-200J0D01*
G02Y1567561I1661J1458D01*
G03X1130238Y1567693I-150J132D01*
G01Y1568313D01*
G02X1130440Y1568516I202J1D01*
G37*
G36*
G01X1147763D02*
X1150583D01*
G02X1150786Y1568313I0J-203D01*
G01Y1567691D01*
G03X1150836Y1567559I200J0D01*
G02Y1564647I-1664J-1456D01*
G03X1150786Y1564515I150J-132D01*
G01Y1562573D01*
G03X1150836Y1562441I200J0D01*
G02Y1559529I-1664J-1456D01*
G03X1150786Y1559397I150J-132D01*
G01Y1558775D01*
G02X1150583Y1558572I-203J0D01*
G01X1147763D01*
G02X1147560Y1558775I0J203D01*
G01Y1559397D01*
G03X1147510Y1559529I-200J0D01*
G02Y1562441I1664J1456D01*
G03X1147560Y1562573I-150J132D01*
G01Y1564515D01*
G03X1147510Y1564647I-200J0D01*
G02Y1567559I1664J1456D01*
G03X1147560Y1567691I-150J132D01*
G01Y1568313D01*
G02X1147763Y1568516I203J0D01*
G37*
G36*
G01X1165086D02*
X1167906D01*
G02X1168108Y1568313I-1J-203D01*
G01Y1567693D01*
G03X1168158Y1567561I200J0D01*
G02Y1564645I-1661J-1458D01*
G03X1168108Y1564513I150J-132D01*
G01Y1562575D01*
G03X1168158Y1562443I200J0D01*
G02Y1559527I-1661J-1458D01*
G03X1168108Y1559395I150J-132D01*
G01Y1558775D01*
G02X1167906Y1558572I-202J-1D01*
G01X1165086D01*
G02X1164884Y1558775I1J203D01*
G01Y1559395D01*
G03X1164834Y1559527I-200J0D01*
G02Y1562443I1661J1458D01*
G03X1164884Y1562575I-150J132D01*
G01Y1564513D01*
G03X1164834Y1564645I-200J0D01*
G02Y1567561I1661J1458D01*
G03X1164884Y1567693I-150J132D01*
G01Y1568313D01*
G02X1165086Y1568516I202J1D01*
G37*
G36*
G01X1182408D02*
X1185228D01*
G02X1185430Y1568313I-1J-203D01*
G01Y1567693D01*
G03X1185480Y1567561I200J0D01*
G02Y1564645I-1661J-1458D01*
G03X1185430Y1564513I150J-132D01*
G01Y1562575D01*
G03X1185480Y1562443I200J0D01*
G02Y1559527I-1661J-1458D01*
G03X1185430Y1559395I150J-132D01*
G01Y1558775D01*
G02X1185228Y1558572I-202J-1D01*
G01X1182408D01*
G02X1182206Y1558775I1J203D01*
G01Y1559395D01*
G03X1182156Y1559527I-200J0D01*
G02Y1562443I1661J1458D01*
G03X1182206Y1562575I-150J132D01*
G01Y1564513D01*
G03X1182156Y1564645I-200J0D01*
G02Y1567561I1661J1458D01*
G03X1182206Y1567693I-150J132D01*
G01Y1568313D01*
G02X1182408Y1568516I202J1D01*
G37*
G36*
G01X1303669D02*
X1306489D01*
G02X1306692Y1568313I0J-203D01*
G01Y1567691D01*
G03X1306742Y1567559I200J0D01*
G02Y1564647I-1664J-1456D01*
G03X1306692Y1564515I150J-132D01*
G01Y1562573D01*
G03X1306742Y1562441I200J0D01*
G02Y1559529I-1664J-1456D01*
G03X1306692Y1559397I150J-132D01*
G01Y1558775D01*
G02X1306489Y1558572I-203J0D01*
G01X1303669D01*
G02X1303466Y1558775I0J203D01*
G01Y1559397D01*
G03X1303416Y1559529I-200J0D01*
G02Y1562441I1664J1456D01*
G03X1303466Y1562573I-150J132D01*
G01Y1564515D01*
G03X1303416Y1564647I-200J0D01*
G02Y1567559I1664J1456D01*
G03X1303466Y1567691I-150J132D01*
G01Y1568313D01*
G02X1303669Y1568516I203J0D01*
G37*
G36*
G01X1320992D02*
X1323812D01*
G02X1324014Y1568313I-1J-203D01*
G01Y1567693D01*
G03X1324064Y1567561I200J0D01*
G02Y1564645I-1661J-1458D01*
G03X1324014Y1564513I150J-132D01*
G01Y1562575D01*
G03X1324064Y1562443I200J0D01*
G02Y1559527I-1661J-1458D01*
G03X1324014Y1559395I150J-132D01*
G01Y1558775D01*
G02X1323812Y1558572I-202J-1D01*
G01X1320992D01*
G02X1320790Y1558775I1J203D01*
G01Y1559395D01*
G03X1320740Y1559527I-200J0D01*
G02Y1562443I1661J1458D01*
G03X1320790Y1562575I-150J132D01*
G01Y1564513D01*
G03X1320740Y1564645I-200J0D01*
G02Y1567561I1661J1458D01*
G03X1320790Y1567693I-150J132D01*
G01Y1568313D01*
G02X1320992Y1568516I202J1D01*
G37*
G36*
G01X1338315D02*
X1341135D01*
G02X1341338Y1568313I0J-203D01*
G01Y1567691D01*
G03X1341388Y1567559I200J0D01*
G02Y1564647I-1664J-1456D01*
G03X1341338Y1564515I150J-132D01*
G01Y1562573D01*
G03X1341388Y1562441I200J0D01*
G02Y1559529I-1664J-1456D01*
G03X1341338Y1559397I150J-132D01*
G01Y1558775D01*
G02X1341135Y1558572I-203J0D01*
G01X1338315D01*
G02X1338112Y1558775I0J203D01*
G01Y1559397D01*
G03X1338062Y1559529I-200J0D01*
G02Y1562441I1664J1456D01*
G03X1338112Y1562573I-150J132D01*
G01Y1564515D01*
G03X1338062Y1564647I-200J0D01*
G02Y1567559I1664J1456D01*
G03X1338112Y1567691I-150J132D01*
G01Y1568313D01*
G02X1338315Y1568516I203J0D01*
G37*
G36*
G01X1355637D02*
X1358457D01*
G02X1358660Y1568313I0J-203D01*
G01Y1567691D01*
G03X1358710Y1567559I200J0D01*
G02Y1564647I-1664J-1456D01*
G03X1358660Y1564515I150J-132D01*
G01Y1562573D01*
G03X1358710Y1562441I200J0D01*
G02Y1559529I-1664J-1456D01*
G03X1358660Y1559397I150J-132D01*
G01Y1558775D01*
G02X1358457Y1558572I-203J0D01*
G01X1355637D01*
G02X1355434Y1558775I0J203D01*
G01Y1559397D01*
G03X1355384Y1559529I-200J0D01*
G02Y1562441I1664J1456D01*
G03X1355434Y1562573I-150J132D01*
G01Y1564515D01*
G03X1355384Y1564647I-200J0D01*
G02Y1567559I1664J1456D01*
G03X1355434Y1567691I-150J132D01*
G01Y1568313D01*
G02X1355637Y1568516I203J0D01*
G37*
G36*
G01X1476897D02*
X1479717D01*
G02X1479920Y1568313I0J-203D01*
G01Y1567691D01*
G03X1479970Y1567559I200J0D01*
G02Y1564647I-1664J-1456D01*
G03X1479920Y1564515I150J-132D01*
G01Y1562573D01*
G03X1479970Y1562441I200J0D01*
G02Y1559529I-1664J-1456D01*
G03X1479920Y1559397I150J-132D01*
G01Y1558775D01*
G02X1479717Y1558572I-203J0D01*
G01X1476897D01*
G02X1476694Y1558775I0J203D01*
G01Y1559397D01*
G03X1476644Y1559529I-200J0D01*
G02Y1562441I1664J1456D01*
G03X1476694Y1562573I-150J132D01*
G01Y1564515D01*
G03X1476644Y1564647I-200J0D01*
G02Y1567559I1664J1456D01*
G03X1476694Y1567691I-150J132D01*
G01Y1568313D01*
G02X1476897Y1568516I203J0D01*
G37*
G36*
G01X1650125D02*
X1652945D01*
G02X1653148Y1568313I0J-203D01*
G01Y1567691D01*
G03X1653198Y1567559I200J0D01*
G02Y1564647I-1664J-1456D01*
G03X1653148Y1564515I150J-132D01*
G01Y1562573D01*
G03X1653198Y1562441I200J0D01*
G02Y1559529I-1664J-1456D01*
G03X1653148Y1559397I150J-132D01*
G01Y1558775D01*
G02X1652945Y1558572I-203J0D01*
G01X1650125D01*
G02X1649922Y1558775I0J203D01*
G01Y1559397D01*
G03X1649872Y1559529I-200J0D01*
G02Y1562441I1664J1456D01*
G03X1649922Y1562573I-150J132D01*
G01Y1564515D01*
G03X1649872Y1564647I-200J0D01*
G02Y1567559I1664J1456D01*
G03X1649922Y1567691I-150J132D01*
G01Y1568313D01*
G02X1650125Y1568516I203J0D01*
G37*
G36*
G01X1667448D02*
X1670268D01*
G02X1670470Y1568313I-1J-203D01*
G01Y1567693D01*
G03X1670520Y1567561I200J0D01*
G02Y1564645I-1661J-1458D01*
G03X1670470Y1564513I150J-132D01*
G01Y1562575D01*
G03X1670520Y1562443I200J0D01*
G02Y1559527I-1661J-1458D01*
G03X1670470Y1559395I150J-132D01*
G01Y1558775D01*
G02X1670268Y1558572I-202J-1D01*
G01X1667448D01*
G02X1667246Y1558775I1J203D01*
G01Y1559395D01*
G03X1667196Y1559527I-200J0D01*
G02Y1562443I1661J1458D01*
G03X1667246Y1562575I-150J132D01*
G01Y1564513D01*
G03X1667196Y1564645I-200J0D01*
G02Y1567561I1661J1458D01*
G03X1667246Y1567693I-150J132D01*
G01Y1568313D01*
G02X1667448Y1568516I202J1D01*
G37*
G36*
G01X1684771D02*
X1687591D01*
G02X1687794Y1568313I0J-203D01*
G01Y1567691D01*
G03X1687844Y1567559I200J0D01*
G02Y1564647I-1664J-1456D01*
G03X1687794Y1564515I150J-132D01*
G01Y1562573D01*
G03X1687844Y1562441I200J0D01*
G02Y1559529I-1664J-1456D01*
G03X1687794Y1559397I150J-132D01*
G01Y1558775D01*
G02X1687591Y1558572I-203J0D01*
G01X1684771D01*
G02X1684568Y1558775I0J203D01*
G01Y1559397D01*
G03X1684518Y1559529I-200J0D01*
G02Y1562441I1664J1456D01*
G03X1684568Y1562573I-150J132D01*
G01Y1564515D01*
G03X1684518Y1564647I-200J0D01*
G02Y1567559I1664J1456D01*
G03X1684568Y1567691I-150J132D01*
G01Y1568313D01*
G02X1684771Y1568516I203J0D01*
G37*
G36*
G01X1702093D02*
X1704913D01*
G02X1705116Y1568313I0J-203D01*
G01Y1567691D01*
G03X1705166Y1567559I200J0D01*
G02Y1564647I-1664J-1456D01*
G03X1705116Y1564515I150J-132D01*
G01Y1562573D01*
G03X1705166Y1562441I200J0D01*
G02Y1559529I-1664J-1456D01*
G03X1705116Y1559397I150J-132D01*
G01Y1558775D01*
G02X1704913Y1558572I-203J0D01*
G01X1702093D01*
G02X1701890Y1558775I0J203D01*
G01Y1559397D01*
G03X1701840Y1559529I-200J0D01*
G02Y1562441I1664J1456D01*
G03X1701890Y1562573I-150J132D01*
G01Y1564515D01*
G03X1701840Y1564647I-200J0D01*
G02Y1567559I1664J1456D01*
G03X1701890Y1567691I-150J132D01*
G01Y1568313D01*
G02X1702093Y1568516I203J0D01*
G37*
G36*
G01X134456Y1572846D02*
X137276D01*
G02X137478Y1572644I0J-202D01*
G01Y1572024D01*
G03X137528Y1571892I200J0D01*
G02Y1568976I-1661J-1458D01*
G03X137478Y1568844I150J-132D01*
G01Y1566905D01*
G03X137528Y1566773I200J0D01*
G02Y1563857I-1661J-1458D01*
G03X137478Y1563725I150J-132D01*
G01Y1563106D01*
G02X137276Y1562904I-202J0D01*
G01X134456D01*
G02X134254Y1563106I0J202D01*
G01Y1563725D01*
G03X134204Y1563857I-200J0D01*
G02Y1566773I1661J1458D01*
G03X134254Y1566905I-150J132D01*
G01Y1568844D01*
G03X134204Y1568976I-200J0D01*
G02Y1571892I1661J1458D01*
G03X134254Y1572024I-150J132D01*
G01Y1572644D01*
G02X134456Y1572846I202J0D01*
G37*
G36*
G01X169102D02*
X171922D01*
G02X172124Y1572644I0J-202D01*
G01Y1572024D01*
G03X172174Y1571892I200J0D01*
G02Y1568976I-1661J-1458D01*
G03X172124Y1568844I150J-132D01*
G01Y1566905D01*
G03X172174Y1566773I200J0D01*
G02Y1563857I-1661J-1458D01*
G03X172124Y1563725I150J-132D01*
G01Y1563106D01*
G02X171922Y1562904I-202J0D01*
G01X169102D01*
G02X168900Y1563106I0J202D01*
G01Y1563725D01*
G03X168850Y1563857I-200J0D01*
G02Y1566773I1661J1458D01*
G03X168900Y1566905I-150J132D01*
G01Y1568844D01*
G03X168850Y1568976I-200J0D01*
G02Y1571892I1661J1458D01*
G03X168900Y1572024I-150J132D01*
G01Y1572644D01*
G02X169102Y1572846I202J0D01*
G37*
G36*
G01X307684D02*
X310504D01*
G02X310706Y1572644I0J-202D01*
G01Y1572024D01*
G03X310756Y1571892I200J0D01*
G02Y1568976I-1661J-1458D01*
G03X310706Y1568844I150J-132D01*
G01Y1566905D01*
G03X310756Y1566773I200J0D01*
G02Y1563857I-1661J-1458D01*
G03X310706Y1563725I150J-132D01*
G01Y1563106D01*
G02X310504Y1562904I-202J0D01*
G01X307684D01*
G02X307482Y1563106I0J202D01*
G01Y1563725D01*
G03X307432Y1563857I-200J0D01*
G02Y1566773I1661J1458D01*
G03X307482Y1566905I-150J132D01*
G01Y1568844D01*
G03X307432Y1568976I-200J0D01*
G02Y1571892I1661J1458D01*
G03X307482Y1572024I-150J132D01*
G01Y1572644D01*
G02X307684Y1572846I202J0D01*
G37*
G36*
G01X342330D02*
X345150D01*
G02X345352Y1572644I0J-202D01*
G01Y1572024D01*
G03X345402Y1571892I200J0D01*
G02Y1568976I-1661J-1458D01*
G03X345352Y1568844I150J-132D01*
G01Y1566905D01*
G03X345402Y1566773I200J0D01*
G02Y1563857I-1661J-1458D01*
G03X345352Y1563725I150J-132D01*
G01Y1563106D01*
G02X345150Y1562904I-202J0D01*
G01X342330D01*
G02X342128Y1563106I0J202D01*
G01Y1563725D01*
G03X342078Y1563857I-200J0D01*
G02Y1566773I1661J1458D01*
G03X342128Y1566905I-150J132D01*
G01Y1568844D01*
G03X342078Y1568976I-200J0D01*
G02Y1571892I1661J1458D01*
G03X342128Y1572024I-150J132D01*
G01Y1572644D01*
G02X342330Y1572846I202J0D01*
G37*
G36*
G01X636818D02*
X639638D01*
G02X639840Y1572644I0J-202D01*
G01Y1572024D01*
G03X639890Y1571892I200J0D01*
G02Y1568976I-1661J-1458D01*
G03X639840Y1568844I150J-132D01*
G01Y1566905D01*
G03X639890Y1566773I200J0D01*
G02Y1563857I-1661J-1458D01*
G03X639840Y1563725I150J-132D01*
G01Y1563106D01*
G02X639638Y1562904I-202J0D01*
G01X636818D01*
G02X636616Y1563106I0J202D01*
G01Y1563725D01*
G03X636566Y1563857I-200J0D01*
G02Y1566773I1661J1458D01*
G03X636616Y1566905I-150J132D01*
G01Y1568844D01*
G03X636566Y1568976I-200J0D01*
G02Y1571892I1661J1458D01*
G03X636616Y1572024I-150J132D01*
G01Y1572644D01*
G02X636818Y1572846I202J0D01*
G37*
G36*
G01X671464D02*
X674284D01*
G02X674486Y1572644I0J-202D01*
G01Y1572024D01*
G03X674536Y1571892I200J0D01*
G02Y1568976I-1661J-1458D01*
G03X674486Y1568844I150J-132D01*
G01Y1566905D01*
G03X674536Y1566773I200J0D01*
G02Y1563857I-1661J-1458D01*
G03X674486Y1563725I150J-132D01*
G01Y1563106D01*
G02X674284Y1562904I-202J0D01*
G01X671464D01*
G02X671262Y1563106I0J202D01*
G01Y1563725D01*
G03X671212Y1563857I-200J0D01*
G02Y1566773I1661J1458D01*
G03X671262Y1566905I-150J132D01*
G01Y1568844D01*
G03X671212Y1568976I-200J0D01*
G02Y1571892I1661J1458D01*
G03X671262Y1572024I-150J132D01*
G01Y1572644D01*
G02X671464Y1572846I202J0D01*
G37*
G36*
G01X1156424D02*
X1159244D01*
G02X1159446Y1572644I0J-202D01*
G01Y1572024D01*
G03X1159496Y1571892I200J0D01*
G02Y1568976I-1661J-1458D01*
G03X1159446Y1568844I150J-132D01*
G01Y1566905D01*
G03X1159496Y1566773I200J0D01*
G02Y1563857I-1661J-1458D01*
G03X1159446Y1563725I150J-132D01*
G01Y1563106D01*
G02X1159244Y1562904I-202J0D01*
G01X1156424D01*
G02X1156222Y1563106I0J202D01*
G01Y1563725D01*
G03X1156172Y1563857I-200J0D01*
G02Y1566773I1661J1458D01*
G03X1156222Y1566905I-150J132D01*
G01Y1568844D01*
G03X1156172Y1568976I-200J0D01*
G02Y1571892I1661J1458D01*
G03X1156222Y1572024I-150J132D01*
G01Y1572644D01*
G02X1156424Y1572846I202J0D01*
G37*
G36*
G01X1191070D02*
X1193890D01*
G02X1194092Y1572644I0J-202D01*
G01Y1572024D01*
G03X1194142Y1571892I200J0D01*
G02Y1568976I-1661J-1458D01*
G03X1194092Y1568844I150J-132D01*
G01Y1566905D01*
G03X1194142Y1566773I200J0D01*
G02Y1563857I-1661J-1458D01*
G03X1194092Y1563725I150J-132D01*
G01Y1563106D01*
G02X1193890Y1562904I-202J0D01*
G01X1191070D01*
G02X1190868Y1563106I0J202D01*
G01Y1563725D01*
G03X1190818Y1563857I-200J0D01*
G02Y1566773I1661J1458D01*
G03X1190868Y1566905I-150J132D01*
G01Y1568844D01*
G03X1190818Y1568976I-200J0D01*
G02Y1571892I1661J1458D01*
G03X1190868Y1572024I-150J132D01*
G01Y1572644D01*
G02X1191070Y1572846I202J0D01*
G37*
G36*
G01X1312330D02*
X1315150D01*
G02X1315352Y1572644I0J-202D01*
G01Y1572024D01*
G03X1315402Y1571892I200J0D01*
G02Y1568976I-1661J-1458D01*
G03X1315352Y1568844I150J-132D01*
G01Y1566905D01*
G03X1315402Y1566773I200J0D01*
G02Y1563857I-1661J-1458D01*
G03X1315352Y1563725I150J-132D01*
G01Y1563106D01*
G02X1315150Y1562904I-202J0D01*
G01X1312330D01*
G02X1312128Y1563106I0J202D01*
G01Y1563725D01*
G03X1312078Y1563857I-200J0D01*
G02Y1566773I1661J1458D01*
G03X1312128Y1566905I-150J132D01*
G01Y1568844D01*
G03X1312078Y1568976I-200J0D01*
G02Y1571892I1661J1458D01*
G03X1312128Y1572024I-150J132D01*
G01Y1572644D01*
G02X1312330Y1572846I202J0D01*
G37*
G36*
G01X1346976D02*
X1349796D01*
G02X1349998Y1572644I0J-202D01*
G01Y1572024D01*
G03X1350048Y1571892I200J0D01*
G02Y1568976I-1661J-1458D01*
G03X1349998Y1568844I150J-132D01*
G01Y1566905D01*
G03X1350048Y1566773I200J0D01*
G02Y1563857I-1661J-1458D01*
G03X1349998Y1563725I150J-132D01*
G01Y1563106D01*
G02X1349796Y1562904I-202J0D01*
G01X1346976D01*
G02X1346774Y1563106I0J202D01*
G01Y1563725D01*
G03X1346724Y1563857I-200J0D01*
G02Y1566773I1661J1458D01*
G03X1346774Y1566905I-150J132D01*
G01Y1568844D01*
G03X1346724Y1568976I-200J0D01*
G02Y1571892I1661J1458D01*
G03X1346774Y1572024I-150J132D01*
G01Y1572644D01*
G02X1346976Y1572846I202J0D01*
G37*
G36*
G01X1658786D02*
X1661606D01*
G02X1661808Y1572644I0J-202D01*
G01Y1572024D01*
G03X1661858Y1571892I200J0D01*
G02Y1568976I-1661J-1458D01*
G03X1661808Y1568844I150J-132D01*
G01Y1566905D01*
G03X1661858Y1566773I200J0D01*
G02Y1563857I-1661J-1458D01*
G03X1661808Y1563725I150J-132D01*
G01Y1563106D01*
G02X1661606Y1562904I-202J0D01*
G01X1658786D01*
G02X1658584Y1563106I0J202D01*
G01Y1563725D01*
G03X1658534Y1563857I-200J0D01*
G02Y1566773I1661J1458D01*
G03X1658584Y1566905I-150J132D01*
G01Y1568844D01*
G03X1658534Y1568976I-200J0D01*
G02Y1571892I1661J1458D01*
G03X1658584Y1572024I-150J132D01*
G01Y1572644D01*
G02X1658786Y1572846I202J0D01*
G37*
G36*
G01X1693432D02*
X1696252D01*
G02X1696454Y1572644I0J-202D01*
G01Y1572024D01*
G03X1696504Y1571892I200J0D01*
G02Y1568976I-1661J-1458D01*
G03X1696454Y1568844I150J-132D01*
G01Y1566905D01*
G03X1696504Y1566773I200J0D01*
G02Y1563857I-1661J-1458D01*
G03X1696454Y1563725I150J-132D01*
G01Y1563106D01*
G02X1696252Y1562904I-202J0D01*
G01X1693432D01*
G02X1693230Y1563106I0J202D01*
G01Y1563725D01*
G03X1693180Y1563857I-200J0D01*
G02Y1566773I1661J1458D01*
G03X1693230Y1566905I-150J132D01*
G01Y1568844D01*
G03X1693180Y1568976I-200J0D01*
G02Y1571892I1661J1458D01*
G03X1693230Y1572024I-150J132D01*
G01Y1572644D01*
G02X1693432Y1572846I202J0D01*
G37*
G36*
G01X117133D02*
X119953D01*
G02X120156Y1572644I1J-202D01*
G01Y1572022D01*
G03X120206Y1571890I200J0D01*
G02Y1568978I-1664J-1456D01*
G03X120156Y1568846I150J-132D01*
G01Y1566903D01*
G03X120206Y1566771I200J0D01*
G02Y1563859I-1664J-1456D01*
G03X120156Y1563727I150J-132D01*
G01Y1563106D01*
G02X119953Y1562904I-203J1D01*
G01X117133D01*
G02X116930Y1563106I-1J202D01*
G01Y1563727D01*
G03X116880Y1563859I-200J0D01*
G02Y1566771I1664J1456D01*
G03X116930Y1566903I-150J132D01*
G01Y1568846D01*
G03X116880Y1568978I-200J0D01*
G02Y1571890I1664J1456D01*
G03X116930Y1572022I-150J132D01*
G01Y1572644D01*
G02X117133Y1572846I203J-1D01*
G37*
G36*
G01X151779D02*
X154599D01*
G02X154802Y1572644I1J-202D01*
G01Y1572022D01*
G03X154852Y1571890I200J0D01*
G02Y1568978I-1664J-1456D01*
G03X154802Y1568846I150J-132D01*
G01Y1566903D01*
G03X154852Y1566771I200J0D01*
G02Y1563859I-1664J-1456D01*
G03X154802Y1563727I150J-132D01*
G01Y1563106D01*
G02X154599Y1562904I-203J1D01*
G01X151779D01*
G02X151576Y1563106I-1J202D01*
G01Y1563727D01*
G03X151526Y1563859I-200J0D01*
G02Y1566771I1664J1456D01*
G03X151576Y1566903I-150J132D01*
G01Y1568846D01*
G03X151526Y1568978I-200J0D01*
G02Y1571890I1664J1456D01*
G03X151576Y1572022I-150J132D01*
G01Y1572644D01*
G02X151779Y1572846I203J-1D01*
G37*
G36*
G01X290361D02*
X293181D01*
G02X293384Y1572644I1J-202D01*
G01Y1572022D01*
G03X293434Y1571890I200J0D01*
G02Y1568978I-1664J-1456D01*
G03X293384Y1568846I150J-132D01*
G01Y1566903D01*
G03X293434Y1566771I200J0D01*
G02Y1563859I-1664J-1456D01*
G03X293384Y1563727I150J-132D01*
G01Y1563106D01*
G02X293181Y1562904I-203J1D01*
G01X290361D01*
G02X290158Y1563106I-1J202D01*
G01Y1563727D01*
G03X290108Y1563859I-200J0D01*
G02Y1566771I1664J1456D01*
G03X290158Y1566903I-150J132D01*
G01Y1568846D01*
G03X290108Y1568978I-200J0D01*
G02Y1571890I1664J1456D01*
G03X290158Y1572022I-150J132D01*
G01Y1572644D01*
G02X290361Y1572846I203J-1D01*
G37*
G36*
G01X325007D02*
X327827D01*
G02X328030Y1572644I1J-202D01*
G01Y1572022D01*
G03X328080Y1571890I200J0D01*
G02Y1568978I-1664J-1456D01*
G03X328030Y1568846I150J-132D01*
G01Y1566903D01*
G03X328080Y1566771I200J0D01*
G02Y1563859I-1664J-1456D01*
G03X328030Y1563727I150J-132D01*
G01Y1563106D01*
G02X327827Y1562904I-203J1D01*
G01X325007D01*
G02X324804Y1563106I-1J202D01*
G01Y1563727D01*
G03X324754Y1563859I-200J0D01*
G02Y1566771I1664J1456D01*
G03X324804Y1566903I-150J132D01*
G01Y1568846D01*
G03X324754Y1568978I-200J0D01*
G02Y1571890I1664J1456D01*
G03X324804Y1572022I-150J132D01*
G01Y1572644D01*
G02X325007Y1572846I203J-1D01*
G37*
G36*
G01X515559D02*
X518379D01*
G02X518582Y1572644I1J-202D01*
G01Y1572022D01*
G03X518632Y1571890I200J0D01*
G02Y1568978I-1664J-1456D01*
G03X518582Y1568846I150J-132D01*
G01Y1566903D01*
G03X518632Y1566771I200J0D01*
G02Y1563859I-1664J-1456D01*
G03X518582Y1563727I150J-132D01*
G01Y1563106D01*
G02X518379Y1562904I-203J1D01*
G01X515559D01*
G02X515356Y1563106I-1J202D01*
G01Y1563727D01*
G03X515306Y1563859I-200J0D01*
G02Y1566771I1664J1456D01*
G03X515356Y1566903I-150J132D01*
G01Y1568846D01*
G03X515306Y1568978I-200J0D01*
G02Y1571890I1664J1456D01*
G03X515356Y1572022I-150J132D01*
G01Y1572644D01*
G02X515559Y1572846I203J-1D01*
G37*
G36*
G01X654141D02*
X656961D01*
G02X657164Y1572644I1J-202D01*
G01Y1572022D01*
G03X657214Y1571890I200J0D01*
G02Y1568978I-1664J-1456D01*
G03X657164Y1568846I150J-132D01*
G01Y1566903D01*
G03X657214Y1566771I200J0D01*
G02Y1563859I-1664J-1456D01*
G03X657164Y1563727I150J-132D01*
G01Y1563106D01*
G02X656961Y1562904I-203J1D01*
G01X654141D01*
G02X653938Y1563106I-1J202D01*
G01Y1563727D01*
G03X653888Y1563859I-200J0D01*
G02Y1566771I1664J1456D01*
G03X653938Y1566903I-150J132D01*
G01Y1568846D01*
G03X653888Y1568978I-200J0D01*
G02Y1571890I1664J1456D01*
G03X653938Y1572022I-150J132D01*
G01Y1572644D01*
G02X654141Y1572846I203J-1D01*
G37*
G36*
G01X688787D02*
X691607D01*
G02X691810Y1572644I1J-202D01*
G01Y1572022D01*
G03X691860Y1571890I200J0D01*
G02Y1568978I-1664J-1456D01*
G03X691810Y1568846I150J-132D01*
G01Y1566903D01*
G03X691860Y1566771I200J0D01*
G02Y1563859I-1664J-1456D01*
G03X691810Y1563727I150J-132D01*
G01Y1563106D01*
G02X691607Y1562904I-203J1D01*
G01X688787D01*
G02X688584Y1563106I-1J202D01*
G01Y1563727D01*
G03X688534Y1563859I-200J0D01*
G02Y1566771I1664J1456D01*
G03X688584Y1566903I-150J132D01*
G01Y1568846D01*
G03X688534Y1568978I-200J0D01*
G02Y1571890I1664J1456D01*
G03X688584Y1572022I-150J132D01*
G01Y1572644D01*
G02X688787Y1572846I203J-1D01*
G37*
G36*
G01X1139101D02*
X1141921D01*
G02X1142124Y1572644I1J-202D01*
G01Y1572022D01*
G03X1142174Y1571890I200J0D01*
G02Y1568978I-1664J-1456D01*
G03X1142124Y1568846I150J-132D01*
G01Y1566903D01*
G03X1142174Y1566771I200J0D01*
G02Y1563859I-1664J-1456D01*
G03X1142124Y1563727I150J-132D01*
G01Y1563106D01*
G02X1141921Y1562904I-203J1D01*
G01X1139101D01*
G02X1138898Y1563106I-1J202D01*
G01Y1563727D01*
G03X1138848Y1563859I-200J0D01*
G02Y1566771I1664J1456D01*
G03X1138898Y1566903I-150J132D01*
G01Y1568846D01*
G03X1138848Y1568978I-200J0D01*
G02Y1571890I1664J1456D01*
G03X1138898Y1572022I-150J132D01*
G01Y1572644D01*
G02X1139101Y1572846I203J-1D01*
G37*
G36*
G01X1173747D02*
X1176567D01*
G02X1176770Y1572644I1J-202D01*
G01Y1572022D01*
G03X1176820Y1571890I200J0D01*
G02Y1568978I-1664J-1456D01*
G03X1176770Y1568846I150J-132D01*
G01Y1566903D01*
G03X1176820Y1566771I200J0D01*
G02Y1563859I-1664J-1456D01*
G03X1176770Y1563727I150J-132D01*
G01Y1563106D01*
G02X1176567Y1562904I-203J1D01*
G01X1173747D01*
G02X1173544Y1563106I-1J202D01*
G01Y1563727D01*
G03X1173494Y1563859I-200J0D01*
G02Y1566771I1664J1456D01*
G03X1173544Y1566903I-150J132D01*
G01Y1568846D01*
G03X1173494Y1568978I-200J0D01*
G02Y1571890I1664J1456D01*
G03X1173544Y1572022I-150J132D01*
G01Y1572644D01*
G02X1173747Y1572846I203J-1D01*
G37*
G36*
G01X1329653D02*
X1332473D01*
G02X1332676Y1572644I1J-202D01*
G01Y1572022D01*
G03X1332726Y1571890I200J0D01*
G02Y1568978I-1664J-1456D01*
G03X1332676Y1568846I150J-132D01*
G01Y1566903D01*
G03X1332726Y1566771I200J0D01*
G02Y1563859I-1664J-1456D01*
G03X1332676Y1563727I150J-132D01*
G01Y1563106D01*
G02X1332473Y1562904I-203J1D01*
G01X1329653D01*
G02X1329450Y1563106I-1J202D01*
G01Y1563727D01*
G03X1329400Y1563859I-200J0D01*
G02Y1566771I1664J1456D01*
G03X1329450Y1566903I-150J132D01*
G01Y1568846D01*
G03X1329400Y1568978I-200J0D01*
G02Y1571890I1664J1456D01*
G03X1329450Y1572022I-150J132D01*
G01Y1572644D01*
G02X1329653Y1572846I203J-1D01*
G37*
G36*
G01X1364299D02*
X1367119D01*
G02X1367322Y1572644I1J-202D01*
G01Y1572022D01*
G03X1367372Y1571890I200J0D01*
G02Y1568978I-1664J-1456D01*
G03X1367322Y1568846I150J-132D01*
G01Y1566903D01*
G03X1367372Y1566771I200J0D01*
G02Y1563859I-1664J-1456D01*
G03X1367322Y1563727I150J-132D01*
G01Y1563106D01*
G02X1367119Y1562904I-203J1D01*
G01X1364299D01*
G02X1364096Y1563106I-1J202D01*
G01Y1563727D01*
G03X1364046Y1563859I-200J0D01*
G02Y1566771I1664J1456D01*
G03X1364096Y1566903I-150J132D01*
G01Y1568846D01*
G03X1364046Y1568978I-200J0D01*
G02Y1571890I1664J1456D01*
G03X1364096Y1572022I-150J132D01*
G01Y1572644D01*
G02X1364299Y1572846I203J-1D01*
G37*
G36*
G01X1676109D02*
X1678929D01*
G02X1679132Y1572644I1J-202D01*
G01Y1572022D01*
G03X1679182Y1571890I200J0D01*
G02Y1568978I-1664J-1456D01*
G03X1679132Y1568846I150J-132D01*
G01Y1566903D01*
G03X1679182Y1566771I200J0D01*
G02Y1563859I-1664J-1456D01*
G03X1679132Y1563727I150J-132D01*
G01Y1563106D01*
G02X1678929Y1562904I-203J1D01*
G01X1676109D01*
G02X1675906Y1563106I-1J202D01*
G01Y1563727D01*
G03X1675856Y1563859I-200J0D01*
G02Y1566771I1664J1456D01*
G03X1675906Y1566903I-150J132D01*
G01Y1568846D01*
G03X1675856Y1568978I-200J0D01*
G02Y1571890I1664J1456D01*
G03X1675906Y1572022I-150J132D01*
G01Y1572644D01*
G02X1676109Y1572846I203J-1D01*
G37*
G36*
G01X1710755D02*
X1713575D01*
G02X1713778Y1572644I1J-202D01*
G01Y1572022D01*
G03X1713828Y1571890I200J0D01*
G02Y1568978I-1664J-1456D01*
G03X1713778Y1568846I150J-132D01*
G01Y1566903D01*
G03X1713828Y1566771I200J0D01*
G02Y1563859I-1664J-1456D01*
G03X1713778Y1563727I150J-132D01*
G01Y1563106D01*
G02X1713575Y1562904I-203J1D01*
G01X1710755D01*
G02X1710552Y1563106I-1J202D01*
G01Y1563727D01*
G03X1710502Y1563859I-200J0D01*
G02Y1566771I1664J1456D01*
G03X1710552Y1566903I-150J132D01*
G01Y1568846D01*
G03X1710502Y1568978I-200J0D01*
G02Y1571890I1664J1456D01*
G03X1710552Y1572022I-150J132D01*
G01Y1572644D01*
G02X1710755Y1572846I203J-1D01*
G37*
G36*
G01X108472Y1583870D02*
X111292D01*
G02X111494Y1583667I-1J-203D01*
G01Y1583047D01*
G03X111544Y1582915I200J0D01*
G02Y1579999I-1661J-1458D01*
G03X111494Y1579867I150J-132D01*
G01Y1577929D01*
G03X111544Y1577797I200J0D01*
G02Y1574881I-1661J-1458D01*
G03X111494Y1574749I150J-132D01*
G01Y1574129D01*
G02X111292Y1573926I-202J-1D01*
G01X108472D01*
G02X108270Y1574129I1J203D01*
G01Y1574749D01*
G03X108220Y1574881I-200J0D01*
G02Y1577797I1661J1458D01*
G03X108270Y1577929I-150J132D01*
G01Y1579867D01*
G03X108220Y1579999I-200J0D01*
G02Y1582915I1661J1458D01*
G03X108270Y1583047I-150J132D01*
G01Y1583667D01*
G02X108472Y1583870I202J1D01*
G37*
G36*
G01X125795D02*
X128615D01*
G02X128818Y1583667I0J-203D01*
G01Y1583045D01*
G03X128868Y1582913I200J0D01*
G02Y1580001I-1664J-1456D01*
G03X128818Y1579869I150J-132D01*
G01Y1577927D01*
G03X128868Y1577795I200J0D01*
G02Y1574883I-1664J-1456D01*
G03X128818Y1574751I150J-132D01*
G01Y1574129D01*
G02X128615Y1573926I-203J0D01*
G01X125795D01*
G02X125592Y1574129I0J203D01*
G01Y1574751D01*
G03X125542Y1574883I-200J0D01*
G02Y1577795I1664J1456D01*
G03X125592Y1577927I-150J132D01*
G01Y1579869D01*
G03X125542Y1580001I-200J0D01*
G02Y1582913I1664J1456D01*
G03X125592Y1583045I-150J132D01*
G01Y1583667D01*
G02X125795Y1583870I203J0D01*
G37*
G36*
G01X143118D02*
X145938D01*
G02X146140Y1583667I-1J-203D01*
G01Y1583047D01*
G03X146190Y1582915I200J0D01*
G02Y1579999I-1661J-1458D01*
G03X146140Y1579867I150J-132D01*
G01Y1577929D01*
G03X146190Y1577797I200J0D01*
G02Y1574881I-1661J-1458D01*
G03X146140Y1574749I150J-132D01*
G01Y1574129D01*
G02X145938Y1573926I-202J-1D01*
G01X143118D01*
G02X142916Y1574129I1J203D01*
G01Y1574749D01*
G03X142866Y1574881I-200J0D01*
G02Y1577797I1661J1458D01*
G03X142916Y1577929I-150J132D01*
G01Y1579867D01*
G03X142866Y1579999I-200J0D01*
G02Y1582915I1661J1458D01*
G03X142916Y1583047I-150J132D01*
G01Y1583667D01*
G02X143118Y1583870I202J1D01*
G37*
G36*
G01X160440D02*
X163260D01*
G02X163462Y1583667I-1J-203D01*
G01Y1583047D01*
G03X163512Y1582915I200J0D01*
G02Y1579999I-1661J-1458D01*
G03X163462Y1579867I150J-132D01*
G01Y1577929D01*
G03X163512Y1577797I200J0D01*
G02Y1574881I-1661J-1458D01*
G03X163462Y1574749I150J-132D01*
G01Y1574129D01*
G02X163260Y1573926I-202J-1D01*
G01X160440D01*
G02X160238Y1574129I1J203D01*
G01Y1574749D01*
G03X160188Y1574881I-200J0D01*
G02Y1577797I1661J1458D01*
G03X160238Y1577929I-150J132D01*
G01Y1579867D01*
G03X160188Y1579999I-200J0D01*
G02Y1582915I1661J1458D01*
G03X160238Y1583047I-150J132D01*
G01Y1583667D01*
G02X160440Y1583870I202J1D01*
G37*
G36*
G01X281700D02*
X284520D01*
G02X284722Y1583667I-1J-203D01*
G01Y1583047D01*
G03X284772Y1582915I200J0D01*
G02Y1579999I-1661J-1458D01*
G03X284722Y1579867I150J-132D01*
G01Y1577929D01*
G03X284772Y1577797I200J0D01*
G02Y1574881I-1661J-1458D01*
G03X284722Y1574749I150J-132D01*
G01Y1574129D01*
G02X284520Y1573926I-202J-1D01*
G01X281700D01*
G02X281498Y1574129I1J203D01*
G01Y1574749D01*
G03X281448Y1574881I-200J0D01*
G02Y1577797I1661J1458D01*
G03X281498Y1577929I-150J132D01*
G01Y1579867D01*
G03X281448Y1579999I-200J0D01*
G02Y1582915I1661J1458D01*
G03X281498Y1583047I-150J132D01*
G01Y1583667D01*
G02X281700Y1583870I202J1D01*
G37*
G36*
G01X299023D02*
X301843D01*
G02X302046Y1583667I0J-203D01*
G01Y1583045D01*
G03X302096Y1582913I200J0D01*
G02Y1580001I-1664J-1456D01*
G03X302046Y1579869I150J-132D01*
G01Y1577927D01*
G03X302096Y1577795I200J0D01*
G02Y1574883I-1664J-1456D01*
G03X302046Y1574751I150J-132D01*
G01Y1574129D01*
G02X301843Y1573926I-203J0D01*
G01X299023D01*
G02X298820Y1574129I0J203D01*
G01Y1574751D01*
G03X298770Y1574883I-200J0D01*
G02Y1577795I1664J1456D01*
G03X298820Y1577927I-150J132D01*
G01Y1579869D01*
G03X298770Y1580001I-200J0D01*
G02Y1582913I1664J1456D01*
G03X298820Y1583045I-150J132D01*
G01Y1583667D01*
G02X299023Y1583870I203J0D01*
G37*
G36*
G01X316346D02*
X319166D01*
G02X319368Y1583667I-1J-203D01*
G01Y1583047D01*
G03X319418Y1582915I200J0D01*
G02Y1579999I-1661J-1458D01*
G03X319368Y1579867I150J-132D01*
G01Y1577929D01*
G03X319418Y1577797I200J0D01*
G02Y1574881I-1661J-1458D01*
G03X319368Y1574749I150J-132D01*
G01Y1574129D01*
G02X319166Y1573926I-202J-1D01*
G01X316346D01*
G02X316144Y1574129I1J203D01*
G01Y1574749D01*
G03X316094Y1574881I-200J0D01*
G02Y1577797I1661J1458D01*
G03X316144Y1577929I-150J132D01*
G01Y1579867D01*
G03X316094Y1579999I-200J0D01*
G02Y1582915I1661J1458D01*
G03X316144Y1583047I-150J132D01*
G01Y1583667D01*
G02X316346Y1583870I202J1D01*
G37*
G36*
G01X333668D02*
X336488D01*
G02X336690Y1583667I-1J-203D01*
G01Y1583047D01*
G03X336740Y1582915I200J0D01*
G02Y1579999I-1661J-1458D01*
G03X336690Y1579867I150J-132D01*
G01Y1577929D01*
G03X336740Y1577797I200J0D01*
G02Y1574881I-1661J-1458D01*
G03X336690Y1574749I150J-132D01*
G01Y1574129D01*
G02X336488Y1573926I-202J-1D01*
G01X333668D01*
G02X333466Y1574129I1J203D01*
G01Y1574749D01*
G03X333416Y1574881I-200J0D01*
G02Y1577797I1661J1458D01*
G03X333466Y1577929I-150J132D01*
G01Y1579867D01*
G03X333416Y1579999I-200J0D01*
G02Y1582915I1661J1458D01*
G03X333466Y1583047I-150J132D01*
G01Y1583667D01*
G02X333668Y1583870I202J1D01*
G37*
G36*
G01X628157D02*
X630977D01*
G02X631180Y1583667I0J-203D01*
G01Y1583045D01*
G03X631230Y1582913I200J0D01*
G02Y1580001I-1664J-1456D01*
G03X631180Y1579869I150J-132D01*
G01Y1577927D01*
G03X631230Y1577795I200J0D01*
G02Y1574883I-1664J-1456D01*
G03X631180Y1574751I150J-132D01*
G01Y1574129D01*
G02X630977Y1573926I-203J0D01*
G01X628157D01*
G02X627954Y1574129I0J203D01*
G01Y1574751D01*
G03X627904Y1574883I-200J0D01*
G02Y1577795I1664J1456D01*
G03X627954Y1577927I-150J132D01*
G01Y1579869D01*
G03X627904Y1580001I-200J0D01*
G02Y1582913I1664J1456D01*
G03X627954Y1583045I-150J132D01*
G01Y1583667D01*
G02X628157Y1583870I203J0D01*
G37*
G36*
G01X645480D02*
X648300D01*
G02X648502Y1583667I-1J-203D01*
G01Y1583047D01*
G03X648552Y1582915I200J0D01*
G02Y1579999I-1661J-1458D01*
G03X648502Y1579867I150J-132D01*
G01Y1577929D01*
G03X648552Y1577797I200J0D01*
G02Y1574881I-1661J-1458D01*
G03X648502Y1574749I150J-132D01*
G01Y1574129D01*
G02X648300Y1573926I-202J-1D01*
G01X645480D01*
G02X645278Y1574129I1J203D01*
G01Y1574749D01*
G03X645228Y1574881I-200J0D01*
G02Y1577797I1661J1458D01*
G03X645278Y1577929I-150J132D01*
G01Y1579867D01*
G03X645228Y1579999I-200J0D01*
G02Y1582915I1661J1458D01*
G03X645278Y1583047I-150J132D01*
G01Y1583667D01*
G02X645480Y1583870I202J1D01*
G37*
G36*
G01X662803D02*
X665623D01*
G02X665826Y1583667I0J-203D01*
G01Y1583045D01*
G03X665876Y1582913I200J0D01*
G02Y1580001I-1664J-1456D01*
G03X665826Y1579869I150J-132D01*
G01Y1577927D01*
G03X665876Y1577795I200J0D01*
G02Y1574883I-1664J-1456D01*
G03X665826Y1574751I150J-132D01*
G01Y1574129D01*
G02X665623Y1573926I-203J0D01*
G01X662803D01*
G02X662600Y1574129I0J203D01*
G01Y1574751D01*
G03X662550Y1574883I-200J0D01*
G02Y1577795I1664J1456D01*
G03X662600Y1577927I-150J132D01*
G01Y1579869D01*
G03X662550Y1580001I-200J0D01*
G02Y1582913I1664J1456D01*
G03X662600Y1583045I-150J132D01*
G01Y1583667D01*
G02X662803Y1583870I203J0D01*
G37*
G36*
G01X680125D02*
X682945D01*
G02X683148Y1583667I0J-203D01*
G01Y1583045D01*
G03X683198Y1582913I200J0D01*
G02Y1580001I-1664J-1456D01*
G03X683148Y1579869I150J-132D01*
G01Y1577927D01*
G03X683198Y1577795I200J0D01*
G02Y1574883I-1664J-1456D01*
G03X683148Y1574751I150J-132D01*
G01Y1574129D01*
G02X682945Y1573926I-203J0D01*
G01X680125D01*
G02X679922Y1574129I0J203D01*
G01Y1574751D01*
G03X679872Y1574883I-200J0D01*
G02Y1577795I1664J1456D01*
G03X679922Y1577927I-150J132D01*
G01Y1579869D01*
G03X679872Y1580001I-200J0D01*
G02Y1582913I1664J1456D01*
G03X679922Y1583045I-150J132D01*
G01Y1583667D01*
G02X680125Y1583870I203J0D01*
G37*
G36*
G01X1130440D02*
X1133260D01*
G02X1133462Y1583667I-1J-203D01*
G01Y1583047D01*
G03X1133512Y1582915I200J0D01*
G02Y1579999I-1661J-1458D01*
G03X1133462Y1579867I150J-132D01*
G01Y1577929D01*
G03X1133512Y1577797I200J0D01*
G02Y1574881I-1661J-1458D01*
G03X1133462Y1574749I150J-132D01*
G01Y1574129D01*
G02X1133260Y1573926I-202J-1D01*
G01X1130440D01*
G02X1130238Y1574129I1J203D01*
G01Y1574749D01*
G03X1130188Y1574881I-200J0D01*
G02Y1577797I1661J1458D01*
G03X1130238Y1577929I-150J132D01*
G01Y1579867D01*
G03X1130188Y1579999I-200J0D01*
G02Y1582915I1661J1458D01*
G03X1130238Y1583047I-150J132D01*
G01Y1583667D01*
G02X1130440Y1583870I202J1D01*
G37*
G36*
G01X1147763D02*
X1150583D01*
G02X1150786Y1583667I0J-203D01*
G01Y1583045D01*
G03X1150836Y1582913I200J0D01*
G02Y1580001I-1664J-1456D01*
G03X1150786Y1579869I150J-132D01*
G01Y1577927D01*
G03X1150836Y1577795I200J0D01*
G02Y1574883I-1664J-1456D01*
G03X1150786Y1574751I150J-132D01*
G01Y1574129D01*
G02X1150583Y1573926I-203J0D01*
G01X1147763D01*
G02X1147560Y1574129I0J203D01*
G01Y1574751D01*
G03X1147510Y1574883I-200J0D01*
G02Y1577795I1664J1456D01*
G03X1147560Y1577927I-150J132D01*
G01Y1579869D01*
G03X1147510Y1580001I-200J0D01*
G02Y1582913I1664J1456D01*
G03X1147560Y1583045I-150J132D01*
G01Y1583667D01*
G02X1147763Y1583870I203J0D01*
G37*
G36*
G01X1165086D02*
X1167906D01*
G02X1168108Y1583667I-1J-203D01*
G01Y1583047D01*
G03X1168158Y1582915I200J0D01*
G02Y1579999I-1661J-1458D01*
G03X1168108Y1579867I150J-132D01*
G01Y1577929D01*
G03X1168158Y1577797I200J0D01*
G02Y1574881I-1661J-1458D01*
G03X1168108Y1574749I150J-132D01*
G01Y1574129D01*
G02X1167906Y1573926I-202J-1D01*
G01X1165086D01*
G02X1164884Y1574129I1J203D01*
G01Y1574749D01*
G03X1164834Y1574881I-200J0D01*
G02Y1577797I1661J1458D01*
G03X1164884Y1577929I-150J132D01*
G01Y1579867D01*
G03X1164834Y1579999I-200J0D01*
G02Y1582915I1661J1458D01*
G03X1164884Y1583047I-150J132D01*
G01Y1583667D01*
G02X1165086Y1583870I202J1D01*
G37*
G36*
G01X1182408D02*
X1185228D01*
G02X1185430Y1583667I-1J-203D01*
G01Y1583047D01*
G03X1185480Y1582915I200J0D01*
G02Y1579999I-1661J-1458D01*
G03X1185430Y1579867I150J-132D01*
G01Y1577929D01*
G03X1185480Y1577797I200J0D01*
G02Y1574881I-1661J-1458D01*
G03X1185430Y1574749I150J-132D01*
G01Y1574129D01*
G02X1185228Y1573926I-202J-1D01*
G01X1182408D01*
G02X1182206Y1574129I1J203D01*
G01Y1574749D01*
G03X1182156Y1574881I-200J0D01*
G02Y1577797I1661J1458D01*
G03X1182206Y1577929I-150J132D01*
G01Y1579867D01*
G03X1182156Y1579999I-200J0D01*
G02Y1582915I1661J1458D01*
G03X1182206Y1583047I-150J132D01*
G01Y1583667D01*
G02X1182408Y1583870I202J1D01*
G37*
G36*
G01X1303669D02*
X1306489D01*
G02X1306692Y1583667I0J-203D01*
G01Y1583045D01*
G03X1306742Y1582913I200J0D01*
G02Y1580001I-1664J-1456D01*
G03X1306692Y1579869I150J-132D01*
G01Y1577927D01*
G03X1306742Y1577795I200J0D01*
G02Y1574883I-1664J-1456D01*
G03X1306692Y1574751I150J-132D01*
G01Y1574129D01*
G02X1306489Y1573926I-203J0D01*
G01X1303669D01*
G02X1303466Y1574129I0J203D01*
G01Y1574751D01*
G03X1303416Y1574883I-200J0D01*
G02Y1577795I1664J1456D01*
G03X1303466Y1577927I-150J132D01*
G01Y1579869D01*
G03X1303416Y1580001I-200J0D01*
G02Y1582913I1664J1456D01*
G03X1303466Y1583045I-150J132D01*
G01Y1583667D01*
G02X1303669Y1583870I203J0D01*
G37*
G36*
G01X1320992D02*
X1323812D01*
G02X1324014Y1583667I-1J-203D01*
G01Y1583047D01*
G03X1324064Y1582915I200J0D01*
G02Y1579999I-1661J-1458D01*
G03X1324014Y1579867I150J-132D01*
G01Y1577929D01*
G03X1324064Y1577797I200J0D01*
G02Y1574881I-1661J-1458D01*
G03X1324014Y1574749I150J-132D01*
G01Y1574129D01*
G02X1323812Y1573926I-202J-1D01*
G01X1320992D01*
G02X1320790Y1574129I1J203D01*
G01Y1574749D01*
G03X1320740Y1574881I-200J0D01*
G02Y1577797I1661J1458D01*
G03X1320790Y1577929I-150J132D01*
G01Y1579867D01*
G03X1320740Y1579999I-200J0D01*
G02Y1582915I1661J1458D01*
G03X1320790Y1583047I-150J132D01*
G01Y1583667D01*
G02X1320992Y1583870I202J1D01*
G37*
G36*
G01X1338315D02*
X1341135D01*
G02X1341338Y1583667I0J-203D01*
G01Y1583045D01*
G03X1341388Y1582913I200J0D01*
G02Y1580001I-1664J-1456D01*
G03X1341338Y1579869I150J-132D01*
G01Y1577927D01*
G03X1341388Y1577795I200J0D01*
G02Y1574883I-1664J-1456D01*
G03X1341338Y1574751I150J-132D01*
G01Y1574129D01*
G02X1341135Y1573926I-203J0D01*
G01X1338315D01*
G02X1338112Y1574129I0J203D01*
G01Y1574751D01*
G03X1338062Y1574883I-200J0D01*
G02Y1577795I1664J1456D01*
G03X1338112Y1577927I-150J132D01*
G01Y1579869D01*
G03X1338062Y1580001I-200J0D01*
G02Y1582913I1664J1456D01*
G03X1338112Y1583045I-150J132D01*
G01Y1583667D01*
G02X1338315Y1583870I203J0D01*
G37*
G36*
G01X1355637D02*
X1358457D01*
G02X1358660Y1583667I0J-203D01*
G01Y1583045D01*
G03X1358710Y1582913I200J0D01*
G02Y1580001I-1664J-1456D01*
G03X1358660Y1579869I150J-132D01*
G01Y1577927D01*
G03X1358710Y1577795I200J0D01*
G02Y1574883I-1664J-1456D01*
G03X1358660Y1574751I150J-132D01*
G01Y1574129D01*
G02X1358457Y1573926I-203J0D01*
G01X1355637D01*
G02X1355434Y1574129I0J203D01*
G01Y1574751D01*
G03X1355384Y1574883I-200J0D01*
G02Y1577795I1664J1456D01*
G03X1355434Y1577927I-150J132D01*
G01Y1579869D01*
G03X1355384Y1580001I-200J0D01*
G02Y1582913I1664J1456D01*
G03X1355434Y1583045I-150J132D01*
G01Y1583667D01*
G02X1355637Y1583870I203J0D01*
G37*
G36*
G01X1476897D02*
X1479717D01*
G02X1479920Y1583667I0J-203D01*
G01Y1583045D01*
G03X1479970Y1582913I200J0D01*
G02Y1580001I-1664J-1456D01*
G03X1479920Y1579869I150J-132D01*
G01Y1577927D01*
G03X1479970Y1577795I200J0D01*
G02Y1574883I-1664J-1456D01*
G03X1479920Y1574751I150J-132D01*
G01Y1574129D01*
G02X1479717Y1573926I-203J0D01*
G01X1476897D01*
G02X1476694Y1574129I0J203D01*
G01Y1574751D01*
G03X1476644Y1574883I-200J0D01*
G02Y1577795I1664J1456D01*
G03X1476694Y1577927I-150J132D01*
G01Y1579869D01*
G03X1476644Y1580001I-200J0D01*
G02Y1582913I1664J1456D01*
G03X1476694Y1583045I-150J132D01*
G01Y1583667D01*
G02X1476897Y1583870I203J0D01*
G37*
G36*
G01X1650125D02*
X1652945D01*
G02X1653148Y1583667I0J-203D01*
G01Y1583045D01*
G03X1653198Y1582913I200J0D01*
G02Y1580001I-1664J-1456D01*
G03X1653148Y1579869I150J-132D01*
G01Y1577927D01*
G03X1653198Y1577795I200J0D01*
G02Y1574883I-1664J-1456D01*
G03X1653148Y1574751I150J-132D01*
G01Y1574129D01*
G02X1652945Y1573926I-203J0D01*
G01X1650125D01*
G02X1649922Y1574129I0J203D01*
G01Y1574751D01*
G03X1649872Y1574883I-200J0D01*
G02Y1577795I1664J1456D01*
G03X1649922Y1577927I-150J132D01*
G01Y1579869D01*
G03X1649872Y1580001I-200J0D01*
G02Y1582913I1664J1456D01*
G03X1649922Y1583045I-150J132D01*
G01Y1583667D01*
G02X1650125Y1583870I203J0D01*
G37*
G36*
G01X1667448D02*
X1670268D01*
G02X1670470Y1583667I-1J-203D01*
G01Y1583047D01*
G03X1670520Y1582915I200J0D01*
G02Y1579999I-1661J-1458D01*
G03X1670470Y1579867I150J-132D01*
G01Y1577929D01*
G03X1670520Y1577797I200J0D01*
G02Y1574881I-1661J-1458D01*
G03X1670470Y1574749I150J-132D01*
G01Y1574129D01*
G02X1670268Y1573926I-202J-1D01*
G01X1667448D01*
G02X1667246Y1574129I1J203D01*
G01Y1574749D01*
G03X1667196Y1574881I-200J0D01*
G02Y1577797I1661J1458D01*
G03X1667246Y1577929I-150J132D01*
G01Y1579867D01*
G03X1667196Y1579999I-200J0D01*
G02Y1582915I1661J1458D01*
G03X1667246Y1583047I-150J132D01*
G01Y1583667D01*
G02X1667448Y1583870I202J1D01*
G37*
G36*
G01X1684771D02*
X1687591D01*
G02X1687794Y1583667I0J-203D01*
G01Y1583045D01*
G03X1687844Y1582913I200J0D01*
G02Y1580001I-1664J-1456D01*
G03X1687794Y1579869I150J-132D01*
G01Y1577927D01*
G03X1687844Y1577795I200J0D01*
G02Y1574883I-1664J-1456D01*
G03X1687794Y1574751I150J-132D01*
G01Y1574129D01*
G02X1687591Y1573926I-203J0D01*
G01X1684771D01*
G02X1684568Y1574129I0J203D01*
G01Y1574751D01*
G03X1684518Y1574883I-200J0D01*
G02Y1577795I1664J1456D01*
G03X1684568Y1577927I-150J132D01*
G01Y1579869D01*
G03X1684518Y1580001I-200J0D01*
G02Y1582913I1664J1456D01*
G03X1684568Y1583045I-150J132D01*
G01Y1583667D01*
G02X1684771Y1583870I203J0D01*
G37*
G36*
G01X1702093D02*
X1704913D01*
G02X1705116Y1583667I0J-203D01*
G01Y1583045D01*
G03X1705166Y1582913I200J0D01*
G02Y1580001I-1664J-1456D01*
G03X1705116Y1579869I150J-132D01*
G01Y1577927D01*
G03X1705166Y1577795I200J0D01*
G02Y1574883I-1664J-1456D01*
G03X1705116Y1574751I150J-132D01*
G01Y1574129D01*
G02X1704913Y1573926I-203J0D01*
G01X1702093D01*
G02X1701890Y1574129I0J203D01*
G01Y1574751D01*
G03X1701840Y1574883I-200J0D01*
G02Y1577795I1664J1456D01*
G03X1701890Y1577927I-150J132D01*
G01Y1579869D01*
G03X1701840Y1580001I-200J0D01*
G02Y1582913I1664J1456D01*
G03X1701890Y1583045I-150J132D01*
G01Y1583667D01*
G02X1702093Y1583870I203J0D01*
G37*
G36*
G01X134456Y1588200D02*
X137276D01*
G02X137478Y1587998I0J-202D01*
G01Y1587378D01*
G03X137528Y1587246I200J0D01*
G02Y1584330I-1661J-1458D01*
G03X137478Y1584198I150J-132D01*
G01Y1582260D01*
G03X137528Y1582128I200J0D01*
G02Y1579212I-1661J-1458D01*
G03X137478Y1579080I150J-132D01*
G01Y1578460D01*
G02X137276Y1578258I-202J0D01*
G01X134456D01*
G02X134254Y1578460I0J202D01*
G01Y1579080D01*
G03X134204Y1579212I-200J0D01*
G02Y1582128I1661J1458D01*
G03X134254Y1582260I-150J132D01*
G01Y1584198D01*
G03X134204Y1584330I-200J0D01*
G02Y1587246I1661J1458D01*
G03X134254Y1587378I-150J132D01*
G01Y1587998D01*
G02X134456Y1588200I202J0D01*
G37*
G36*
G01X169102D02*
X171922D01*
G02X172124Y1587998I0J-202D01*
G01Y1587378D01*
G03X172174Y1587246I200J0D01*
G02Y1584330I-1661J-1458D01*
G03X172124Y1584198I150J-132D01*
G01Y1582260D01*
G03X172174Y1582128I200J0D01*
G02Y1579212I-1661J-1458D01*
G03X172124Y1579080I150J-132D01*
G01Y1578460D01*
G02X171922Y1578258I-202J0D01*
G01X169102D01*
G02X168900Y1578460I0J202D01*
G01Y1579080D01*
G03X168850Y1579212I-200J0D01*
G02Y1582128I1661J1458D01*
G03X168900Y1582260I-150J132D01*
G01Y1584198D01*
G03X168850Y1584330I-200J0D01*
G02Y1587246I1661J1458D01*
G03X168900Y1587378I-150J132D01*
G01Y1587998D01*
G02X169102Y1588200I202J0D01*
G37*
G36*
G01X307684D02*
X310504D01*
G02X310706Y1587998I0J-202D01*
G01Y1587378D01*
G03X310756Y1587246I200J0D01*
G02Y1584330I-1661J-1458D01*
G03X310706Y1584198I150J-132D01*
G01Y1582260D01*
G03X310756Y1582128I200J0D01*
G02Y1579212I-1661J-1458D01*
G03X310706Y1579080I150J-132D01*
G01Y1578460D01*
G02X310504Y1578258I-202J0D01*
G01X307684D01*
G02X307482Y1578460I0J202D01*
G01Y1579080D01*
G03X307432Y1579212I-200J0D01*
G02Y1582128I1661J1458D01*
G03X307482Y1582260I-150J132D01*
G01Y1584198D01*
G03X307432Y1584330I-200J0D01*
G02Y1587246I1661J1458D01*
G03X307482Y1587378I-150J132D01*
G01Y1587998D01*
G02X307684Y1588200I202J0D01*
G37*
G36*
G01X342330D02*
X345150D01*
G02X345352Y1587998I0J-202D01*
G01Y1587378D01*
G03X345402Y1587246I200J0D01*
G02Y1584330I-1661J-1458D01*
G03X345352Y1584198I150J-132D01*
G01Y1582260D01*
G03X345402Y1582128I200J0D01*
G02Y1579212I-1661J-1458D01*
G03X345352Y1579080I150J-132D01*
G01Y1578460D01*
G02X345150Y1578258I-202J0D01*
G01X342330D01*
G02X342128Y1578460I0J202D01*
G01Y1579080D01*
G03X342078Y1579212I-200J0D01*
G02Y1582128I1661J1458D01*
G03X342128Y1582260I-150J132D01*
G01Y1584198D01*
G03X342078Y1584330I-200J0D01*
G02Y1587246I1661J1458D01*
G03X342128Y1587378I-150J132D01*
G01Y1587998D01*
G02X342330Y1588200I202J0D01*
G37*
G36*
G01X636818D02*
X639638D01*
G02X639840Y1587998I0J-202D01*
G01Y1587378D01*
G03X639890Y1587246I200J0D01*
G02Y1584330I-1661J-1458D01*
G03X639840Y1584198I150J-132D01*
G01Y1582260D01*
G03X639890Y1582128I200J0D01*
G02Y1579212I-1661J-1458D01*
G03X639840Y1579080I150J-132D01*
G01Y1578460D01*
G02X639638Y1578258I-202J0D01*
G01X636818D01*
G02X636616Y1578460I0J202D01*
G01Y1579080D01*
G03X636566Y1579212I-200J0D01*
G02Y1582128I1661J1458D01*
G03X636616Y1582260I-150J132D01*
G01Y1584198D01*
G03X636566Y1584330I-200J0D01*
G02Y1587246I1661J1458D01*
G03X636616Y1587378I-150J132D01*
G01Y1587998D01*
G02X636818Y1588200I202J0D01*
G37*
G36*
G01X671464D02*
X674284D01*
G02X674486Y1587998I0J-202D01*
G01Y1587378D01*
G03X674536Y1587246I200J0D01*
G02Y1584330I-1661J-1458D01*
G03X674486Y1584198I150J-132D01*
G01Y1582260D01*
G03X674536Y1582128I200J0D01*
G02Y1579212I-1661J-1458D01*
G03X674486Y1579080I150J-132D01*
G01Y1578460D01*
G02X674284Y1578258I-202J0D01*
G01X671464D01*
G02X671262Y1578460I0J202D01*
G01Y1579080D01*
G03X671212Y1579212I-200J0D01*
G02Y1582128I1661J1458D01*
G03X671262Y1582260I-150J132D01*
G01Y1584198D01*
G03X671212Y1584330I-200J0D01*
G02Y1587246I1661J1458D01*
G03X671262Y1587378I-150J132D01*
G01Y1587998D01*
G02X671464Y1588200I202J0D01*
G37*
G36*
G01X1156424D02*
X1159244D01*
G02X1159446Y1587998I0J-202D01*
G01Y1587378D01*
G03X1159496Y1587246I200J0D01*
G02Y1584330I-1661J-1458D01*
G03X1159446Y1584198I150J-132D01*
G01Y1582260D01*
G03X1159496Y1582128I200J0D01*
G02Y1579212I-1661J-1458D01*
G03X1159446Y1579080I150J-132D01*
G01Y1578460D01*
G02X1159244Y1578258I-202J0D01*
G01X1156424D01*
G02X1156222Y1578460I0J202D01*
G01Y1579080D01*
G03X1156172Y1579212I-200J0D01*
G02Y1582128I1661J1458D01*
G03X1156222Y1582260I-150J132D01*
G01Y1584198D01*
G03X1156172Y1584330I-200J0D01*
G02Y1587246I1661J1458D01*
G03X1156222Y1587378I-150J132D01*
G01Y1587998D01*
G02X1156424Y1588200I202J0D01*
G37*
G36*
G01X1191070D02*
X1193890D01*
G02X1194092Y1587998I0J-202D01*
G01Y1587378D01*
G03X1194142Y1587246I200J0D01*
G02Y1584330I-1661J-1458D01*
G03X1194092Y1584198I150J-132D01*
G01Y1582260D01*
G03X1194142Y1582128I200J0D01*
G02Y1579212I-1661J-1458D01*
G03X1194092Y1579080I150J-132D01*
G01Y1578460D01*
G02X1193890Y1578258I-202J0D01*
G01X1191070D01*
G02X1190868Y1578460I0J202D01*
G01Y1579080D01*
G03X1190818Y1579212I-200J0D01*
G02Y1582128I1661J1458D01*
G03X1190868Y1582260I-150J132D01*
G01Y1584198D01*
G03X1190818Y1584330I-200J0D01*
G02Y1587246I1661J1458D01*
G03X1190868Y1587378I-150J132D01*
G01Y1587998D01*
G02X1191070Y1588200I202J0D01*
G37*
G36*
G01X1312330D02*
X1315150D01*
G02X1315352Y1587998I0J-202D01*
G01Y1587378D01*
G03X1315402Y1587246I200J0D01*
G02Y1584330I-1661J-1458D01*
G03X1315352Y1584198I150J-132D01*
G01Y1582260D01*
G03X1315402Y1582128I200J0D01*
G02Y1579212I-1661J-1458D01*
G03X1315352Y1579080I150J-132D01*
G01Y1578460D01*
G02X1315150Y1578258I-202J0D01*
G01X1312330D01*
G02X1312128Y1578460I0J202D01*
G01Y1579080D01*
G03X1312078Y1579212I-200J0D01*
G02Y1582128I1661J1458D01*
G03X1312128Y1582260I-150J132D01*
G01Y1584198D01*
G03X1312078Y1584330I-200J0D01*
G02Y1587246I1661J1458D01*
G03X1312128Y1587378I-150J132D01*
G01Y1587998D01*
G02X1312330Y1588200I202J0D01*
G37*
G36*
G01X1346976D02*
X1349796D01*
G02X1349998Y1587998I0J-202D01*
G01Y1587378D01*
G03X1350048Y1587246I200J0D01*
G02Y1584330I-1661J-1458D01*
G03X1349998Y1584198I150J-132D01*
G01Y1582260D01*
G03X1350048Y1582128I200J0D01*
G02Y1579212I-1661J-1458D01*
G03X1349998Y1579080I150J-132D01*
G01Y1578460D01*
G02X1349796Y1578258I-202J0D01*
G01X1346976D01*
G02X1346774Y1578460I0J202D01*
G01Y1579080D01*
G03X1346724Y1579212I-200J0D01*
G02Y1582128I1661J1458D01*
G03X1346774Y1582260I-150J132D01*
G01Y1584198D01*
G03X1346724Y1584330I-200J0D01*
G02Y1587246I1661J1458D01*
G03X1346774Y1587378I-150J132D01*
G01Y1587998D01*
G02X1346976Y1588200I202J0D01*
G37*
G36*
G01X1658786D02*
X1661606D01*
G02X1661808Y1587998I0J-202D01*
G01Y1587378D01*
G03X1661858Y1587246I200J0D01*
G02Y1584330I-1661J-1458D01*
G03X1661808Y1584198I150J-132D01*
G01Y1582260D01*
G03X1661858Y1582128I200J0D01*
G02Y1579212I-1661J-1458D01*
G03X1661808Y1579080I150J-132D01*
G01Y1578460D01*
G02X1661606Y1578258I-202J0D01*
G01X1658786D01*
G02X1658584Y1578460I0J202D01*
G01Y1579080D01*
G03X1658534Y1579212I-200J0D01*
G02Y1582128I1661J1458D01*
G03X1658584Y1582260I-150J132D01*
G01Y1584198D01*
G03X1658534Y1584330I-200J0D01*
G02Y1587246I1661J1458D01*
G03X1658584Y1587378I-150J132D01*
G01Y1587998D01*
G02X1658786Y1588200I202J0D01*
G37*
G36*
G01X1693432D02*
X1696252D01*
G02X1696454Y1587998I0J-202D01*
G01Y1587378D01*
G03X1696504Y1587246I200J0D01*
G02Y1584330I-1661J-1458D01*
G03X1696454Y1584198I150J-132D01*
G01Y1582260D01*
G03X1696504Y1582128I200J0D01*
G02Y1579212I-1661J-1458D01*
G03X1696454Y1579080I150J-132D01*
G01Y1578460D01*
G02X1696252Y1578258I-202J0D01*
G01X1693432D01*
G02X1693230Y1578460I0J202D01*
G01Y1579080D01*
G03X1693180Y1579212I-200J0D01*
G02Y1582128I1661J1458D01*
G03X1693230Y1582260I-150J132D01*
G01Y1584198D01*
G03X1693180Y1584330I-200J0D01*
G02Y1587246I1661J1458D01*
G03X1693230Y1587378I-150J132D01*
G01Y1587998D01*
G02X1693432Y1588200I202J0D01*
G37*
G36*
G01X117133D02*
X119953D01*
G02X120156Y1587998I1J-202D01*
G01Y1587376D01*
G03X120206Y1587244I200J0D01*
G02Y1584332I-1664J-1456D01*
G03X120156Y1584200I150J-132D01*
G01Y1582258D01*
G03X120206Y1582126I200J0D01*
G02Y1579214I-1664J-1456D01*
G03X120156Y1579082I150J-132D01*
G01Y1578460D01*
G02X119953Y1578258I-203J1D01*
G01X117133D01*
G02X116930Y1578460I-1J202D01*
G01Y1579082D01*
G03X116880Y1579214I-200J0D01*
G02Y1582126I1664J1456D01*
G03X116930Y1582258I-150J132D01*
G01Y1584200D01*
G03X116880Y1584332I-200J0D01*
G02Y1587244I1664J1456D01*
G03X116930Y1587376I-150J132D01*
G01Y1587998D01*
G02X117133Y1588200I203J-1D01*
G37*
G36*
G01X151779D02*
X154599D01*
G02X154802Y1587998I1J-202D01*
G01Y1587376D01*
G03X154852Y1587244I200J0D01*
G02Y1584332I-1664J-1456D01*
G03X154802Y1584200I150J-132D01*
G01Y1582258D01*
G03X154852Y1582126I200J0D01*
G02Y1579214I-1664J-1456D01*
G03X154802Y1579082I150J-132D01*
G01Y1578460D01*
G02X154599Y1578258I-203J1D01*
G01X151779D01*
G02X151576Y1578460I-1J202D01*
G01Y1579082D01*
G03X151526Y1579214I-200J0D01*
G02Y1582126I1664J1456D01*
G03X151576Y1582258I-150J132D01*
G01Y1584200D01*
G03X151526Y1584332I-200J0D01*
G02Y1587244I1664J1456D01*
G03X151576Y1587376I-150J132D01*
G01Y1587998D01*
G02X151779Y1588200I203J-1D01*
G37*
G36*
G01X290361D02*
X293181D01*
G02X293384Y1587998I1J-202D01*
G01Y1587376D01*
G03X293434Y1587244I200J0D01*
G02Y1584332I-1664J-1456D01*
G03X293384Y1584200I150J-132D01*
G01Y1582258D01*
G03X293434Y1582126I200J0D01*
G02Y1579214I-1664J-1456D01*
G03X293384Y1579082I150J-132D01*
G01Y1578460D01*
G02X293181Y1578258I-203J1D01*
G01X290361D01*
G02X290158Y1578460I-1J202D01*
G01Y1579082D01*
G03X290108Y1579214I-200J0D01*
G02Y1582126I1664J1456D01*
G03X290158Y1582258I-150J132D01*
G01Y1584200D01*
G03X290108Y1584332I-200J0D01*
G02Y1587244I1664J1456D01*
G03X290158Y1587376I-150J132D01*
G01Y1587998D01*
G02X290361Y1588200I203J-1D01*
G37*
G36*
G01X325007D02*
X327827D01*
G02X328030Y1587998I1J-202D01*
G01Y1587376D01*
G03X328080Y1587244I200J0D01*
G02Y1584332I-1664J-1456D01*
G03X328030Y1584200I150J-132D01*
G01Y1582258D01*
G03X328080Y1582126I200J0D01*
G02Y1579214I-1664J-1456D01*
G03X328030Y1579082I150J-132D01*
G01Y1578460D01*
G02X327827Y1578258I-203J1D01*
G01X325007D01*
G02X324804Y1578460I-1J202D01*
G01Y1579082D01*
G03X324754Y1579214I-200J0D01*
G02Y1582126I1664J1456D01*
G03X324804Y1582258I-150J132D01*
G01Y1584200D01*
G03X324754Y1584332I-200J0D01*
G02Y1587244I1664J1456D01*
G03X324804Y1587376I-150J132D01*
G01Y1587998D01*
G02X325007Y1588200I203J-1D01*
G37*
G36*
G01X515559D02*
X518379D01*
G02X518582Y1587998I1J-202D01*
G01Y1587376D01*
G03X518632Y1587244I200J0D01*
G02Y1584332I-1664J-1456D01*
G03X518582Y1584200I150J-132D01*
G01Y1582258D01*
G03X518632Y1582126I200J0D01*
G02Y1579214I-1664J-1456D01*
G03X518582Y1579082I150J-132D01*
G01Y1578460D01*
G02X518379Y1578258I-203J1D01*
G01X515559D01*
G02X515356Y1578460I-1J202D01*
G01Y1579082D01*
G03X515306Y1579214I-200J0D01*
G02Y1582126I1664J1456D01*
G03X515356Y1582258I-150J132D01*
G01Y1584200D01*
G03X515306Y1584332I-200J0D01*
G02Y1587244I1664J1456D01*
G03X515356Y1587376I-150J132D01*
G01Y1587998D01*
G02X515559Y1588200I203J-1D01*
G37*
G36*
G01X654141D02*
X656961D01*
G02X657164Y1587998I1J-202D01*
G01Y1587376D01*
G03X657214Y1587244I200J0D01*
G02Y1584332I-1664J-1456D01*
G03X657164Y1584200I150J-132D01*
G01Y1582258D01*
G03X657214Y1582126I200J0D01*
G02Y1579214I-1664J-1456D01*
G03X657164Y1579082I150J-132D01*
G01Y1578460D01*
G02X656961Y1578258I-203J1D01*
G01X654141D01*
G02X653938Y1578460I-1J202D01*
G01Y1579082D01*
G03X653888Y1579214I-200J0D01*
G02Y1582126I1664J1456D01*
G03X653938Y1582258I-150J132D01*
G01Y1584200D01*
G03X653888Y1584332I-200J0D01*
G02Y1587244I1664J1456D01*
G03X653938Y1587376I-150J132D01*
G01Y1587998D01*
G02X654141Y1588200I203J-1D01*
G37*
G36*
G01X688787D02*
X691607D01*
G02X691810Y1587998I1J-202D01*
G01Y1587376D01*
G03X691860Y1587244I200J0D01*
G02Y1584332I-1664J-1456D01*
G03X691810Y1584200I150J-132D01*
G01Y1582258D01*
G03X691860Y1582126I200J0D01*
G02Y1579214I-1664J-1456D01*
G03X691810Y1579082I150J-132D01*
G01Y1578460D01*
G02X691607Y1578258I-203J1D01*
G01X688787D01*
G02X688584Y1578460I-1J202D01*
G01Y1579082D01*
G03X688534Y1579214I-200J0D01*
G02Y1582126I1664J1456D01*
G03X688584Y1582258I-150J132D01*
G01Y1584200D01*
G03X688534Y1584332I-200J0D01*
G02Y1587244I1664J1456D01*
G03X688584Y1587376I-150J132D01*
G01Y1587998D01*
G02X688787Y1588200I203J-1D01*
G37*
G36*
G01X1139101D02*
X1141921D01*
G02X1142124Y1587998I1J-202D01*
G01Y1587376D01*
G03X1142174Y1587244I200J0D01*
G02Y1584332I-1664J-1456D01*
G03X1142124Y1584200I150J-132D01*
G01Y1582258D01*
G03X1142174Y1582126I200J0D01*
G02Y1579214I-1664J-1456D01*
G03X1142124Y1579082I150J-132D01*
G01Y1578460D01*
G02X1141921Y1578258I-203J1D01*
G01X1139101D01*
G02X1138898Y1578460I-1J202D01*
G01Y1579082D01*
G03X1138848Y1579214I-200J0D01*
G02Y1582126I1664J1456D01*
G03X1138898Y1582258I-150J132D01*
G01Y1584200D01*
G03X1138848Y1584332I-200J0D01*
G02Y1587244I1664J1456D01*
G03X1138898Y1587376I-150J132D01*
G01Y1587998D01*
G02X1139101Y1588200I203J-1D01*
G37*
G36*
G01X1173747D02*
X1176567D01*
G02X1176770Y1587998I1J-202D01*
G01Y1587376D01*
G03X1176820Y1587244I200J0D01*
G02Y1584332I-1664J-1456D01*
G03X1176770Y1584200I150J-132D01*
G01Y1582258D01*
G03X1176820Y1582126I200J0D01*
G02Y1579214I-1664J-1456D01*
G03X1176770Y1579082I150J-132D01*
G01Y1578460D01*
G02X1176567Y1578258I-203J1D01*
G01X1173747D01*
G02X1173544Y1578460I-1J202D01*
G01Y1579082D01*
G03X1173494Y1579214I-200J0D01*
G02Y1582126I1664J1456D01*
G03X1173544Y1582258I-150J132D01*
G01Y1584200D01*
G03X1173494Y1584332I-200J0D01*
G02Y1587244I1664J1456D01*
G03X1173544Y1587376I-150J132D01*
G01Y1587998D01*
G02X1173747Y1588200I203J-1D01*
G37*
G36*
G01X1329653D02*
X1332473D01*
G02X1332676Y1587998I1J-202D01*
G01Y1587376D01*
G03X1332726Y1587244I200J0D01*
G02Y1584332I-1664J-1456D01*
G03X1332676Y1584200I150J-132D01*
G01Y1582258D01*
G03X1332726Y1582126I200J0D01*
G02Y1579214I-1664J-1456D01*
G03X1332676Y1579082I150J-132D01*
G01Y1578460D01*
G02X1332473Y1578258I-203J1D01*
G01X1329653D01*
G02X1329450Y1578460I-1J202D01*
G01Y1579082D01*
G03X1329400Y1579214I-200J0D01*
G02Y1582126I1664J1456D01*
G03X1329450Y1582258I-150J132D01*
G01Y1584200D01*
G03X1329400Y1584332I-200J0D01*
G02Y1587244I1664J1456D01*
G03X1329450Y1587376I-150J132D01*
G01Y1587998D01*
G02X1329653Y1588200I203J-1D01*
G37*
G36*
G01X1364299D02*
X1367119D01*
G02X1367322Y1587998I1J-202D01*
G01Y1587376D01*
G03X1367372Y1587244I200J0D01*
G02Y1584332I-1664J-1456D01*
G03X1367322Y1584200I150J-132D01*
G01Y1582258D01*
G03X1367372Y1582126I200J0D01*
G02Y1579214I-1664J-1456D01*
G03X1367322Y1579082I150J-132D01*
G01Y1578460D01*
G02X1367119Y1578258I-203J1D01*
G01X1364299D01*
G02X1364096Y1578460I-1J202D01*
G01Y1579082D01*
G03X1364046Y1579214I-200J0D01*
G02Y1582126I1664J1456D01*
G03X1364096Y1582258I-150J132D01*
G01Y1584200D01*
G03X1364046Y1584332I-200J0D01*
G02Y1587244I1664J1456D01*
G03X1364096Y1587376I-150J132D01*
G01Y1587998D01*
G02X1364299Y1588200I203J-1D01*
G37*
G36*
G01X1676109D02*
X1678929D01*
G02X1679132Y1587998I1J-202D01*
G01Y1587376D01*
G03X1679182Y1587244I200J0D01*
G02Y1584332I-1664J-1456D01*
G03X1679132Y1584200I150J-132D01*
G01Y1582258D01*
G03X1679182Y1582126I200J0D01*
G02Y1579214I-1664J-1456D01*
G03X1679132Y1579082I150J-132D01*
G01Y1578460D01*
G02X1678929Y1578258I-203J1D01*
G01X1676109D01*
G02X1675906Y1578460I-1J202D01*
G01Y1579082D01*
G03X1675856Y1579214I-200J0D01*
G02Y1582126I1664J1456D01*
G03X1675906Y1582258I-150J132D01*
G01Y1584200D01*
G03X1675856Y1584332I-200J0D01*
G02Y1587244I1664J1456D01*
G03X1675906Y1587376I-150J132D01*
G01Y1587998D01*
G02X1676109Y1588200I203J-1D01*
G37*
G36*
G01X1710755D02*
X1713575D01*
G02X1713778Y1587998I1J-202D01*
G01Y1587376D01*
G03X1713828Y1587244I200J0D01*
G02Y1584332I-1664J-1456D01*
G03X1713778Y1584200I150J-132D01*
G01Y1582258D01*
G03X1713828Y1582126I200J0D01*
G02Y1579214I-1664J-1456D01*
G03X1713778Y1579082I150J-132D01*
G01Y1578460D01*
G02X1713575Y1578258I-203J1D01*
G01X1710755D01*
G02X1710552Y1578460I-1J202D01*
G01Y1579082D01*
G03X1710502Y1579214I-200J0D01*
G02Y1582126I1664J1456D01*
G03X1710552Y1582258I-150J132D01*
G01Y1584200D01*
G03X1710502Y1584332I-200J0D01*
G02Y1587244I1664J1456D01*
G03X1710552Y1587376I-150J132D01*
G01Y1587998D01*
G02X1710755Y1588200I203J-1D01*
G37*
G36*
G01X108472Y1599224D02*
X111292D01*
G02X111494Y1599021I-1J-203D01*
G01Y1598401D01*
G03X111544Y1598269I200J0D01*
G02Y1595353I-1661J-1458D01*
G03X111494Y1595221I150J-132D01*
G01Y1593283D01*
G03X111544Y1593151I200J0D01*
G02Y1590235I-1661J-1458D01*
G03X111494Y1590103I150J-132D01*
G01Y1589483D01*
G02X111292Y1589280I-202J-1D01*
G01X108472D01*
G02X108270Y1589483I1J203D01*
G01Y1590103D01*
G03X108220Y1590235I-200J0D01*
G02Y1593151I1661J1458D01*
G03X108270Y1593283I-150J132D01*
G01Y1595221D01*
G03X108220Y1595353I-200J0D01*
G02Y1598269I1661J1458D01*
G03X108270Y1598401I-150J132D01*
G01Y1599021D01*
G02X108472Y1599224I202J1D01*
G37*
G36*
G01X125795D02*
X128615D01*
G02X128818Y1599021I0J-203D01*
G01Y1598399D01*
G03X128868Y1598267I200J0D01*
G02Y1595355I-1664J-1456D01*
G03X128818Y1595223I150J-132D01*
G01Y1593281D01*
G03X128868Y1593149I200J0D01*
G02Y1590237I-1664J-1456D01*
G03X128818Y1590105I150J-132D01*
G01Y1589483D01*
G02X128615Y1589280I-203J0D01*
G01X125795D01*
G02X125592Y1589483I0J203D01*
G01Y1590105D01*
G03X125542Y1590237I-200J0D01*
G02Y1593149I1664J1456D01*
G03X125592Y1593281I-150J132D01*
G01Y1595223D01*
G03X125542Y1595355I-200J0D01*
G02Y1598267I1664J1456D01*
G03X125592Y1598399I-150J132D01*
G01Y1599021D01*
G02X125795Y1599224I203J0D01*
G37*
G36*
G01X143118D02*
X145938D01*
G02X146140Y1599021I-1J-203D01*
G01Y1598401D01*
G03X146190Y1598269I200J0D01*
G02Y1595353I-1661J-1458D01*
G03X146140Y1595221I150J-132D01*
G01Y1593283D01*
G03X146190Y1593151I200J0D01*
G02Y1590235I-1661J-1458D01*
G03X146140Y1590103I150J-132D01*
G01Y1589483D01*
G02X145938Y1589280I-202J-1D01*
G01X143118D01*
G02X142916Y1589483I1J203D01*
G01Y1590103D01*
G03X142866Y1590235I-200J0D01*
G02Y1593151I1661J1458D01*
G03X142916Y1593283I-150J132D01*
G01Y1595221D01*
G03X142866Y1595353I-200J0D01*
G02Y1598269I1661J1458D01*
G03X142916Y1598401I-150J132D01*
G01Y1599021D01*
G02X143118Y1599224I202J1D01*
G37*
G36*
G01X160440D02*
X163260D01*
G02X163462Y1599021I-1J-203D01*
G01Y1598401D01*
G03X163512Y1598269I200J0D01*
G02Y1595353I-1661J-1458D01*
G03X163462Y1595221I150J-132D01*
G01Y1593283D01*
G03X163512Y1593151I200J0D01*
G02Y1590235I-1661J-1458D01*
G03X163462Y1590103I150J-132D01*
G01Y1589483D01*
G02X163260Y1589280I-202J-1D01*
G01X160440D01*
G02X160238Y1589483I1J203D01*
G01Y1590103D01*
G03X160188Y1590235I-200J0D01*
G02Y1593151I1661J1458D01*
G03X160238Y1593283I-150J132D01*
G01Y1595221D01*
G03X160188Y1595353I-200J0D01*
G02Y1598269I1661J1458D01*
G03X160238Y1598401I-150J132D01*
G01Y1599021D01*
G02X160440Y1599224I202J1D01*
G37*
G36*
G01X281700D02*
X284520D01*
G02X284722Y1599021I-1J-203D01*
G01Y1598401D01*
G03X284772Y1598269I200J0D01*
G02Y1595353I-1661J-1458D01*
G03X284722Y1595221I150J-132D01*
G01Y1593283D01*
G03X284772Y1593151I200J0D01*
G02Y1590235I-1661J-1458D01*
G03X284722Y1590103I150J-132D01*
G01Y1589483D01*
G02X284520Y1589280I-202J-1D01*
G01X281700D01*
G02X281498Y1589483I1J203D01*
G01Y1590103D01*
G03X281448Y1590235I-200J0D01*
G02Y1593151I1661J1458D01*
G03X281498Y1593283I-150J132D01*
G01Y1595221D01*
G03X281448Y1595353I-200J0D01*
G02Y1598269I1661J1458D01*
G03X281498Y1598401I-150J132D01*
G01Y1599021D01*
G02X281700Y1599224I202J1D01*
G37*
G36*
G01X299023D02*
X301843D01*
G02X302046Y1599021I0J-203D01*
G01Y1598399D01*
G03X302096Y1598267I200J0D01*
G02Y1595355I-1664J-1456D01*
G03X302046Y1595223I150J-132D01*
G01Y1593281D01*
G03X302096Y1593149I200J0D01*
G02Y1590237I-1664J-1456D01*
G03X302046Y1590105I150J-132D01*
G01Y1589483D01*
G02X301843Y1589280I-203J0D01*
G01X299023D01*
G02X298820Y1589483I0J203D01*
G01Y1590105D01*
G03X298770Y1590237I-200J0D01*
G02Y1593149I1664J1456D01*
G03X298820Y1593281I-150J132D01*
G01Y1595223D01*
G03X298770Y1595355I-200J0D01*
G02Y1598267I1664J1456D01*
G03X298820Y1598399I-150J132D01*
G01Y1599021D01*
G02X299023Y1599224I203J0D01*
G37*
G36*
G01X316346D02*
X319166D01*
G02X319368Y1599021I-1J-203D01*
G01Y1598401D01*
G03X319418Y1598269I200J0D01*
G02Y1595353I-1661J-1458D01*
G03X319368Y1595221I150J-132D01*
G01Y1593283D01*
G03X319418Y1593151I200J0D01*
G02Y1590235I-1661J-1458D01*
G03X319368Y1590103I150J-132D01*
G01Y1589483D01*
G02X319166Y1589280I-202J-1D01*
G01X316346D01*
G02X316144Y1589483I1J203D01*
G01Y1590103D01*
G03X316094Y1590235I-200J0D01*
G02Y1593151I1661J1458D01*
G03X316144Y1593283I-150J132D01*
G01Y1595221D01*
G03X316094Y1595353I-200J0D01*
G02Y1598269I1661J1458D01*
G03X316144Y1598401I-150J132D01*
G01Y1599021D01*
G02X316346Y1599224I202J1D01*
G37*
G36*
G01X333668D02*
X336488D01*
G02X336690Y1599021I-1J-203D01*
G01Y1598401D01*
G03X336740Y1598269I200J0D01*
G02Y1595353I-1661J-1458D01*
G03X336690Y1595221I150J-132D01*
G01Y1593283D01*
G03X336740Y1593151I200J0D01*
G02Y1590235I-1661J-1458D01*
G03X336690Y1590103I150J-132D01*
G01Y1589483D01*
G02X336488Y1589280I-202J-1D01*
G01X333668D01*
G02X333466Y1589483I1J203D01*
G01Y1590103D01*
G03X333416Y1590235I-200J0D01*
G02Y1593151I1661J1458D01*
G03X333466Y1593283I-150J132D01*
G01Y1595221D01*
G03X333416Y1595353I-200J0D01*
G02Y1598269I1661J1458D01*
G03X333466Y1598401I-150J132D01*
G01Y1599021D01*
G02X333668Y1599224I202J1D01*
G37*
G36*
G01X628157D02*
X630977D01*
G02X631180Y1599021I0J-203D01*
G01Y1598399D01*
G03X631230Y1598267I200J0D01*
G02Y1595355I-1664J-1456D01*
G03X631180Y1595223I150J-132D01*
G01Y1593281D01*
G03X631230Y1593149I200J0D01*
G02Y1590237I-1664J-1456D01*
G03X631180Y1590105I150J-132D01*
G01Y1589483D01*
G02X630977Y1589280I-203J0D01*
G01X628157D01*
G02X627954Y1589483I0J203D01*
G01Y1590105D01*
G03X627904Y1590237I-200J0D01*
G02Y1593149I1664J1456D01*
G03X627954Y1593281I-150J132D01*
G01Y1595223D01*
G03X627904Y1595355I-200J0D01*
G02Y1598267I1664J1456D01*
G03X627954Y1598399I-150J132D01*
G01Y1599021D01*
G02X628157Y1599224I203J0D01*
G37*
G36*
G01X645480D02*
X648300D01*
G02X648502Y1599021I-1J-203D01*
G01Y1598401D01*
G03X648552Y1598269I200J0D01*
G02Y1595353I-1661J-1458D01*
G03X648502Y1595221I150J-132D01*
G01Y1593283D01*
G03X648552Y1593151I200J0D01*
G02Y1590235I-1661J-1458D01*
G03X648502Y1590103I150J-132D01*
G01Y1589483D01*
G02X648300Y1589280I-202J-1D01*
G01X645480D01*
G02X645278Y1589483I1J203D01*
G01Y1590103D01*
G03X645228Y1590235I-200J0D01*
G02Y1593151I1661J1458D01*
G03X645278Y1593283I-150J132D01*
G01Y1595221D01*
G03X645228Y1595353I-200J0D01*
G02Y1598269I1661J1458D01*
G03X645278Y1598401I-150J132D01*
G01Y1599021D01*
G02X645480Y1599224I202J1D01*
G37*
G36*
G01X662803D02*
X665623D01*
G02X665826Y1599021I0J-203D01*
G01Y1598399D01*
G03X665876Y1598267I200J0D01*
G02Y1595355I-1664J-1456D01*
G03X665826Y1595223I150J-132D01*
G01Y1593281D01*
G03X665876Y1593149I200J0D01*
G02Y1590237I-1664J-1456D01*
G03X665826Y1590105I150J-132D01*
G01Y1589483D01*
G02X665623Y1589280I-203J0D01*
G01X662803D01*
G02X662600Y1589483I0J203D01*
G01Y1590105D01*
G03X662550Y1590237I-200J0D01*
G02Y1593149I1664J1456D01*
G03X662600Y1593281I-150J132D01*
G01Y1595223D01*
G03X662550Y1595355I-200J0D01*
G02Y1598267I1664J1456D01*
G03X662600Y1598399I-150J132D01*
G01Y1599021D01*
G02X662803Y1599224I203J0D01*
G37*
G36*
G01X680125D02*
X682945D01*
G02X683148Y1599021I0J-203D01*
G01Y1598399D01*
G03X683198Y1598267I200J0D01*
G02Y1595355I-1664J-1456D01*
G03X683148Y1595223I150J-132D01*
G01Y1593281D01*
G03X683198Y1593149I200J0D01*
G02Y1590237I-1664J-1456D01*
G03X683148Y1590105I150J-132D01*
G01Y1589483D01*
G02X682945Y1589280I-203J0D01*
G01X680125D01*
G02X679922Y1589483I0J203D01*
G01Y1590105D01*
G03X679872Y1590237I-200J0D01*
G02Y1593149I1664J1456D01*
G03X679922Y1593281I-150J132D01*
G01Y1595223D01*
G03X679872Y1595355I-200J0D01*
G02Y1598267I1664J1456D01*
G03X679922Y1598399I-150J132D01*
G01Y1599021D01*
G02X680125Y1599224I203J0D01*
G37*
G36*
G01X1130440D02*
X1133260D01*
G02X1133462Y1599021I-1J-203D01*
G01Y1598401D01*
G03X1133512Y1598269I200J0D01*
G02Y1595353I-1661J-1458D01*
G03X1133462Y1595221I150J-132D01*
G01Y1593283D01*
G03X1133512Y1593151I200J0D01*
G02Y1590235I-1661J-1458D01*
G03X1133462Y1590103I150J-132D01*
G01Y1589483D01*
G02X1133260Y1589280I-202J-1D01*
G01X1130440D01*
G02X1130238Y1589483I1J203D01*
G01Y1590103D01*
G03X1130188Y1590235I-200J0D01*
G02Y1593151I1661J1458D01*
G03X1130238Y1593283I-150J132D01*
G01Y1595221D01*
G03X1130188Y1595353I-200J0D01*
G02Y1598269I1661J1458D01*
G03X1130238Y1598401I-150J132D01*
G01Y1599021D01*
G02X1130440Y1599224I202J1D01*
G37*
G36*
G01X1147763D02*
X1150583D01*
G02X1150786Y1599021I0J-203D01*
G01Y1598399D01*
G03X1150836Y1598267I200J0D01*
G02Y1595355I-1664J-1456D01*
G03X1150786Y1595223I150J-132D01*
G01Y1593281D01*
G03X1150836Y1593149I200J0D01*
G02Y1590237I-1664J-1456D01*
G03X1150786Y1590105I150J-132D01*
G01Y1589483D01*
G02X1150583Y1589280I-203J0D01*
G01X1147763D01*
G02X1147560Y1589483I0J203D01*
G01Y1590105D01*
G03X1147510Y1590237I-200J0D01*
G02Y1593149I1664J1456D01*
G03X1147560Y1593281I-150J132D01*
G01Y1595223D01*
G03X1147510Y1595355I-200J0D01*
G02Y1598267I1664J1456D01*
G03X1147560Y1598399I-150J132D01*
G01Y1599021D01*
G02X1147763Y1599224I203J0D01*
G37*
G36*
G01X1165086D02*
X1167906D01*
G02X1168108Y1599021I-1J-203D01*
G01Y1598401D01*
G03X1168158Y1598269I200J0D01*
G02Y1595353I-1661J-1458D01*
G03X1168108Y1595221I150J-132D01*
G01Y1593283D01*
G03X1168158Y1593151I200J0D01*
G02Y1590235I-1661J-1458D01*
G03X1168108Y1590103I150J-132D01*
G01Y1589483D01*
G02X1167906Y1589280I-202J-1D01*
G01X1165086D01*
G02X1164884Y1589483I1J203D01*
G01Y1590103D01*
G03X1164834Y1590235I-200J0D01*
G02Y1593151I1661J1458D01*
G03X1164884Y1593283I-150J132D01*
G01Y1595221D01*
G03X1164834Y1595353I-200J0D01*
G02Y1598269I1661J1458D01*
G03X1164884Y1598401I-150J132D01*
G01Y1599021D01*
G02X1165086Y1599224I202J1D01*
G37*
G36*
G01X1182408D02*
X1185228D01*
G02X1185430Y1599021I-1J-203D01*
G01Y1598401D01*
G03X1185480Y1598269I200J0D01*
G02Y1595353I-1661J-1458D01*
G03X1185430Y1595221I150J-132D01*
G01Y1593283D01*
G03X1185480Y1593151I200J0D01*
G02Y1590235I-1661J-1458D01*
G03X1185430Y1590103I150J-132D01*
G01Y1589483D01*
G02X1185228Y1589280I-202J-1D01*
G01X1182408D01*
G02X1182206Y1589483I1J203D01*
G01Y1590103D01*
G03X1182156Y1590235I-200J0D01*
G02Y1593151I1661J1458D01*
G03X1182206Y1593283I-150J132D01*
G01Y1595221D01*
G03X1182156Y1595353I-200J0D01*
G02Y1598269I1661J1458D01*
G03X1182206Y1598401I-150J132D01*
G01Y1599021D01*
G02X1182408Y1599224I202J1D01*
G37*
G36*
G01X1303669D02*
X1306489D01*
G02X1306692Y1599021I0J-203D01*
G01Y1598399D01*
G03X1306742Y1598267I200J0D01*
G02Y1595355I-1664J-1456D01*
G03X1306692Y1595223I150J-132D01*
G01Y1593281D01*
G03X1306742Y1593149I200J0D01*
G02Y1590237I-1664J-1456D01*
G03X1306692Y1590105I150J-132D01*
G01Y1589483D01*
G02X1306489Y1589280I-203J0D01*
G01X1303669D01*
G02X1303466Y1589483I0J203D01*
G01Y1590105D01*
G03X1303416Y1590237I-200J0D01*
G02Y1593149I1664J1456D01*
G03X1303466Y1593281I-150J132D01*
G01Y1595223D01*
G03X1303416Y1595355I-200J0D01*
G02Y1598267I1664J1456D01*
G03X1303466Y1598399I-150J132D01*
G01Y1599021D01*
G02X1303669Y1599224I203J0D01*
G37*
G36*
G01X1320992D02*
X1323812D01*
G02X1324014Y1599021I-1J-203D01*
G01Y1598401D01*
G03X1324064Y1598269I200J0D01*
G02Y1595353I-1661J-1458D01*
G03X1324014Y1595221I150J-132D01*
G01Y1593283D01*
G03X1324064Y1593151I200J0D01*
G02Y1590235I-1661J-1458D01*
G03X1324014Y1590103I150J-132D01*
G01Y1589483D01*
G02X1323812Y1589280I-202J-1D01*
G01X1320992D01*
G02X1320790Y1589483I1J203D01*
G01Y1590103D01*
G03X1320740Y1590235I-200J0D01*
G02Y1593151I1661J1458D01*
G03X1320790Y1593283I-150J132D01*
G01Y1595221D01*
G03X1320740Y1595353I-200J0D01*
G02Y1598269I1661J1458D01*
G03X1320790Y1598401I-150J132D01*
G01Y1599021D01*
G02X1320992Y1599224I202J1D01*
G37*
G36*
G01X1338315D02*
X1341135D01*
G02X1341338Y1599021I0J-203D01*
G01Y1598399D01*
G03X1341388Y1598267I200J0D01*
G02Y1595355I-1664J-1456D01*
G03X1341338Y1595223I150J-132D01*
G01Y1593281D01*
G03X1341388Y1593149I200J0D01*
G02Y1590237I-1664J-1456D01*
G03X1341338Y1590105I150J-132D01*
G01Y1589483D01*
G02X1341135Y1589280I-203J0D01*
G01X1338315D01*
G02X1338112Y1589483I0J203D01*
G01Y1590105D01*
G03X1338062Y1590237I-200J0D01*
G02Y1593149I1664J1456D01*
G03X1338112Y1593281I-150J132D01*
G01Y1595223D01*
G03X1338062Y1595355I-200J0D01*
G02Y1598267I1664J1456D01*
G03X1338112Y1598399I-150J132D01*
G01Y1599021D01*
G02X1338315Y1599224I203J0D01*
G37*
G36*
G01X1355637D02*
X1358457D01*
G02X1358660Y1599021I0J-203D01*
G01Y1598399D01*
G03X1358710Y1598267I200J0D01*
G02Y1595355I-1664J-1456D01*
G03X1358660Y1595223I150J-132D01*
G01Y1593281D01*
G03X1358710Y1593149I200J0D01*
G02Y1590237I-1664J-1456D01*
G03X1358660Y1590105I150J-132D01*
G01Y1589483D01*
G02X1358457Y1589280I-203J0D01*
G01X1355637D01*
G02X1355434Y1589483I0J203D01*
G01Y1590105D01*
G03X1355384Y1590237I-200J0D01*
G02Y1593149I1664J1456D01*
G03X1355434Y1593281I-150J132D01*
G01Y1595223D01*
G03X1355384Y1595355I-200J0D01*
G02Y1598267I1664J1456D01*
G03X1355434Y1598399I-150J132D01*
G01Y1599021D01*
G02X1355637Y1599224I203J0D01*
G37*
G36*
G01X1476897D02*
X1479717D01*
G02X1479920Y1599021I0J-203D01*
G01Y1598399D01*
G03X1479970Y1598267I200J0D01*
G02Y1595355I-1664J-1456D01*
G03X1479920Y1595223I150J-132D01*
G01Y1593281D01*
G03X1479970Y1593149I200J0D01*
G02Y1590237I-1664J-1456D01*
G03X1479920Y1590105I150J-132D01*
G01Y1589483D01*
G02X1479717Y1589280I-203J0D01*
G01X1476897D01*
G02X1476694Y1589483I0J203D01*
G01Y1590105D01*
G03X1476644Y1590237I-200J0D01*
G02Y1593149I1664J1456D01*
G03X1476694Y1593281I-150J132D01*
G01Y1595223D01*
G03X1476644Y1595355I-200J0D01*
G02Y1598267I1664J1456D01*
G03X1476694Y1598399I-150J132D01*
G01Y1599021D01*
G02X1476897Y1599224I203J0D01*
G37*
G36*
G01X1650125D02*
X1652945D01*
G02X1653148Y1599021I0J-203D01*
G01Y1598399D01*
G03X1653198Y1598267I200J0D01*
G02Y1595355I-1664J-1456D01*
G03X1653148Y1595223I150J-132D01*
G01Y1593281D01*
G03X1653198Y1593149I200J0D01*
G02Y1590237I-1664J-1456D01*
G03X1653148Y1590105I150J-132D01*
G01Y1589483D01*
G02X1652945Y1589280I-203J0D01*
G01X1650125D01*
G02X1649922Y1589483I0J203D01*
G01Y1590105D01*
G03X1649872Y1590237I-200J0D01*
G02Y1593149I1664J1456D01*
G03X1649922Y1593281I-150J132D01*
G01Y1595223D01*
G03X1649872Y1595355I-200J0D01*
G02Y1598267I1664J1456D01*
G03X1649922Y1598399I-150J132D01*
G01Y1599021D01*
G02X1650125Y1599224I203J0D01*
G37*
G36*
G01X1667448D02*
X1670268D01*
G02X1670470Y1599021I-1J-203D01*
G01Y1598401D01*
G03X1670520Y1598269I200J0D01*
G02Y1595353I-1661J-1458D01*
G03X1670470Y1595221I150J-132D01*
G01Y1593283D01*
G03X1670520Y1593151I200J0D01*
G02Y1590235I-1661J-1458D01*
G03X1670470Y1590103I150J-132D01*
G01Y1589483D01*
G02X1670268Y1589280I-202J-1D01*
G01X1667448D01*
G02X1667246Y1589483I1J203D01*
G01Y1590103D01*
G03X1667196Y1590235I-200J0D01*
G02Y1593151I1661J1458D01*
G03X1667246Y1593283I-150J132D01*
G01Y1595221D01*
G03X1667196Y1595353I-200J0D01*
G02Y1598269I1661J1458D01*
G03X1667246Y1598401I-150J132D01*
G01Y1599021D01*
G02X1667448Y1599224I202J1D01*
G37*
G36*
G01X1684771D02*
X1687591D01*
G02X1687794Y1599021I0J-203D01*
G01Y1598399D01*
G03X1687844Y1598267I200J0D01*
G02Y1595355I-1664J-1456D01*
G03X1687794Y1595223I150J-132D01*
G01Y1593281D01*
G03X1687844Y1593149I200J0D01*
G02Y1590237I-1664J-1456D01*
G03X1687794Y1590105I150J-132D01*
G01Y1589483D01*
G02X1687591Y1589280I-203J0D01*
G01X1684771D01*
G02X1684568Y1589483I0J203D01*
G01Y1590105D01*
G03X1684518Y1590237I-200J0D01*
G02Y1593149I1664J1456D01*
G03X1684568Y1593281I-150J132D01*
G01Y1595223D01*
G03X1684518Y1595355I-200J0D01*
G02Y1598267I1664J1456D01*
G03X1684568Y1598399I-150J132D01*
G01Y1599021D01*
G02X1684771Y1599224I203J0D01*
G37*
G36*
G01X1702093D02*
X1704913D01*
G02X1705116Y1599021I0J-203D01*
G01Y1598399D01*
G03X1705166Y1598267I200J0D01*
G02Y1595355I-1664J-1456D01*
G03X1705116Y1595223I150J-132D01*
G01Y1593281D01*
G03X1705166Y1593149I200J0D01*
G02Y1590237I-1664J-1456D01*
G03X1705116Y1590105I150J-132D01*
G01Y1589483D01*
G02X1704913Y1589280I-203J0D01*
G01X1702093D01*
G02X1701890Y1589483I0J203D01*
G01Y1590105D01*
G03X1701840Y1590237I-200J0D01*
G02Y1593149I1664J1456D01*
G03X1701890Y1593281I-150J132D01*
G01Y1595223D01*
G03X1701840Y1595355I-200J0D01*
G02Y1598267I1664J1456D01*
G03X1701890Y1598399I-150J132D01*
G01Y1599021D01*
G02X1702093Y1599224I203J0D01*
G37*
G36*
G01X134456Y1603554D02*
X137276D01*
G02X137478Y1603352I0J-202D01*
G01Y1602732D01*
G03X137528Y1602600I200J0D01*
G02Y1599684I-1661J-1458D01*
G03X137478Y1599552I150J-132D01*
G01Y1597614D01*
G03X137528Y1597482I200J0D01*
G02Y1594566I-1661J-1458D01*
G03X137478Y1594434I150J-132D01*
G01Y1593814D01*
G02X137276Y1593612I-202J0D01*
G01X134456D01*
G02X134254Y1593814I0J202D01*
G01Y1594434D01*
G03X134204Y1594566I-200J0D01*
G02Y1597482I1661J1458D01*
G03X134254Y1597614I-150J132D01*
G01Y1599552D01*
G03X134204Y1599684I-200J0D01*
G02Y1602600I1661J1458D01*
G03X134254Y1602732I-150J132D01*
G01Y1603352D01*
G02X134456Y1603554I202J0D01*
G37*
G36*
G01X169102D02*
X171922D01*
G02X172124Y1603352I0J-202D01*
G01Y1602732D01*
G03X172174Y1602600I200J0D01*
G02Y1599684I-1661J-1458D01*
G03X172124Y1599552I150J-132D01*
G01Y1597614D01*
G03X172174Y1597482I200J0D01*
G02Y1594566I-1661J-1458D01*
G03X172124Y1594434I150J-132D01*
G01Y1593814D01*
G02X171922Y1593612I-202J0D01*
G01X169102D01*
G02X168900Y1593814I0J202D01*
G01Y1594434D01*
G03X168850Y1594566I-200J0D01*
G02Y1597482I1661J1458D01*
G03X168900Y1597614I-150J132D01*
G01Y1599552D01*
G03X168850Y1599684I-200J0D01*
G02Y1602600I1661J1458D01*
G03X168900Y1602732I-150J132D01*
G01Y1603352D01*
G02X169102Y1603554I202J0D01*
G37*
G36*
G01X307684D02*
X310504D01*
G02X310706Y1603352I0J-202D01*
G01Y1602732D01*
G03X310756Y1602600I200J0D01*
G02Y1599684I-1661J-1458D01*
G03X310706Y1599552I150J-132D01*
G01Y1597614D01*
G03X310756Y1597482I200J0D01*
G02Y1594566I-1661J-1458D01*
G03X310706Y1594434I150J-132D01*
G01Y1593814D01*
G02X310504Y1593612I-202J0D01*
G01X307684D01*
G02X307482Y1593814I0J202D01*
G01Y1594434D01*
G03X307432Y1594566I-200J0D01*
G02Y1597482I1661J1458D01*
G03X307482Y1597614I-150J132D01*
G01Y1599552D01*
G03X307432Y1599684I-200J0D01*
G02Y1602600I1661J1458D01*
G03X307482Y1602732I-150J132D01*
G01Y1603352D01*
G02X307684Y1603554I202J0D01*
G37*
G36*
G01X342330D02*
X345150D01*
G02X345352Y1603352I0J-202D01*
G01Y1602732D01*
G03X345402Y1602600I200J0D01*
G02Y1599684I-1661J-1458D01*
G03X345352Y1599552I150J-132D01*
G01Y1597614D01*
G03X345402Y1597482I200J0D01*
G02Y1594566I-1661J-1458D01*
G03X345352Y1594434I150J-132D01*
G01Y1593814D01*
G02X345150Y1593612I-202J0D01*
G01X342330D01*
G02X342128Y1593814I0J202D01*
G01Y1594434D01*
G03X342078Y1594566I-200J0D01*
G02Y1597482I1661J1458D01*
G03X342128Y1597614I-150J132D01*
G01Y1599552D01*
G03X342078Y1599684I-200J0D01*
G02Y1602600I1661J1458D01*
G03X342128Y1602732I-150J132D01*
G01Y1603352D01*
G02X342330Y1603554I202J0D01*
G37*
G36*
G01X636818D02*
X639638D01*
G02X639840Y1603352I0J-202D01*
G01Y1602732D01*
G03X639890Y1602600I200J0D01*
G02Y1599684I-1661J-1458D01*
G03X639840Y1599552I150J-132D01*
G01Y1597614D01*
G03X639890Y1597482I200J0D01*
G02Y1594566I-1661J-1458D01*
G03X639840Y1594434I150J-132D01*
G01Y1593814D01*
G02X639638Y1593612I-202J0D01*
G01X636818D01*
G02X636616Y1593814I0J202D01*
G01Y1594434D01*
G03X636566Y1594566I-200J0D01*
G02Y1597482I1661J1458D01*
G03X636616Y1597614I-150J132D01*
G01Y1599552D01*
G03X636566Y1599684I-200J0D01*
G02Y1602600I1661J1458D01*
G03X636616Y1602732I-150J132D01*
G01Y1603352D01*
G02X636818Y1603554I202J0D01*
G37*
G36*
G01X671464D02*
X674284D01*
G02X674486Y1603352I0J-202D01*
G01Y1602732D01*
G03X674536Y1602600I200J0D01*
G02Y1599684I-1661J-1458D01*
G03X674486Y1599552I150J-132D01*
G01Y1597614D01*
G03X674536Y1597482I200J0D01*
G02Y1594566I-1661J-1458D01*
G03X674486Y1594434I150J-132D01*
G01Y1593814D01*
G02X674284Y1593612I-202J0D01*
G01X671464D01*
G02X671262Y1593814I0J202D01*
G01Y1594434D01*
G03X671212Y1594566I-200J0D01*
G02Y1597482I1661J1458D01*
G03X671262Y1597614I-150J132D01*
G01Y1599552D01*
G03X671212Y1599684I-200J0D01*
G02Y1602600I1661J1458D01*
G03X671262Y1602732I-150J132D01*
G01Y1603352D01*
G02X671464Y1603554I202J0D01*
G37*
G36*
G01X1156424D02*
X1159244D01*
G02X1159446Y1603352I0J-202D01*
G01Y1602732D01*
G03X1159496Y1602600I200J0D01*
G02Y1599684I-1661J-1458D01*
G03X1159446Y1599552I150J-132D01*
G01Y1597614D01*
G03X1159496Y1597482I200J0D01*
G02Y1594566I-1661J-1458D01*
G03X1159446Y1594434I150J-132D01*
G01Y1593814D01*
G02X1159244Y1593612I-202J0D01*
G01X1156424D01*
G02X1156222Y1593814I0J202D01*
G01Y1594434D01*
G03X1156172Y1594566I-200J0D01*
G02Y1597482I1661J1458D01*
G03X1156222Y1597614I-150J132D01*
G01Y1599552D01*
G03X1156172Y1599684I-200J0D01*
G02Y1602600I1661J1458D01*
G03X1156222Y1602732I-150J132D01*
G01Y1603352D01*
G02X1156424Y1603554I202J0D01*
G37*
G36*
G01X1191070D02*
X1193890D01*
G02X1194092Y1603352I0J-202D01*
G01Y1602732D01*
G03X1194142Y1602600I200J0D01*
G02Y1599684I-1661J-1458D01*
G03X1194092Y1599552I150J-132D01*
G01Y1597614D01*
G03X1194142Y1597482I200J0D01*
G02Y1594566I-1661J-1458D01*
G03X1194092Y1594434I150J-132D01*
G01Y1593814D01*
G02X1193890Y1593612I-202J0D01*
G01X1191070D01*
G02X1190868Y1593814I0J202D01*
G01Y1594434D01*
G03X1190818Y1594566I-200J0D01*
G02Y1597482I1661J1458D01*
G03X1190868Y1597614I-150J132D01*
G01Y1599552D01*
G03X1190818Y1599684I-200J0D01*
G02Y1602600I1661J1458D01*
G03X1190868Y1602732I-150J132D01*
G01Y1603352D01*
G02X1191070Y1603554I202J0D01*
G37*
G36*
G01X1312330D02*
X1315150D01*
G02X1315352Y1603352I0J-202D01*
G01Y1602732D01*
G03X1315402Y1602600I200J0D01*
G02Y1599684I-1661J-1458D01*
G03X1315352Y1599552I150J-132D01*
G01Y1597614D01*
G03X1315402Y1597482I200J0D01*
G02Y1594566I-1661J-1458D01*
G03X1315352Y1594434I150J-132D01*
G01Y1593814D01*
G02X1315150Y1593612I-202J0D01*
G01X1312330D01*
G02X1312128Y1593814I0J202D01*
G01Y1594434D01*
G03X1312078Y1594566I-200J0D01*
G02Y1597482I1661J1458D01*
G03X1312128Y1597614I-150J132D01*
G01Y1599552D01*
G03X1312078Y1599684I-200J0D01*
G02Y1602600I1661J1458D01*
G03X1312128Y1602732I-150J132D01*
G01Y1603352D01*
G02X1312330Y1603554I202J0D01*
G37*
G36*
G01X1346976D02*
X1349796D01*
G02X1349998Y1603352I0J-202D01*
G01Y1602732D01*
G03X1350048Y1602600I200J0D01*
G02Y1599684I-1661J-1458D01*
G03X1349998Y1599552I150J-132D01*
G01Y1597614D01*
G03X1350048Y1597482I200J0D01*
G02Y1594566I-1661J-1458D01*
G03X1349998Y1594434I150J-132D01*
G01Y1593814D01*
G02X1349796Y1593612I-202J0D01*
G01X1346976D01*
G02X1346774Y1593814I0J202D01*
G01Y1594434D01*
G03X1346724Y1594566I-200J0D01*
G02Y1597482I1661J1458D01*
G03X1346774Y1597614I-150J132D01*
G01Y1599552D01*
G03X1346724Y1599684I-200J0D01*
G02Y1602600I1661J1458D01*
G03X1346774Y1602732I-150J132D01*
G01Y1603352D01*
G02X1346976Y1603554I202J0D01*
G37*
G36*
G01X1658786D02*
X1661606D01*
G02X1661808Y1603352I0J-202D01*
G01Y1602732D01*
G03X1661858Y1602600I200J0D01*
G02Y1599684I-1661J-1458D01*
G03X1661808Y1599552I150J-132D01*
G01Y1597614D01*
G03X1661858Y1597482I200J0D01*
G02Y1594566I-1661J-1458D01*
G03X1661808Y1594434I150J-132D01*
G01Y1593814D01*
G02X1661606Y1593612I-202J0D01*
G01X1658786D01*
G02X1658584Y1593814I0J202D01*
G01Y1594434D01*
G03X1658534Y1594566I-200J0D01*
G02Y1597482I1661J1458D01*
G03X1658584Y1597614I-150J132D01*
G01Y1599552D01*
G03X1658534Y1599684I-200J0D01*
G02Y1602600I1661J1458D01*
G03X1658584Y1602732I-150J132D01*
G01Y1603352D01*
G02X1658786Y1603554I202J0D01*
G37*
G36*
G01X1693432D02*
X1696252D01*
G02X1696454Y1603352I0J-202D01*
G01Y1602732D01*
G03X1696504Y1602600I200J0D01*
G02Y1599684I-1661J-1458D01*
G03X1696454Y1599552I150J-132D01*
G01Y1597614D01*
G03X1696504Y1597482I200J0D01*
G02Y1594566I-1661J-1458D01*
G03X1696454Y1594434I150J-132D01*
G01Y1593814D01*
G02X1696252Y1593612I-202J0D01*
G01X1693432D01*
G02X1693230Y1593814I0J202D01*
G01Y1594434D01*
G03X1693180Y1594566I-200J0D01*
G02Y1597482I1661J1458D01*
G03X1693230Y1597614I-150J132D01*
G01Y1599552D01*
G03X1693180Y1599684I-200J0D01*
G02Y1602600I1661J1458D01*
G03X1693230Y1602732I-150J132D01*
G01Y1603352D01*
G02X1693432Y1603554I202J0D01*
G37*
G36*
G01X117133D02*
X119953D01*
G02X120156Y1603352I1J-202D01*
G01Y1602730D01*
G03X120206Y1602598I200J0D01*
G02Y1599686I-1664J-1456D01*
G03X120156Y1599554I150J-132D01*
G01Y1597612D01*
G03X120206Y1597480I200J0D01*
G02Y1594568I-1664J-1456D01*
G03X120156Y1594436I150J-132D01*
G01Y1593814D01*
G02X119953Y1593612I-203J1D01*
G01X117133D01*
G02X116930Y1593814I-1J202D01*
G01Y1594436D01*
G03X116880Y1594568I-200J0D01*
G02Y1597480I1664J1456D01*
G03X116930Y1597612I-150J132D01*
G01Y1599554D01*
G03X116880Y1599686I-200J0D01*
G02Y1602598I1664J1456D01*
G03X116930Y1602730I-150J132D01*
G01Y1603352D01*
G02X117133Y1603554I203J-1D01*
G37*
G36*
G01X151779D02*
X154599D01*
G02X154802Y1603352I1J-202D01*
G01Y1602730D01*
G03X154852Y1602598I200J0D01*
G02Y1599686I-1664J-1456D01*
G03X154802Y1599554I150J-132D01*
G01Y1597612D01*
G03X154852Y1597480I200J0D01*
G02Y1594568I-1664J-1456D01*
G03X154802Y1594436I150J-132D01*
G01Y1593814D01*
G02X154599Y1593612I-203J1D01*
G01X151779D01*
G02X151576Y1593814I-1J202D01*
G01Y1594436D01*
G03X151526Y1594568I-200J0D01*
G02Y1597480I1664J1456D01*
G03X151576Y1597612I-150J132D01*
G01Y1599554D01*
G03X151526Y1599686I-200J0D01*
G02Y1602598I1664J1456D01*
G03X151576Y1602730I-150J132D01*
G01Y1603352D01*
G02X151779Y1603554I203J-1D01*
G37*
G36*
G01X186425D02*
X189245D01*
G02X189448Y1603352I1J-202D01*
G01Y1602730D01*
G03X189498Y1602598I200J0D01*
G02Y1599686I-1664J-1456D01*
G03X189448Y1599554I150J-132D01*
G01Y1597612D01*
G03X189498Y1597480I200J0D01*
G02Y1594568I-1664J-1456D01*
G03X189448Y1594436I150J-132D01*
G01Y1593814D01*
G02X189245Y1593612I-203J1D01*
G01X186425D01*
G02X186222Y1593814I-1J202D01*
G01Y1594436D01*
G03X186172Y1594568I-200J0D01*
G02Y1597480I1664J1456D01*
G03X186222Y1597612I-150J132D01*
G01Y1599554D01*
G03X186172Y1599686I-200J0D01*
G02Y1602598I1664J1456D01*
G03X186222Y1602730I-150J132D01*
G01Y1603352D01*
G02X186425Y1603554I203J-1D01*
G37*
G36*
G01X290361D02*
X293181D01*
G02X293384Y1603352I1J-202D01*
G01Y1602730D01*
G03X293434Y1602598I200J0D01*
G02Y1599686I-1664J-1456D01*
G03X293384Y1599554I150J-132D01*
G01Y1597612D01*
G03X293434Y1597480I200J0D01*
G02Y1594568I-1664J-1456D01*
G03X293384Y1594436I150J-132D01*
G01Y1593814D01*
G02X293181Y1593612I-203J1D01*
G01X290361D01*
G02X290158Y1593814I-1J202D01*
G01Y1594436D01*
G03X290108Y1594568I-200J0D01*
G02Y1597480I1664J1456D01*
G03X290158Y1597612I-150J132D01*
G01Y1599554D01*
G03X290108Y1599686I-200J0D01*
G02Y1602598I1664J1456D01*
G03X290158Y1602730I-150J132D01*
G01Y1603352D01*
G02X290361Y1603554I203J-1D01*
G37*
G36*
G01X325007D02*
X327827D01*
G02X328030Y1603352I1J-202D01*
G01Y1602730D01*
G03X328080Y1602598I200J0D01*
G02Y1599686I-1664J-1456D01*
G03X328030Y1599554I150J-132D01*
G01Y1597612D01*
G03X328080Y1597480I200J0D01*
G02Y1594568I-1664J-1456D01*
G03X328030Y1594436I150J-132D01*
G01Y1593814D01*
G02X327827Y1593612I-203J1D01*
G01X325007D01*
G02X324804Y1593814I-1J202D01*
G01Y1594436D01*
G03X324754Y1594568I-200J0D01*
G02Y1597480I1664J1456D01*
G03X324804Y1597612I-150J132D01*
G01Y1599554D01*
G03X324754Y1599686I-200J0D01*
G02Y1602598I1664J1456D01*
G03X324804Y1602730I-150J132D01*
G01Y1603352D01*
G02X325007Y1603554I203J-1D01*
G37*
G36*
G01X359653D02*
X362473D01*
G02X362676Y1603352I1J-202D01*
G01Y1602730D01*
G03X362726Y1602598I200J0D01*
G02Y1599686I-1664J-1456D01*
G03X362676Y1599554I150J-132D01*
G01Y1597612D01*
G03X362726Y1597480I200J0D01*
G02Y1594568I-1664J-1456D01*
G03X362676Y1594436I150J-132D01*
G01Y1593814D01*
G02X362473Y1593612I-203J1D01*
G01X359653D01*
G02X359450Y1593814I-1J202D01*
G01Y1594436D01*
G03X359400Y1594568I-200J0D01*
G02Y1597480I1664J1456D01*
G03X359450Y1597612I-150J132D01*
G01Y1599554D01*
G03X359400Y1599686I-200J0D01*
G02Y1602598I1664J1456D01*
G03X359450Y1602730I-150J132D01*
G01Y1603352D01*
G02X359653Y1603554I203J-1D01*
G37*
G36*
G01X515559D02*
X518379D01*
G02X518582Y1603352I1J-202D01*
G01Y1602730D01*
G03X518632Y1602598I200J0D01*
G02Y1599686I-1664J-1456D01*
G03X518582Y1599554I150J-132D01*
G01Y1597612D01*
G03X518632Y1597480I200J0D01*
G02Y1594568I-1664J-1456D01*
G03X518582Y1594436I150J-132D01*
G01Y1593814D01*
G02X518379Y1593612I-203J1D01*
G01X515559D01*
G02X515356Y1593814I-1J202D01*
G01Y1594436D01*
G03X515306Y1594568I-200J0D01*
G02Y1597480I1664J1456D01*
G03X515356Y1597612I-150J132D01*
G01Y1599554D01*
G03X515306Y1599686I-200J0D01*
G02Y1602598I1664J1456D01*
G03X515356Y1602730I-150J132D01*
G01Y1603352D01*
G02X515559Y1603554I203J-1D01*
G37*
G36*
G01X654141D02*
X656961D01*
G02X657164Y1603352I1J-202D01*
G01Y1602730D01*
G03X657214Y1602598I200J0D01*
G02Y1599686I-1664J-1456D01*
G03X657164Y1599554I150J-132D01*
G01Y1597612D01*
G03X657214Y1597480I200J0D01*
G02Y1594568I-1664J-1456D01*
G03X657164Y1594436I150J-132D01*
G01Y1593814D01*
G02X656961Y1593612I-203J1D01*
G01X654141D01*
G02X653938Y1593814I-1J202D01*
G01Y1594436D01*
G03X653888Y1594568I-200J0D01*
G02Y1597480I1664J1456D01*
G03X653938Y1597612I-150J132D01*
G01Y1599554D01*
G03X653888Y1599686I-200J0D01*
G02Y1602598I1664J1456D01*
G03X653938Y1602730I-150J132D01*
G01Y1603352D01*
G02X654141Y1603554I203J-1D01*
G37*
G36*
G01X688787D02*
X691607D01*
G02X691810Y1603352I1J-202D01*
G01Y1602730D01*
G03X691860Y1602598I200J0D01*
G02Y1599686I-1664J-1456D01*
G03X691810Y1599554I150J-132D01*
G01Y1597612D01*
G03X691860Y1597480I200J0D01*
G02Y1594568I-1664J-1456D01*
G03X691810Y1594436I150J-132D01*
G01Y1593814D01*
G02X691607Y1593612I-203J1D01*
G01X688787D01*
G02X688584Y1593814I-1J202D01*
G01Y1594436D01*
G03X688534Y1594568I-200J0D01*
G02Y1597480I1664J1456D01*
G03X688584Y1597612I-150J132D01*
G01Y1599554D01*
G03X688534Y1599686I-200J0D01*
G02Y1602598I1664J1456D01*
G03X688584Y1602730I-150J132D01*
G01Y1603352D01*
G02X688787Y1603554I203J-1D01*
G37*
G36*
G01X1139101D02*
X1141921D01*
G02X1142124Y1603352I1J-202D01*
G01Y1602730D01*
G03X1142174Y1602598I200J0D01*
G02Y1599686I-1664J-1456D01*
G03X1142124Y1599554I150J-132D01*
G01Y1597612D01*
G03X1142174Y1597480I200J0D01*
G02Y1594568I-1664J-1456D01*
G03X1142124Y1594436I150J-132D01*
G01Y1593814D01*
G02X1141921Y1593612I-203J1D01*
G01X1139101D01*
G02X1138898Y1593814I-1J202D01*
G01Y1594436D01*
G03X1138848Y1594568I-200J0D01*
G02Y1597480I1664J1456D01*
G03X1138898Y1597612I-150J132D01*
G01Y1599554D01*
G03X1138848Y1599686I-200J0D01*
G02Y1602598I1664J1456D01*
G03X1138898Y1602730I-150J132D01*
G01Y1603352D01*
G02X1139101Y1603554I203J-1D01*
G37*
G36*
G01X1173747D02*
X1176567D01*
G02X1176770Y1603352I1J-202D01*
G01Y1602730D01*
G03X1176820Y1602598I200J0D01*
G02Y1599686I-1664J-1456D01*
G03X1176770Y1599554I150J-132D01*
G01Y1597612D01*
G03X1176820Y1597480I200J0D01*
G02Y1594568I-1664J-1456D01*
G03X1176770Y1594436I150J-132D01*
G01Y1593814D01*
G02X1176567Y1593612I-203J1D01*
G01X1173747D01*
G02X1173544Y1593814I-1J202D01*
G01Y1594436D01*
G03X1173494Y1594568I-200J0D01*
G02Y1597480I1664J1456D01*
G03X1173544Y1597612I-150J132D01*
G01Y1599554D01*
G03X1173494Y1599686I-200J0D01*
G02Y1602598I1664J1456D01*
G03X1173544Y1602730I-150J132D01*
G01Y1603352D01*
G02X1173747Y1603554I203J-1D01*
G37*
G36*
G01X1329653D02*
X1332473D01*
G02X1332676Y1603352I1J-202D01*
G01Y1602730D01*
G03X1332726Y1602598I200J0D01*
G02Y1599686I-1664J-1456D01*
G03X1332676Y1599554I150J-132D01*
G01Y1597612D01*
G03X1332726Y1597480I200J0D01*
G02Y1594568I-1664J-1456D01*
G03X1332676Y1594436I150J-132D01*
G01Y1593814D01*
G02X1332473Y1593612I-203J1D01*
G01X1329653D01*
G02X1329450Y1593814I-1J202D01*
G01Y1594436D01*
G03X1329400Y1594568I-200J0D01*
G02Y1597480I1664J1456D01*
G03X1329450Y1597612I-150J132D01*
G01Y1599554D01*
G03X1329400Y1599686I-200J0D01*
G02Y1602598I1664J1456D01*
G03X1329450Y1602730I-150J132D01*
G01Y1603352D01*
G02X1329653Y1603554I203J-1D01*
G37*
G36*
G01X1364299D02*
X1367119D01*
G02X1367322Y1603352I1J-202D01*
G01Y1602730D01*
G03X1367372Y1602598I200J0D01*
G02Y1599686I-1664J-1456D01*
G03X1367322Y1599554I150J-132D01*
G01Y1597612D01*
G03X1367372Y1597480I200J0D01*
G02Y1594568I-1664J-1456D01*
G03X1367322Y1594436I150J-132D01*
G01Y1593814D01*
G02X1367119Y1593612I-203J1D01*
G01X1364299D01*
G02X1364096Y1593814I-1J202D01*
G01Y1594436D01*
G03X1364046Y1594568I-200J0D01*
G02Y1597480I1664J1456D01*
G03X1364096Y1597612I-150J132D01*
G01Y1599554D01*
G03X1364046Y1599686I-200J0D01*
G02Y1602598I1664J1456D01*
G03X1364096Y1602730I-150J132D01*
G01Y1603352D01*
G02X1364299Y1603554I203J-1D01*
G37*
G36*
G01X1676109D02*
X1678929D01*
G02X1679132Y1603352I1J-202D01*
G01Y1602730D01*
G03X1679182Y1602598I200J0D01*
G02Y1599686I-1664J-1456D01*
G03X1679132Y1599554I150J-132D01*
G01Y1597612D01*
G03X1679182Y1597480I200J0D01*
G02Y1594568I-1664J-1456D01*
G03X1679132Y1594436I150J-132D01*
G01Y1593814D01*
G02X1678929Y1593612I-203J1D01*
G01X1676109D01*
G02X1675906Y1593814I-1J202D01*
G01Y1594436D01*
G03X1675856Y1594568I-200J0D01*
G02Y1597480I1664J1456D01*
G03X1675906Y1597612I-150J132D01*
G01Y1599554D01*
G03X1675856Y1599686I-200J0D01*
G02Y1602598I1664J1456D01*
G03X1675906Y1602730I-150J132D01*
G01Y1603352D01*
G02X1676109Y1603554I203J-1D01*
G37*
G36*
G01X1710755D02*
X1713575D01*
G02X1713778Y1603352I1J-202D01*
G01Y1602730D01*
G03X1713828Y1602598I200J0D01*
G02Y1599686I-1664J-1456D01*
G03X1713778Y1599554I150J-132D01*
G01Y1597612D01*
G03X1713828Y1597480I200J0D01*
G02Y1594568I-1664J-1456D01*
G03X1713778Y1594436I150J-132D01*
G01Y1593814D01*
G02X1713575Y1593612I-203J1D01*
G01X1710755D01*
G02X1710552Y1593814I-1J202D01*
G01Y1594436D01*
G03X1710502Y1594568I-200J0D01*
G02Y1597480I1664J1456D01*
G03X1710552Y1597612I-150J132D01*
G01Y1599554D01*
G03X1710502Y1599686I-200J0D01*
G02Y1602598I1664J1456D01*
G03X1710552Y1602730I-150J132D01*
G01Y1603352D01*
G02X1710755Y1603554I203J-1D01*
G37*
G36*
G01X108472Y1614578D02*
X111292D01*
G02X111494Y1614376I0J-202D01*
G01Y1613756D01*
G03X111544Y1613624I200J0D01*
G02Y1610708I-1661J-1458D01*
G03X111494Y1610576I150J-132D01*
G01Y1608638D01*
G03X111544Y1608506I200J0D01*
G02Y1605590I-1661J-1458D01*
G03X111494Y1605458I150J-132D01*
G01Y1604838D01*
G02X111292Y1604636I-202J0D01*
G01X108472D01*
G02X108270Y1604838I0J202D01*
G01Y1605458D01*
G03X108220Y1605590I-200J0D01*
G02Y1608506I1661J1458D01*
G03X108270Y1608638I-150J132D01*
G01Y1610576D01*
G03X108220Y1610708I-200J0D01*
G02Y1613624I1661J1458D01*
G03X108270Y1613756I-150J132D01*
G01Y1614376D01*
G02X108472Y1614578I202J0D01*
G37*
G36*
G01X143118D02*
X145938D01*
G02X146140Y1614376I0J-202D01*
G01Y1613756D01*
G03X146190Y1613624I200J0D01*
G02Y1610708I-1661J-1458D01*
G03X146140Y1610576I150J-132D01*
G01Y1608638D01*
G03X146190Y1608506I200J0D01*
G02Y1605590I-1661J-1458D01*
G03X146140Y1605458I150J-132D01*
G01Y1604838D01*
G02X145938Y1604636I-202J0D01*
G01X143118D01*
G02X142916Y1604838I0J202D01*
G01Y1605458D01*
G03X142866Y1605590I-200J0D01*
G02Y1608506I1661J1458D01*
G03X142916Y1608638I-150J132D01*
G01Y1610576D01*
G03X142866Y1610708I-200J0D01*
G02Y1613624I1661J1458D01*
G03X142916Y1613756I-150J132D01*
G01Y1614376D01*
G02X143118Y1614578I202J0D01*
G37*
G36*
G01X160440D02*
X163260D01*
G02X163462Y1614376I0J-202D01*
G01Y1613756D01*
G03X163512Y1613624I200J0D01*
G02Y1610708I-1661J-1458D01*
G03X163462Y1610576I150J-132D01*
G01Y1608638D01*
G03X163512Y1608506I200J0D01*
G02Y1605590I-1661J-1458D01*
G03X163462Y1605458I150J-132D01*
G01Y1604838D01*
G02X163260Y1604636I-202J0D01*
G01X160440D01*
G02X160238Y1604838I0J202D01*
G01Y1605458D01*
G03X160188Y1605590I-200J0D01*
G02Y1608506I1661J1458D01*
G03X160238Y1608638I-150J132D01*
G01Y1610576D01*
G03X160188Y1610708I-200J0D01*
G02Y1613624I1661J1458D01*
G03X160238Y1613756I-150J132D01*
G01Y1614376D01*
G02X160440Y1614578I202J0D01*
G37*
G36*
G01X281700D02*
X284520D01*
G02X284722Y1614376I0J-202D01*
G01Y1613756D01*
G03X284772Y1613624I200J0D01*
G02Y1610708I-1661J-1458D01*
G03X284722Y1610576I150J-132D01*
G01Y1608638D01*
G03X284772Y1608506I200J0D01*
G02Y1605590I-1661J-1458D01*
G03X284722Y1605458I150J-132D01*
G01Y1604838D01*
G02X284520Y1604636I-202J0D01*
G01X281700D01*
G02X281498Y1604838I0J202D01*
G01Y1605458D01*
G03X281448Y1605590I-200J0D01*
G02Y1608506I1661J1458D01*
G03X281498Y1608638I-150J132D01*
G01Y1610576D01*
G03X281448Y1610708I-200J0D01*
G02Y1613624I1661J1458D01*
G03X281498Y1613756I-150J132D01*
G01Y1614376D01*
G02X281700Y1614578I202J0D01*
G37*
G36*
G01X316346D02*
X319166D01*
G02X319368Y1614376I0J-202D01*
G01Y1613756D01*
G03X319418Y1613624I200J0D01*
G02Y1610708I-1661J-1458D01*
G03X319368Y1610576I150J-132D01*
G01Y1608638D01*
G03X319418Y1608506I200J0D01*
G02Y1605590I-1661J-1458D01*
G03X319368Y1605458I150J-132D01*
G01Y1604838D01*
G02X319166Y1604636I-202J0D01*
G01X316346D01*
G02X316144Y1604838I0J202D01*
G01Y1605458D01*
G03X316094Y1605590I-200J0D01*
G02Y1608506I1661J1458D01*
G03X316144Y1608638I-150J132D01*
G01Y1610576D01*
G03X316094Y1610708I-200J0D01*
G02Y1613624I1661J1458D01*
G03X316144Y1613756I-150J132D01*
G01Y1614376D01*
G02X316346Y1614578I202J0D01*
G37*
G36*
G01X333668D02*
X336488D01*
G02X336690Y1614376I0J-202D01*
G01Y1613756D01*
G03X336740Y1613624I200J0D01*
G02Y1610708I-1661J-1458D01*
G03X336690Y1610576I150J-132D01*
G01Y1608638D01*
G03X336740Y1608506I200J0D01*
G02Y1605590I-1661J-1458D01*
G03X336690Y1605458I150J-132D01*
G01Y1604838D01*
G02X336488Y1604636I-202J0D01*
G01X333668D01*
G02X333466Y1604838I0J202D01*
G01Y1605458D01*
G03X333416Y1605590I-200J0D01*
G02Y1608506I1661J1458D01*
G03X333466Y1608638I-150J132D01*
G01Y1610576D01*
G03X333416Y1610708I-200J0D01*
G02Y1613624I1661J1458D01*
G03X333466Y1613756I-150J132D01*
G01Y1614376D01*
G02X333668Y1614578I202J0D01*
G37*
G36*
G01X645480D02*
X648300D01*
G02X648502Y1614376I0J-202D01*
G01Y1613756D01*
G03X648552Y1613624I200J0D01*
G02Y1610708I-1661J-1458D01*
G03X648502Y1610576I150J-132D01*
G01Y1608638D01*
G03X648552Y1608506I200J0D01*
G02Y1605590I-1661J-1458D01*
G03X648502Y1605458I150J-132D01*
G01Y1604838D01*
G02X648300Y1604636I-202J0D01*
G01X645480D01*
G02X645278Y1604838I0J202D01*
G01Y1605458D01*
G03X645228Y1605590I-200J0D01*
G02Y1608506I1661J1458D01*
G03X645278Y1608638I-150J132D01*
G01Y1610576D01*
G03X645228Y1610708I-200J0D01*
G02Y1613624I1661J1458D01*
G03X645278Y1613756I-150J132D01*
G01Y1614376D01*
G02X645480Y1614578I202J0D01*
G37*
G36*
G01X1130440D02*
X1133260D01*
G02X1133462Y1614376I0J-202D01*
G01Y1613756D01*
G03X1133512Y1613624I200J0D01*
G02Y1610708I-1661J-1458D01*
G03X1133462Y1610576I150J-132D01*
G01Y1608638D01*
G03X1133512Y1608506I200J0D01*
G02Y1605590I-1661J-1458D01*
G03X1133462Y1605458I150J-132D01*
G01Y1604838D01*
G02X1133260Y1604636I-202J0D01*
G01X1130440D01*
G02X1130238Y1604838I0J202D01*
G01Y1605458D01*
G03X1130188Y1605590I-200J0D01*
G02Y1608506I1661J1458D01*
G03X1130238Y1608638I-150J132D01*
G01Y1610576D01*
G03X1130188Y1610708I-200J0D01*
G02Y1613624I1661J1458D01*
G03X1130238Y1613756I-150J132D01*
G01Y1614376D01*
G02X1130440Y1614578I202J0D01*
G37*
G36*
G01X1165086D02*
X1167906D01*
G02X1168108Y1614376I0J-202D01*
G01Y1613756D01*
G03X1168158Y1613624I200J0D01*
G02Y1610708I-1661J-1458D01*
G03X1168108Y1610576I150J-132D01*
G01Y1608638D01*
G03X1168158Y1608506I200J0D01*
G02Y1605590I-1661J-1458D01*
G03X1168108Y1605458I150J-132D01*
G01Y1604838D01*
G02X1167906Y1604636I-202J0D01*
G01X1165086D01*
G02X1164884Y1604838I0J202D01*
G01Y1605458D01*
G03X1164834Y1605590I-200J0D01*
G02Y1608506I1661J1458D01*
G03X1164884Y1608638I-150J132D01*
G01Y1610576D01*
G03X1164834Y1610708I-200J0D01*
G02Y1613624I1661J1458D01*
G03X1164884Y1613756I-150J132D01*
G01Y1614376D01*
G02X1165086Y1614578I202J0D01*
G37*
G36*
G01X1182408D02*
X1185228D01*
G02X1185430Y1614376I0J-202D01*
G01Y1613756D01*
G03X1185480Y1613624I200J0D01*
G02Y1610708I-1661J-1458D01*
G03X1185430Y1610576I150J-132D01*
G01Y1608638D01*
G03X1185480Y1608506I200J0D01*
G02Y1605590I-1661J-1458D01*
G03X1185430Y1605458I150J-132D01*
G01Y1604838D01*
G02X1185228Y1604636I-202J0D01*
G01X1182408D01*
G02X1182206Y1604838I0J202D01*
G01Y1605458D01*
G03X1182156Y1605590I-200J0D01*
G02Y1608506I1661J1458D01*
G03X1182206Y1608638I-150J132D01*
G01Y1610576D01*
G03X1182156Y1610708I-200J0D01*
G02Y1613624I1661J1458D01*
G03X1182206Y1613756I-150J132D01*
G01Y1614376D01*
G02X1182408Y1614578I202J0D01*
G37*
G36*
G01X1320992D02*
X1323812D01*
G02X1324014Y1614376I0J-202D01*
G01Y1613756D01*
G03X1324064Y1613624I200J0D01*
G02Y1610708I-1661J-1458D01*
G03X1324014Y1610576I150J-132D01*
G01Y1608638D01*
G03X1324064Y1608506I200J0D01*
G02Y1605590I-1661J-1458D01*
G03X1324014Y1605458I150J-132D01*
G01Y1604838D01*
G02X1323812Y1604636I-202J0D01*
G01X1320992D01*
G02X1320790Y1604838I0J202D01*
G01Y1605458D01*
G03X1320740Y1605590I-200J0D01*
G02Y1608506I1661J1458D01*
G03X1320790Y1608638I-150J132D01*
G01Y1610576D01*
G03X1320740Y1610708I-200J0D01*
G02Y1613624I1661J1458D01*
G03X1320790Y1613756I-150J132D01*
G01Y1614376D01*
G02X1320992Y1614578I202J0D01*
G37*
G36*
G01X1667448D02*
X1670268D01*
G02X1670470Y1614376I0J-202D01*
G01Y1613756D01*
G03X1670520Y1613624I200J0D01*
G02Y1610708I-1661J-1458D01*
G03X1670470Y1610576I150J-132D01*
G01Y1608638D01*
G03X1670520Y1608506I200J0D01*
G02Y1605590I-1661J-1458D01*
G03X1670470Y1605458I150J-132D01*
G01Y1604838D01*
G02X1670268Y1604636I-202J0D01*
G01X1667448D01*
G02X1667246Y1604838I0J202D01*
G01Y1605458D01*
G03X1667196Y1605590I-200J0D01*
G02Y1608506I1661J1458D01*
G03X1667246Y1608638I-150J132D01*
G01Y1610576D01*
G03X1667196Y1610708I-200J0D01*
G02Y1613624I1661J1458D01*
G03X1667246Y1613756I-150J132D01*
G01Y1614376D01*
G02X1667448Y1614578I202J0D01*
G37*
G36*
G01X125795D02*
X128615D01*
G02X128818Y1614376I1J-202D01*
G01Y1613754D01*
G03X128868Y1613622I200J0D01*
G02Y1610710I-1664J-1456D01*
G03X128818Y1610578I150J-132D01*
G01Y1608636D01*
G03X128868Y1608504I200J0D01*
G02Y1605592I-1664J-1456D01*
G03X128818Y1605460I150J-132D01*
G01Y1604838D01*
G02X128615Y1604636I-203J1D01*
G01X125795D01*
G02X125592Y1604838I-1J202D01*
G01Y1605460D01*
G03X125542Y1605592I-200J0D01*
G02Y1608504I1664J1456D01*
G03X125592Y1608636I-150J132D01*
G01Y1610578D01*
G03X125542Y1610710I-200J0D01*
G02Y1613622I1664J1456D01*
G03X125592Y1613754I-150J132D01*
G01Y1614376D01*
G02X125795Y1614578I203J-1D01*
G37*
G36*
G01X299023D02*
X301843D01*
G02X302046Y1614376I1J-202D01*
G01Y1613754D01*
G03X302096Y1613622I200J0D01*
G02Y1610710I-1664J-1456D01*
G03X302046Y1610578I150J-132D01*
G01Y1608636D01*
G03X302096Y1608504I200J0D01*
G02Y1605592I-1664J-1456D01*
G03X302046Y1605460I150J-132D01*
G01Y1604838D01*
G02X301843Y1604636I-203J1D01*
G01X299023D01*
G02X298820Y1604838I-1J202D01*
G01Y1605460D01*
G03X298770Y1605592I-200J0D01*
G02Y1608504I1664J1456D01*
G03X298820Y1608636I-150J132D01*
G01Y1610578D01*
G03X298770Y1610710I-200J0D01*
G02Y1613622I1664J1456D01*
G03X298820Y1613754I-150J132D01*
G01Y1614376D01*
G02X299023Y1614578I203J-1D01*
G37*
G36*
G01X628157D02*
X630977D01*
G02X631180Y1614376I1J-202D01*
G01Y1613754D01*
G03X631230Y1613622I200J0D01*
G02Y1610710I-1664J-1456D01*
G03X631180Y1610578I150J-132D01*
G01Y1608636D01*
G03X631230Y1608504I200J0D01*
G02Y1605592I-1664J-1456D01*
G03X631180Y1605460I150J-132D01*
G01Y1604838D01*
G02X630977Y1604636I-203J1D01*
G01X628157D01*
G02X627954Y1604838I-1J202D01*
G01Y1605460D01*
G03X627904Y1605592I-200J0D01*
G02Y1608504I1664J1456D01*
G03X627954Y1608636I-150J132D01*
G01Y1610578D01*
G03X627904Y1610710I-200J0D01*
G02Y1613622I1664J1456D01*
G03X627954Y1613754I-150J132D01*
G01Y1614376D01*
G02X628157Y1614578I203J-1D01*
G37*
G36*
G01X662803D02*
X665623D01*
G02X665826Y1614376I1J-202D01*
G01Y1613754D01*
G03X665876Y1613622I200J0D01*
G02Y1610710I-1664J-1456D01*
G03X665826Y1610578I150J-132D01*
G01Y1608636D01*
G03X665876Y1608504I200J0D01*
G02Y1605592I-1664J-1456D01*
G03X665826Y1605460I150J-132D01*
G01Y1604838D01*
G02X665623Y1604636I-203J1D01*
G01X662803D01*
G02X662600Y1604838I-1J202D01*
G01Y1605460D01*
G03X662550Y1605592I-200J0D01*
G02Y1608504I1664J1456D01*
G03X662600Y1608636I-150J132D01*
G01Y1610578D01*
G03X662550Y1610710I-200J0D01*
G02Y1613622I1664J1456D01*
G03X662600Y1613754I-150J132D01*
G01Y1614376D01*
G02X662803Y1614578I203J-1D01*
G37*
G36*
G01X680125D02*
X682945D01*
G02X683148Y1614376I1J-202D01*
G01Y1613754D01*
G03X683198Y1613622I200J0D01*
G02Y1610710I-1664J-1456D01*
G03X683148Y1610578I150J-132D01*
G01Y1608636D01*
G03X683198Y1608504I200J0D01*
G02Y1605592I-1664J-1456D01*
G03X683148Y1605460I150J-132D01*
G01Y1604838D01*
G02X682945Y1604636I-203J1D01*
G01X680125D01*
G02X679922Y1604838I-1J202D01*
G01Y1605460D01*
G03X679872Y1605592I-200J0D01*
G02Y1608504I1664J1456D01*
G03X679922Y1608636I-150J132D01*
G01Y1610578D01*
G03X679872Y1610710I-200J0D01*
G02Y1613622I1664J1456D01*
G03X679922Y1613754I-150J132D01*
G01Y1614376D01*
G02X680125Y1614578I203J-1D01*
G37*
G36*
G01X1147763D02*
X1150583D01*
G02X1150786Y1614376I1J-202D01*
G01Y1613754D01*
G03X1150836Y1613622I200J0D01*
G02Y1610710I-1664J-1456D01*
G03X1150786Y1610578I150J-132D01*
G01Y1608636D01*
G03X1150836Y1608504I200J0D01*
G02Y1605592I-1664J-1456D01*
G03X1150786Y1605460I150J-132D01*
G01Y1604838D01*
G02X1150583Y1604636I-203J1D01*
G01X1147763D01*
G02X1147560Y1604838I-1J202D01*
G01Y1605460D01*
G03X1147510Y1605592I-200J0D01*
G02Y1608504I1664J1456D01*
G03X1147560Y1608636I-150J132D01*
G01Y1610578D01*
G03X1147510Y1610710I-200J0D01*
G02Y1613622I1664J1456D01*
G03X1147560Y1613754I-150J132D01*
G01Y1614376D01*
G02X1147763Y1614578I203J-1D01*
G37*
G36*
G01X1303669D02*
X1306489D01*
G02X1306692Y1614376I1J-202D01*
G01Y1613754D01*
G03X1306742Y1613622I200J0D01*
G02Y1610710I-1664J-1456D01*
G03X1306692Y1610578I150J-132D01*
G01Y1608636D01*
G03X1306742Y1608504I200J0D01*
G02Y1605592I-1664J-1456D01*
G03X1306692Y1605460I150J-132D01*
G01Y1604838D01*
G02X1306489Y1604636I-203J1D01*
G01X1303669D01*
G02X1303466Y1604838I-1J202D01*
G01Y1605460D01*
G03X1303416Y1605592I-200J0D01*
G02Y1608504I1664J1456D01*
G03X1303466Y1608636I-150J132D01*
G01Y1610578D01*
G03X1303416Y1610710I-200J0D01*
G02Y1613622I1664J1456D01*
G03X1303466Y1613754I-150J132D01*
G01Y1614376D01*
G02X1303669Y1614578I203J-1D01*
G37*
G36*
G01X1338315D02*
X1341135D01*
G02X1341338Y1614376I1J-202D01*
G01Y1613754D01*
G03X1341388Y1613622I200J0D01*
G02Y1610710I-1664J-1456D01*
G03X1341338Y1610578I150J-132D01*
G01Y1608636D01*
G03X1341388Y1608504I200J0D01*
G02Y1605592I-1664J-1456D01*
G03X1341338Y1605460I150J-132D01*
G01Y1604838D01*
G02X1341135Y1604636I-203J1D01*
G01X1338315D01*
G02X1338112Y1604838I-1J202D01*
G01Y1605460D01*
G03X1338062Y1605592I-200J0D01*
G02Y1608504I1664J1456D01*
G03X1338112Y1608636I-150J132D01*
G01Y1610578D01*
G03X1338062Y1610710I-200J0D01*
G02Y1613622I1664J1456D01*
G03X1338112Y1613754I-150J132D01*
G01Y1614376D01*
G02X1338315Y1614578I203J-1D01*
G37*
G36*
G01X1355637D02*
X1358457D01*
G02X1358660Y1614376I1J-202D01*
G01Y1613754D01*
G03X1358710Y1613622I200J0D01*
G02Y1610710I-1664J-1456D01*
G03X1358660Y1610578I150J-132D01*
G01Y1608636D01*
G03X1358710Y1608504I200J0D01*
G02Y1605592I-1664J-1456D01*
G03X1358660Y1605460I150J-132D01*
G01Y1604838D01*
G02X1358457Y1604636I-203J1D01*
G01X1355637D01*
G02X1355434Y1604838I-1J202D01*
G01Y1605460D01*
G03X1355384Y1605592I-200J0D01*
G02Y1608504I1664J1456D01*
G03X1355434Y1608636I-150J132D01*
G01Y1610578D01*
G03X1355384Y1610710I-200J0D01*
G02Y1613622I1664J1456D01*
G03X1355434Y1613754I-150J132D01*
G01Y1614376D01*
G02X1355637Y1614578I203J-1D01*
G37*
G36*
G01X1476897D02*
X1479717D01*
G02X1479920Y1614376I1J-202D01*
G01Y1613754D01*
G03X1479970Y1613622I200J0D01*
G02Y1610710I-1664J-1456D01*
G03X1479920Y1610578I150J-132D01*
G01Y1608636D01*
G03X1479970Y1608504I200J0D01*
G02Y1605592I-1664J-1456D01*
G03X1479920Y1605460I150J-132D01*
G01Y1604838D01*
G02X1479717Y1604636I-203J1D01*
G01X1476897D01*
G02X1476694Y1604838I-1J202D01*
G01Y1605460D01*
G03X1476644Y1605592I-200J0D01*
G02Y1608504I1664J1456D01*
G03X1476694Y1608636I-150J132D01*
G01Y1610578D01*
G03X1476644Y1610710I-200J0D01*
G02Y1613622I1664J1456D01*
G03X1476694Y1613754I-150J132D01*
G01Y1614376D01*
G02X1476897Y1614578I203J-1D01*
G37*
G36*
G01X1650125D02*
X1652945D01*
G02X1653148Y1614376I1J-202D01*
G01Y1613754D01*
G03X1653198Y1613622I200J0D01*
G02Y1610710I-1664J-1456D01*
G03X1653148Y1610578I150J-132D01*
G01Y1608636D01*
G03X1653198Y1608504I200J0D01*
G02Y1605592I-1664J-1456D01*
G03X1653148Y1605460I150J-132D01*
G01Y1604838D01*
G02X1652945Y1604636I-203J1D01*
G01X1650125D01*
G02X1649922Y1604838I-1J202D01*
G01Y1605460D01*
G03X1649872Y1605592I-200J0D01*
G02Y1608504I1664J1456D01*
G03X1649922Y1608636I-150J132D01*
G01Y1610578D01*
G03X1649872Y1610710I-200J0D01*
G02Y1613622I1664J1456D01*
G03X1649922Y1613754I-150J132D01*
G01Y1614376D01*
G02X1650125Y1614578I203J-1D01*
G37*
G36*
G01X1684771D02*
X1687591D01*
G02X1687794Y1614376I1J-202D01*
G01Y1613754D01*
G03X1687844Y1613622I200J0D01*
G02Y1610710I-1664J-1456D01*
G03X1687794Y1610578I150J-132D01*
G01Y1608636D01*
G03X1687844Y1608504I200J0D01*
G02Y1605592I-1664J-1456D01*
G03X1687794Y1605460I150J-132D01*
G01Y1604838D01*
G02X1687591Y1604636I-203J1D01*
G01X1684771D01*
G02X1684568Y1604838I-1J202D01*
G01Y1605460D01*
G03X1684518Y1605592I-200J0D01*
G02Y1608504I1664J1456D01*
G03X1684568Y1608636I-150J132D01*
G01Y1610578D01*
G03X1684518Y1610710I-200J0D01*
G02Y1613622I1664J1456D01*
G03X1684568Y1613754I-150J132D01*
G01Y1614376D01*
G02X1684771Y1614578I203J-1D01*
G37*
G36*
G01X1702093D02*
X1704913D01*
G02X1705116Y1614376I1J-202D01*
G01Y1613754D01*
G03X1705166Y1613622I200J0D01*
G02Y1610710I-1664J-1456D01*
G03X1705116Y1610578I150J-132D01*
G01Y1608636D01*
G03X1705166Y1608504I200J0D01*
G02Y1605592I-1664J-1456D01*
G03X1705116Y1605460I150J-132D01*
G01Y1604838D01*
G02X1704913Y1604636I-203J1D01*
G01X1702093D01*
G02X1701890Y1604838I-1J202D01*
G01Y1605460D01*
G03X1701840Y1605592I-200J0D01*
G02Y1608504I1664J1456D01*
G03X1701890Y1608636I-150J132D01*
G01Y1610578D01*
G03X1701840Y1610710I-200J0D01*
G02Y1613622I1664J1456D01*
G03X1701890Y1613754I-150J132D01*
G01Y1614376D01*
G02X1702093Y1614578I203J-1D01*
G37*
G36*
G01X134456Y1618908D02*
X137276D01*
G02X137478Y1618706I0J-202D01*
G01Y1618086D01*
G03X137528Y1617954I200J0D01*
G02Y1615038I-1661J-1458D01*
G03X137478Y1614906I150J-132D01*
G01Y1612968D01*
G03X137528Y1612836I200J0D01*
G02Y1609920I-1661J-1458D01*
G03X137478Y1609788I150J-132D01*
G01Y1609168D01*
G02X137276Y1608966I-202J0D01*
G01X134456D01*
G02X134254Y1609168I0J202D01*
G01Y1609788D01*
G03X134204Y1609920I-200J0D01*
G02Y1612836I1661J1458D01*
G03X134254Y1612968I-150J132D01*
G01Y1614906D01*
G03X134204Y1615038I-200J0D01*
G02Y1617954I1661J1458D01*
G03X134254Y1618086I-150J132D01*
G01Y1618706D01*
G02X134456Y1618908I202J0D01*
G37*
G36*
G01X169102D02*
X171922D01*
G02X172124Y1618706I0J-202D01*
G01Y1618086D01*
G03X172174Y1617954I200J0D01*
G02Y1615038I-1661J-1458D01*
G03X172124Y1614906I150J-132D01*
G01Y1612968D01*
G03X172174Y1612836I200J0D01*
G02Y1609920I-1661J-1458D01*
G03X172124Y1609788I150J-132D01*
G01Y1609168D01*
G02X171922Y1608966I-202J0D01*
G01X169102D01*
G02X168900Y1609168I0J202D01*
G01Y1609788D01*
G03X168850Y1609920I-200J0D01*
G02Y1612836I1661J1458D01*
G03X168900Y1612968I-150J132D01*
G01Y1614906D01*
G03X168850Y1615038I-200J0D01*
G02Y1617954I1661J1458D01*
G03X168900Y1618086I-150J132D01*
G01Y1618706D01*
G02X169102Y1618908I202J0D01*
G37*
G36*
G01X307684D02*
X310504D01*
G02X310706Y1618706I0J-202D01*
G01Y1618086D01*
G03X310756Y1617954I200J0D01*
G02Y1615038I-1661J-1458D01*
G03X310706Y1614906I150J-132D01*
G01Y1612968D01*
G03X310756Y1612836I200J0D01*
G02Y1609920I-1661J-1458D01*
G03X310706Y1609788I150J-132D01*
G01Y1609168D01*
G02X310504Y1608966I-202J0D01*
G01X307684D01*
G02X307482Y1609168I0J202D01*
G01Y1609788D01*
G03X307432Y1609920I-200J0D01*
G02Y1612836I1661J1458D01*
G03X307482Y1612968I-150J132D01*
G01Y1614906D01*
G03X307432Y1615038I-200J0D01*
G02Y1617954I1661J1458D01*
G03X307482Y1618086I-150J132D01*
G01Y1618706D01*
G02X307684Y1618908I202J0D01*
G37*
G36*
G01X342330D02*
X345150D01*
G02X345352Y1618706I0J-202D01*
G01Y1618086D01*
G03X345402Y1617954I200J0D01*
G02Y1615038I-1661J-1458D01*
G03X345352Y1614906I150J-132D01*
G01Y1612968D01*
G03X345402Y1612836I200J0D01*
G02Y1609920I-1661J-1458D01*
G03X345352Y1609788I150J-132D01*
G01Y1609168D01*
G02X345150Y1608966I-202J0D01*
G01X342330D01*
G02X342128Y1609168I0J202D01*
G01Y1609788D01*
G03X342078Y1609920I-200J0D01*
G02Y1612836I1661J1458D01*
G03X342128Y1612968I-150J132D01*
G01Y1614906D01*
G03X342078Y1615038I-200J0D01*
G02Y1617954I1661J1458D01*
G03X342128Y1618086I-150J132D01*
G01Y1618706D01*
G02X342330Y1618908I202J0D01*
G37*
G36*
G01X636818D02*
X639638D01*
G02X639840Y1618706I0J-202D01*
G01Y1618086D01*
G03X639890Y1617954I200J0D01*
G02Y1615038I-1661J-1458D01*
G03X639840Y1614906I150J-132D01*
G01Y1612968D01*
G03X639890Y1612836I200J0D01*
G02Y1609920I-1661J-1458D01*
G03X639840Y1609788I150J-132D01*
G01Y1609168D01*
G02X639638Y1608966I-202J0D01*
G01X636818D01*
G02X636616Y1609168I0J202D01*
G01Y1609788D01*
G03X636566Y1609920I-200J0D01*
G02Y1612836I1661J1458D01*
G03X636616Y1612968I-150J132D01*
G01Y1614906D01*
G03X636566Y1615038I-200J0D01*
G02Y1617954I1661J1458D01*
G03X636616Y1618086I-150J132D01*
G01Y1618706D01*
G02X636818Y1618908I202J0D01*
G37*
G36*
G01X671464D02*
X674284D01*
G02X674486Y1618706I0J-202D01*
G01Y1618086D01*
G03X674536Y1617954I200J0D01*
G02Y1615038I-1661J-1458D01*
G03X674486Y1614906I150J-132D01*
G01Y1612968D01*
G03X674536Y1612836I200J0D01*
G02Y1609920I-1661J-1458D01*
G03X674486Y1609788I150J-132D01*
G01Y1609168D01*
G02X674284Y1608966I-202J0D01*
G01X671464D01*
G02X671262Y1609168I0J202D01*
G01Y1609788D01*
G03X671212Y1609920I-200J0D01*
G02Y1612836I1661J1458D01*
G03X671262Y1612968I-150J132D01*
G01Y1614906D01*
G03X671212Y1615038I-200J0D01*
G02Y1617954I1661J1458D01*
G03X671262Y1618086I-150J132D01*
G01Y1618706D01*
G02X671464Y1618908I202J0D01*
G37*
G36*
G01X1156424D02*
X1159244D01*
G02X1159446Y1618706I0J-202D01*
G01Y1618086D01*
G03X1159496Y1617954I200J0D01*
G02Y1615038I-1661J-1458D01*
G03X1159446Y1614906I150J-132D01*
G01Y1612968D01*
G03X1159496Y1612836I200J0D01*
G02Y1609920I-1661J-1458D01*
G03X1159446Y1609788I150J-132D01*
G01Y1609168D01*
G02X1159244Y1608966I-202J0D01*
G01X1156424D01*
G02X1156222Y1609168I0J202D01*
G01Y1609788D01*
G03X1156172Y1609920I-200J0D01*
G02Y1612836I1661J1458D01*
G03X1156222Y1612968I-150J132D01*
G01Y1614906D01*
G03X1156172Y1615038I-200J0D01*
G02Y1617954I1661J1458D01*
G03X1156222Y1618086I-150J132D01*
G01Y1618706D01*
G02X1156424Y1618908I202J0D01*
G37*
G36*
G01X1191070D02*
X1193890D01*
G02X1194092Y1618706I0J-202D01*
G01Y1618086D01*
G03X1194142Y1617954I200J0D01*
G02Y1615038I-1661J-1458D01*
G03X1194092Y1614906I150J-132D01*
G01Y1612968D01*
G03X1194142Y1612836I200J0D01*
G02Y1609920I-1661J-1458D01*
G03X1194092Y1609788I150J-132D01*
G01Y1609168D01*
G02X1193890Y1608966I-202J0D01*
G01X1191070D01*
G02X1190868Y1609168I0J202D01*
G01Y1609788D01*
G03X1190818Y1609920I-200J0D01*
G02Y1612836I1661J1458D01*
G03X1190868Y1612968I-150J132D01*
G01Y1614906D01*
G03X1190818Y1615038I-200J0D01*
G02Y1617954I1661J1458D01*
G03X1190868Y1618086I-150J132D01*
G01Y1618706D01*
G02X1191070Y1618908I202J0D01*
G37*
G36*
G01X1312330D02*
X1315150D01*
G02X1315352Y1618706I0J-202D01*
G01Y1618086D01*
G03X1315402Y1617954I200J0D01*
G02Y1615038I-1661J-1458D01*
G03X1315352Y1614906I150J-132D01*
G01Y1612968D01*
G03X1315402Y1612836I200J0D01*
G02Y1609920I-1661J-1458D01*
G03X1315352Y1609788I150J-132D01*
G01Y1609168D01*
G02X1315150Y1608966I-202J0D01*
G01X1312330D01*
G02X1312128Y1609168I0J202D01*
G01Y1609788D01*
G03X1312078Y1609920I-200J0D01*
G02Y1612836I1661J1458D01*
G03X1312128Y1612968I-150J132D01*
G01Y1614906D01*
G03X1312078Y1615038I-200J0D01*
G02Y1617954I1661J1458D01*
G03X1312128Y1618086I-150J132D01*
G01Y1618706D01*
G02X1312330Y1618908I202J0D01*
G37*
G36*
G01X1346976D02*
X1349796D01*
G02X1349998Y1618706I0J-202D01*
G01Y1618086D01*
G03X1350048Y1617954I200J0D01*
G02Y1615038I-1661J-1458D01*
G03X1349998Y1614906I150J-132D01*
G01Y1612968D01*
G03X1350048Y1612836I200J0D01*
G02Y1609920I-1661J-1458D01*
G03X1349998Y1609788I150J-132D01*
G01Y1609168D01*
G02X1349796Y1608966I-202J0D01*
G01X1346976D01*
G02X1346774Y1609168I0J202D01*
G01Y1609788D01*
G03X1346724Y1609920I-200J0D01*
G02Y1612836I1661J1458D01*
G03X1346774Y1612968I-150J132D01*
G01Y1614906D01*
G03X1346724Y1615038I-200J0D01*
G02Y1617954I1661J1458D01*
G03X1346774Y1618086I-150J132D01*
G01Y1618706D01*
G02X1346976Y1618908I202J0D01*
G37*
G36*
G01X1658786D02*
X1661606D01*
G02X1661808Y1618706I0J-202D01*
G01Y1618086D01*
G03X1661858Y1617954I200J0D01*
G02Y1615038I-1661J-1458D01*
G03X1661808Y1614906I150J-132D01*
G01Y1612968D01*
G03X1661858Y1612836I200J0D01*
G02Y1609920I-1661J-1458D01*
G03X1661808Y1609788I150J-132D01*
G01Y1609168D01*
G02X1661606Y1608966I-202J0D01*
G01X1658786D01*
G02X1658584Y1609168I0J202D01*
G01Y1609788D01*
G03X1658534Y1609920I-200J0D01*
G02Y1612836I1661J1458D01*
G03X1658584Y1612968I-150J132D01*
G01Y1614906D01*
G03X1658534Y1615038I-200J0D01*
G02Y1617954I1661J1458D01*
G03X1658584Y1618086I-150J132D01*
G01Y1618706D01*
G02X1658786Y1618908I202J0D01*
G37*
G36*
G01X1693432D02*
X1696252D01*
G02X1696454Y1618706I0J-202D01*
G01Y1618086D01*
G03X1696504Y1617954I200J0D01*
G02Y1615038I-1661J-1458D01*
G03X1696454Y1614906I150J-132D01*
G01Y1612968D01*
G03X1696504Y1612836I200J0D01*
G02Y1609920I-1661J-1458D01*
G03X1696454Y1609788I150J-132D01*
G01Y1609168D01*
G02X1696252Y1608966I-202J0D01*
G01X1693432D01*
G02X1693230Y1609168I0J202D01*
G01Y1609788D01*
G03X1693180Y1609920I-200J0D01*
G02Y1612836I1661J1458D01*
G03X1693230Y1612968I-150J132D01*
G01Y1614906D01*
G03X1693180Y1615038I-200J0D01*
G02Y1617954I1661J1458D01*
G03X1693230Y1618086I-150J132D01*
G01Y1618706D01*
G02X1693432Y1618908I202J0D01*
G37*
G36*
G01X117133D02*
X119953D01*
G02X120156Y1618706I1J-202D01*
G01Y1618084D01*
G03X120206Y1617952I200J0D01*
G02Y1615040I-1664J-1456D01*
G03X120156Y1614908I150J-132D01*
G01Y1612966D01*
G03X120206Y1612834I200J0D01*
G02Y1609922I-1664J-1456D01*
G03X120156Y1609790I150J-132D01*
G01Y1609168D01*
G02X119953Y1608966I-203J1D01*
G01X117133D01*
G02X116930Y1609168I-1J202D01*
G01Y1609790D01*
G03X116880Y1609922I-200J0D01*
G02Y1612834I1664J1456D01*
G03X116930Y1612966I-150J132D01*
G01Y1614908D01*
G03X116880Y1615040I-200J0D01*
G02Y1617952I1664J1456D01*
G03X116930Y1618084I-150J132D01*
G01Y1618706D01*
G02X117133Y1618908I203J-1D01*
G37*
G36*
G01X151779D02*
X154599D01*
G02X154802Y1618706I1J-202D01*
G01Y1618084D01*
G03X154852Y1617952I200J0D01*
G02Y1615040I-1664J-1456D01*
G03X154802Y1614908I150J-132D01*
G01Y1612966D01*
G03X154852Y1612834I200J0D01*
G02Y1609922I-1664J-1456D01*
G03X154802Y1609790I150J-132D01*
G01Y1609168D01*
G02X154599Y1608966I-203J1D01*
G01X151779D01*
G02X151576Y1609168I-1J202D01*
G01Y1609790D01*
G03X151526Y1609922I-200J0D01*
G02Y1612834I1664J1456D01*
G03X151576Y1612966I-150J132D01*
G01Y1614908D01*
G03X151526Y1615040I-200J0D01*
G02Y1617952I1664J1456D01*
G03X151576Y1618084I-150J132D01*
G01Y1618706D01*
G02X151779Y1618908I203J-1D01*
G37*
G36*
G01X186425D02*
X189245D01*
G02X189448Y1618706I1J-202D01*
G01Y1618084D01*
G03X189498Y1617952I200J0D01*
G02Y1615040I-1664J-1456D01*
G03X189448Y1614908I150J-132D01*
G01Y1612966D01*
G03X189498Y1612834I200J0D01*
G02Y1609922I-1664J-1456D01*
G03X189448Y1609790I150J-132D01*
G01Y1609168D01*
G02X189245Y1608966I-203J1D01*
G01X186425D01*
G02X186222Y1609168I-1J202D01*
G01Y1609790D01*
G03X186172Y1609922I-200J0D01*
G02Y1612834I1664J1456D01*
G03X186222Y1612966I-150J132D01*
G01Y1614908D01*
G03X186172Y1615040I-200J0D01*
G02Y1617952I1664J1456D01*
G03X186222Y1618084I-150J132D01*
G01Y1618706D01*
G02X186425Y1618908I203J-1D01*
G37*
G36*
G01X290361D02*
X293181D01*
G02X293384Y1618706I1J-202D01*
G01Y1618084D01*
G03X293434Y1617952I200J0D01*
G02Y1615040I-1664J-1456D01*
G03X293384Y1614908I150J-132D01*
G01Y1612966D01*
G03X293434Y1612834I200J0D01*
G02Y1609922I-1664J-1456D01*
G03X293384Y1609790I150J-132D01*
G01Y1609168D01*
G02X293181Y1608966I-203J1D01*
G01X290361D01*
G02X290158Y1609168I-1J202D01*
G01Y1609790D01*
G03X290108Y1609922I-200J0D01*
G02Y1612834I1664J1456D01*
G03X290158Y1612966I-150J132D01*
G01Y1614908D01*
G03X290108Y1615040I-200J0D01*
G02Y1617952I1664J1456D01*
G03X290158Y1618084I-150J132D01*
G01Y1618706D01*
G02X290361Y1618908I203J-1D01*
G37*
G36*
G01X325007D02*
X327827D01*
G02X328030Y1618706I1J-202D01*
G01Y1618084D01*
G03X328080Y1617952I200J0D01*
G02Y1615040I-1664J-1456D01*
G03X328030Y1614908I150J-132D01*
G01Y1612966D01*
G03X328080Y1612834I200J0D01*
G02Y1609922I-1664J-1456D01*
G03X328030Y1609790I150J-132D01*
G01Y1609168D01*
G02X327827Y1608966I-203J1D01*
G01X325007D01*
G02X324804Y1609168I-1J202D01*
G01Y1609790D01*
G03X324754Y1609922I-200J0D01*
G02Y1612834I1664J1456D01*
G03X324804Y1612966I-150J132D01*
G01Y1614908D01*
G03X324754Y1615040I-200J0D01*
G02Y1617952I1664J1456D01*
G03X324804Y1618084I-150J132D01*
G01Y1618706D01*
G02X325007Y1618908I203J-1D01*
G37*
G36*
G01X359653D02*
X362473D01*
G02X362676Y1618706I1J-202D01*
G01Y1618084D01*
G03X362726Y1617952I200J0D01*
G02Y1615040I-1664J-1456D01*
G03X362676Y1614908I150J-132D01*
G01Y1612966D01*
G03X362726Y1612834I200J0D01*
G02Y1609922I-1664J-1456D01*
G03X362676Y1609790I150J-132D01*
G01Y1609168D01*
G02X362473Y1608966I-203J1D01*
G01X359653D01*
G02X359450Y1609168I-1J202D01*
G01Y1609790D01*
G03X359400Y1609922I-200J0D01*
G02Y1612834I1664J1456D01*
G03X359450Y1612966I-150J132D01*
G01Y1614908D01*
G03X359400Y1615040I-200J0D01*
G02Y1617952I1664J1456D01*
G03X359450Y1618084I-150J132D01*
G01Y1618706D01*
G02X359653Y1618908I203J-1D01*
G37*
G36*
G01X515559D02*
X518379D01*
G02X518582Y1618706I1J-202D01*
G01Y1618084D01*
G03X518632Y1617952I200J0D01*
G02Y1615040I-1664J-1456D01*
G03X518582Y1614908I150J-132D01*
G01Y1612966D01*
G03X518632Y1612834I200J0D01*
G02Y1609922I-1664J-1456D01*
G03X518582Y1609790I150J-132D01*
G01Y1609168D01*
G02X518379Y1608966I-203J1D01*
G01X515559D01*
G02X515356Y1609168I-1J202D01*
G01Y1609790D01*
G03X515306Y1609922I-200J0D01*
G02Y1612834I1664J1456D01*
G03X515356Y1612966I-150J132D01*
G01Y1614908D01*
G03X515306Y1615040I-200J0D01*
G02Y1617952I1664J1456D01*
G03X515356Y1618084I-150J132D01*
G01Y1618706D01*
G02X515559Y1618908I203J-1D01*
G37*
G36*
G01X654141D02*
X656961D01*
G02X657164Y1618706I1J-202D01*
G01Y1618084D01*
G03X657214Y1617952I200J0D01*
G02Y1615040I-1664J-1456D01*
G03X657164Y1614908I150J-132D01*
G01Y1612966D01*
G03X657214Y1612834I200J0D01*
G02Y1609922I-1664J-1456D01*
G03X657164Y1609790I150J-132D01*
G01Y1609168D01*
G02X656961Y1608966I-203J1D01*
G01X654141D01*
G02X653938Y1609168I-1J202D01*
G01Y1609790D01*
G03X653888Y1609922I-200J0D01*
G02Y1612834I1664J1456D01*
G03X653938Y1612966I-150J132D01*
G01Y1614908D01*
G03X653888Y1615040I-200J0D01*
G02Y1617952I1664J1456D01*
G03X653938Y1618084I-150J132D01*
G01Y1618706D01*
G02X654141Y1618908I203J-1D01*
G37*
G36*
G01X688787D02*
X691607D01*
G02X691810Y1618706I1J-202D01*
G01Y1618084D01*
G03X691860Y1617952I200J0D01*
G02Y1615040I-1664J-1456D01*
G03X691810Y1614908I150J-132D01*
G01Y1612966D01*
G03X691860Y1612834I200J0D01*
G02Y1609922I-1664J-1456D01*
G03X691810Y1609790I150J-132D01*
G01Y1609168D01*
G02X691607Y1608966I-203J1D01*
G01X688787D01*
G02X688584Y1609168I-1J202D01*
G01Y1609790D01*
G03X688534Y1609922I-200J0D01*
G02Y1612834I1664J1456D01*
G03X688584Y1612966I-150J132D01*
G01Y1614908D01*
G03X688534Y1615040I-200J0D01*
G02Y1617952I1664J1456D01*
G03X688584Y1618084I-150J132D01*
G01Y1618706D01*
G02X688787Y1618908I203J-1D01*
G37*
G36*
G01X1139101D02*
X1141921D01*
G02X1142124Y1618706I1J-202D01*
G01Y1618084D01*
G03X1142174Y1617952I200J0D01*
G02Y1615040I-1664J-1456D01*
G03X1142124Y1614908I150J-132D01*
G01Y1612966D01*
G03X1142174Y1612834I200J0D01*
G02Y1609922I-1664J-1456D01*
G03X1142124Y1609790I150J-132D01*
G01Y1609168D01*
G02X1141921Y1608966I-203J1D01*
G01X1139101D01*
G02X1138898Y1609168I-1J202D01*
G01Y1609790D01*
G03X1138848Y1609922I-200J0D01*
G02Y1612834I1664J1456D01*
G03X1138898Y1612966I-150J132D01*
G01Y1614908D01*
G03X1138848Y1615040I-200J0D01*
G02Y1617952I1664J1456D01*
G03X1138898Y1618084I-150J132D01*
G01Y1618706D01*
G02X1139101Y1618908I203J-1D01*
G37*
G36*
G01X1173747D02*
X1176567D01*
G02X1176770Y1618706I1J-202D01*
G01Y1618084D01*
G03X1176820Y1617952I200J0D01*
G02Y1615040I-1664J-1456D01*
G03X1176770Y1614908I150J-132D01*
G01Y1612966D01*
G03X1176820Y1612834I200J0D01*
G02Y1609922I-1664J-1456D01*
G03X1176770Y1609790I150J-132D01*
G01Y1609168D01*
G02X1176567Y1608966I-203J1D01*
G01X1173747D01*
G02X1173544Y1609168I-1J202D01*
G01Y1609790D01*
G03X1173494Y1609922I-200J0D01*
G02Y1612834I1664J1456D01*
G03X1173544Y1612966I-150J132D01*
G01Y1614908D01*
G03X1173494Y1615040I-200J0D01*
G02Y1617952I1664J1456D01*
G03X1173544Y1618084I-150J132D01*
G01Y1618706D01*
G02X1173747Y1618908I203J-1D01*
G37*
G36*
G01X1329653D02*
X1332473D01*
G02X1332676Y1618706I1J-202D01*
G01Y1618084D01*
G03X1332726Y1617952I200J0D01*
G02Y1615040I-1664J-1456D01*
G03X1332676Y1614908I150J-132D01*
G01Y1612966D01*
G03X1332726Y1612834I200J0D01*
G02Y1609922I-1664J-1456D01*
G03X1332676Y1609790I150J-132D01*
G01Y1609168D01*
G02X1332473Y1608966I-203J1D01*
G01X1329653D01*
G02X1329450Y1609168I-1J202D01*
G01Y1609790D01*
G03X1329400Y1609922I-200J0D01*
G02Y1612834I1664J1456D01*
G03X1329450Y1612966I-150J132D01*
G01Y1614908D01*
G03X1329400Y1615040I-200J0D01*
G02Y1617952I1664J1456D01*
G03X1329450Y1618084I-150J132D01*
G01Y1618706D01*
G02X1329653Y1618908I203J-1D01*
G37*
G36*
G01X1364299D02*
X1367119D01*
G02X1367322Y1618706I1J-202D01*
G01Y1618084D01*
G03X1367372Y1617952I200J0D01*
G02Y1615040I-1664J-1456D01*
G03X1367322Y1614908I150J-132D01*
G01Y1612966D01*
G03X1367372Y1612834I200J0D01*
G02Y1609922I-1664J-1456D01*
G03X1367322Y1609790I150J-132D01*
G01Y1609168D01*
G02X1367119Y1608966I-203J1D01*
G01X1364299D01*
G02X1364096Y1609168I-1J202D01*
G01Y1609790D01*
G03X1364046Y1609922I-200J0D01*
G02Y1612834I1664J1456D01*
G03X1364096Y1612966I-150J132D01*
G01Y1614908D01*
G03X1364046Y1615040I-200J0D01*
G02Y1617952I1664J1456D01*
G03X1364096Y1618084I-150J132D01*
G01Y1618706D01*
G02X1364299Y1618908I203J-1D01*
G37*
G36*
G01X1676109D02*
X1678929D01*
G02X1679132Y1618706I1J-202D01*
G01Y1618084D01*
G03X1679182Y1617952I200J0D01*
G02Y1615040I-1664J-1456D01*
G03X1679132Y1614908I150J-132D01*
G01Y1612966D01*
G03X1679182Y1612834I200J0D01*
G02Y1609922I-1664J-1456D01*
G03X1679132Y1609790I150J-132D01*
G01Y1609168D01*
G02X1678929Y1608966I-203J1D01*
G01X1676109D01*
G02X1675906Y1609168I-1J202D01*
G01Y1609790D01*
G03X1675856Y1609922I-200J0D01*
G02Y1612834I1664J1456D01*
G03X1675906Y1612966I-150J132D01*
G01Y1614908D01*
G03X1675856Y1615040I-200J0D01*
G02Y1617952I1664J1456D01*
G03X1675906Y1618084I-150J132D01*
G01Y1618706D01*
G02X1676109Y1618908I203J-1D01*
G37*
G36*
G01X1710755D02*
X1713575D01*
G02X1713778Y1618706I1J-202D01*
G01Y1618084D01*
G03X1713828Y1617952I200J0D01*
G02Y1615040I-1664J-1456D01*
G03X1713778Y1614908I150J-132D01*
G01Y1612966D01*
G03X1713828Y1612834I200J0D01*
G02Y1609922I-1664J-1456D01*
G03X1713778Y1609790I150J-132D01*
G01Y1609168D01*
G02X1713575Y1608966I-203J1D01*
G01X1710755D01*
G02X1710552Y1609168I-1J202D01*
G01Y1609790D01*
G03X1710502Y1609922I-200J0D01*
G02Y1612834I1664J1456D01*
G03X1710552Y1612966I-150J132D01*
G01Y1614908D01*
G03X1710502Y1615040I-200J0D01*
G02Y1617952I1664J1456D01*
G03X1710552Y1618084I-150J132D01*
G01Y1618706D01*
G02X1710755Y1618908I203J-1D01*
G37*
G36*
G01X1522570Y1409998D02*
X1525970D01*
G02Y1406992I0J-1503D01*
G01X1522570D01*
G02Y1409998I0J1503D01*
G37*
G36*
G01X1559290Y1349690D02*
X1562690D01*
G02Y1346684I0J-1503D01*
G01X1559290D01*
G02Y1349690I0J1503D01*
G37*
G36*
G01X1522570Y1385800D02*
X1525970D01*
G02Y1382794I0J-1503D01*
G01X1522570D01*
G02Y1385800I0J1503D01*
G37*
G36*
G01Y1373888D02*
X1525970D01*
G02Y1370882I0J-1503D01*
G01X1522570D01*
G02Y1373888I0J1503D01*
G37*
G36*
G01Y1398086D02*
X1525970D01*
G02Y1395080I0J-1503D01*
G01X1522570D01*
G02Y1398086I0J1503D01*
G37*
G36*
G01X1510330Y1373888D02*
X1513730D01*
G02Y1370882I0J-1503D01*
G01X1510330D01*
G02Y1373888I0J1503D01*
G37*
G36*
G01X1547050Y1361602D02*
X1550450D01*
G02Y1358596I0J-1503D01*
G01X1547050D01*
G02Y1361602I0J1503D01*
G37*
G36*
G01X1534810D02*
X1538210D01*
G02Y1358596I0J-1503D01*
G01X1534810D01*
G02Y1361602I0J1503D01*
G37*
G36*
G01X1547050Y1349690D02*
X1550450D01*
G02Y1346684I0J-1503D01*
G01X1547050D01*
G02Y1349690I0J1503D01*
G37*
G36*
G01X1534810D02*
X1538210D01*
G02Y1346684I0J-1503D01*
G01X1534810D01*
G02Y1349690I0J1503D01*
G37*
G36*
G01X241623Y1373888D02*
X245023D01*
G02Y1370882I0J-1503D01*
G01X241623D01*
G02Y1373888I0J1503D01*
G37*
G36*
G01Y1361602D02*
X245023D01*
G02Y1358596I0J-1503D01*
G01X241623D01*
G02Y1361602I0J1503D01*
G37*
G36*
G01X1485850Y1409998D02*
X1489250D01*
G02Y1406992I0J-1503D01*
G01X1485850D01*
G02Y1409998I0J1503D01*
G37*
G36*
G01X1510330Y1349690D02*
X1513730D01*
G02Y1346684I0J-1503D01*
G01X1510330D01*
G02Y1349690I0J1503D01*
G37*
G36*
G01X364023Y1398086D02*
X367423D01*
G02Y1395080I0J-1503D01*
G01X364023D01*
G02Y1398086I0J1503D01*
G37*
G36*
G01X1485850Y1385800D02*
X1489250D01*
G02Y1382794I0J-1503D01*
G01X1485850D01*
G02Y1385800I0J1503D01*
G37*
G36*
G01X1473610D02*
X1477010D01*
G02Y1382794I0J-1503D01*
G01X1473610D01*
G02Y1385800I0J1503D01*
G37*
G36*
G01Y1361602D02*
X1477010D01*
G02Y1358596I0J-1503D01*
G01X1473610D01*
G02Y1361602I0J1503D01*
G37*
G36*
G01Y1349690D02*
X1477010D01*
G02Y1346684I0J-1503D01*
G01X1473610D01*
G02Y1349690I0J1503D01*
G37*
G36*
G01X1461370Y1385800D02*
X1464770D01*
G02Y1382794I0J-1503D01*
G01X1461370D01*
G02Y1385800I0J1503D01*
G37*
G36*
G01Y1373888D02*
X1464770D01*
G02Y1370882I0J-1503D01*
G01X1461370D01*
G02Y1373888I0J1503D01*
G37*
G36*
G01Y1361602D02*
X1464770D01*
G02Y1358596I0J-1503D01*
G01X1461370D01*
G02Y1361602I0J1503D01*
G37*
G36*
G01Y1349690D02*
X1464770D01*
G02Y1346684I0J-1503D01*
G01X1461370D01*
G02Y1349690I0J1503D01*
G37*
G36*
G01X1485850Y1373888D02*
X1489250D01*
G02Y1370882I0J-1503D01*
G01X1485850D01*
G02Y1373888I0J1503D01*
G37*
G36*
G01X1498090Y1361602D02*
X1501490D01*
G02Y1358596I0J-1503D01*
G01X1498090D01*
G02Y1361602I0J1503D01*
G37*
G36*
G01X1485850D02*
X1489250D01*
G02Y1358596I0J-1503D01*
G01X1485850D01*
G02Y1361602I0J1503D01*
G37*
G36*
G01X253863Y1409998D02*
X257263D01*
G02Y1406992I0J-1503D01*
G01X253863D01*
G02Y1409998I0J1503D01*
G37*
G36*
G01X266103Y1373888D02*
X269503D01*
G02Y1370882I0J-1503D01*
G01X266103D01*
G02Y1373888I0J1503D01*
G37*
G36*
G01X290583Y1361602D02*
X293983D01*
G02Y1358596I0J-1503D01*
G01X290583D01*
G02Y1361602I0J1503D01*
G37*
G36*
G01X327303Y1349690D02*
X330703D01*
G02Y1346684I0J-1503D01*
G01X327303D01*
G02Y1349690I0J1503D01*
G37*
G36*
G01X290583Y1385800D02*
X293983D01*
G02Y1382794I0J-1503D01*
G01X290583D01*
G02Y1385800I0J1503D01*
G37*
G36*
G01Y1409998D02*
X293983D01*
G02Y1406992I0J-1503D01*
G01X290583D01*
G02Y1409998I0J1503D01*
G37*
G36*
G01X253863Y1398086D02*
X257263D01*
G02Y1395080I0J-1503D01*
G01X253863D01*
G02Y1398086I0J1503D01*
G37*
G36*
G01X364023Y1361602D02*
X367423D01*
G02Y1358596I0J-1503D01*
G01X364023D01*
G02Y1361602I0J1503D01*
G37*
G36*
G01X339543Y1349690D02*
X342943D01*
G02Y1346684I0J-1503D01*
G01X339543D01*
G02Y1349690I0J1503D01*
G37*
G36*
G01X241623D02*
X245023D01*
G02Y1346684I0J-1503D01*
G01X241623D01*
G02Y1349690I0J1503D01*
G37*
G36*
G01X339543Y1361602D02*
X342943D01*
G02Y1358596I0J-1503D01*
G01X339543D01*
G02Y1361602I0J1503D01*
G37*
G36*
G01X302823Y1409998D02*
X306223D01*
G02Y1406992I0J-1503D01*
G01X302823D01*
G02Y1409998I0J1503D01*
G37*
G36*
G01X364023Y1385800D02*
X367423D01*
G02Y1382794I0J-1503D01*
G01X364023D01*
G02Y1385800I0J1503D01*
G37*
G36*
G01X290583Y1398086D02*
X293983D01*
G02Y1395080I0J-1503D01*
G01X290583D01*
G02Y1398086I0J1503D01*
G37*
G36*
G01X112832D02*
X116232D01*
G02Y1395080I0J-1503D01*
G01X112832D01*
G02Y1398086I0J1503D01*
G37*
G36*
G01X364023Y1373888D02*
X367423D01*
G02Y1370882I0J-1503D01*
G01X364023D01*
G02Y1373888I0J1503D01*
G37*
G36*
G01X302823Y1361602D02*
X306223D01*
G02Y1358596I0J-1503D01*
G01X302823D01*
G02Y1361602I0J1503D01*
G37*
G36*
G01X1534810Y1409998D02*
X1538210D01*
G02Y1406992I0J-1503D01*
G01X1534810D01*
G02Y1409998I0J1503D01*
G37*
G36*
G01X1510330Y1385800D02*
X1513730D01*
G02Y1382794I0J-1503D01*
G01X1510330D01*
G02Y1385800I0J1503D01*
G37*
G36*
G01X1534810Y1398086D02*
X1538210D01*
G02Y1395080I0J-1503D01*
G01X1534810D01*
G02Y1398086I0J1503D01*
G37*
G36*
G01X302823Y1349690D02*
X306223D01*
G02Y1346684I0J-1503D01*
G01X302823D01*
G02Y1349690I0J1503D01*
G37*
G36*
G01X88352Y1373888D02*
X91752D01*
G02Y1370882I0J-1503D01*
G01X88352D01*
G02Y1373888I0J1503D01*
G37*
G36*
G01X339543Y1385800D02*
X342943D01*
G02Y1382794I0J-1503D01*
G01X339543D01*
G02Y1385800I0J1503D01*
G37*
G36*
G01X327303Y1373888D02*
X330703D01*
G02Y1370882I0J-1503D01*
G01X327303D01*
G02Y1373888I0J1503D01*
G37*
G36*
G01Y1409998D02*
X330703D01*
G02Y1406992I0J-1503D01*
G01X327303D01*
G02Y1409998I0J1503D01*
G37*
G36*
G01X278343Y1398086D02*
X281743D01*
G02Y1395080I0J-1503D01*
G01X278343D01*
G02Y1398086I0J1503D01*
G37*
G36*
G01X351783Y1349690D02*
X355183D01*
G02Y1346684I0J-1503D01*
G01X351783D01*
G02Y1349690I0J1503D01*
G37*
G36*
G01X186272Y1385800D02*
X189672D01*
G02Y1382794I0J-1503D01*
G01X186272D01*
G02Y1385800I0J1503D01*
G37*
G36*
G01Y1373888D02*
X189672D01*
G02Y1370882I0J-1503D01*
G01X186272D01*
G02Y1373888I0J1503D01*
G37*
G36*
G01X315063Y1361602D02*
X318463D01*
G02Y1358596I0J-1503D01*
G01X315063D01*
G02Y1361602I0J1503D01*
G37*
G36*
G01X327303D02*
X330703D01*
G02Y1358596I0J-1503D01*
G01X327303D01*
G02Y1361602I0J1503D01*
G37*
G36*
G01X315063Y1349690D02*
X318463D01*
G02Y1346684I0J-1503D01*
G01X315063D01*
G02Y1349690I0J1503D01*
G37*
G36*
G01X174032Y1398086D02*
X177432D01*
G02Y1395080I0J-1503D01*
G01X174032D01*
G02Y1398086I0J1503D01*
G37*
G36*
G01X266103Y1349690D02*
X269503D01*
G02Y1346684I0J-1503D01*
G01X266103D01*
G02Y1349690I0J1503D01*
G37*
G36*
G01X1054713Y1361602D02*
X1058113D01*
G02Y1358596I0J-1503D01*
G01X1054713D01*
G02Y1361602I0J1503D01*
G37*
G36*
G01Y1349690D02*
X1058113D01*
G02Y1346684I0J-1503D01*
G01X1054713D01*
G02Y1349690I0J1503D01*
G37*
G36*
G01Y1385800D02*
X1058113D01*
G02Y1382794I0J-1503D01*
G01X1054713D01*
G02Y1385800I0J1503D01*
G37*
G36*
G01Y1373888D02*
X1058113D01*
G02Y1370882I0J-1503D01*
G01X1054713D01*
G02Y1373888I0J1503D01*
G37*
G36*
G01X1177113Y1409998D02*
X1180513D01*
G02Y1406992I0J-1503D01*
G01X1177113D01*
G02Y1409998I0J1503D01*
G37*
G36*
G01Y1398086D02*
X1180513D01*
G02Y1395080I0J-1503D01*
G01X1177113D01*
G02Y1398086I0J1503D01*
G37*
G36*
G01Y1373888D02*
X1180513D01*
G02Y1370882I0J-1503D01*
G01X1177113D01*
G02Y1373888I0J1503D01*
G37*
G36*
G01Y1385800D02*
X1180513D01*
G02Y1382794I0J-1503D01*
G01X1177113D01*
G02Y1385800I0J1503D01*
G37*
G36*
G01Y1361602D02*
X1180513D01*
G02Y1358596I0J-1503D01*
G01X1177113D01*
G02Y1361602I0J1503D01*
G37*
G36*
G01Y1349690D02*
X1180513D01*
G02Y1346684I0J-1503D01*
G01X1177113D01*
G02Y1349690I0J1503D01*
G37*
G36*
G01X1164873Y1409998D02*
X1168273D01*
G02Y1406992I0J-1503D01*
G01X1164873D01*
G02Y1409998I0J1503D01*
G37*
G36*
G01Y1398086D02*
X1168273D01*
G02Y1395080I0J-1503D01*
G01X1164873D01*
G02Y1398086I0J1503D01*
G37*
G36*
G01Y1385800D02*
X1168273D01*
G02Y1382794I0J-1503D01*
G01X1164873D01*
G02Y1385800I0J1503D01*
G37*
G36*
G01Y1373888D02*
X1168273D01*
G02Y1370882I0J-1503D01*
G01X1164873D01*
G02Y1373888I0J1503D01*
G37*
G36*
G01Y1361602D02*
X1168273D01*
G02Y1358596I0J-1503D01*
G01X1164873D01*
G02Y1361602I0J1503D01*
G37*
G36*
G01Y1349690D02*
X1168273D01*
G02Y1346684I0J-1503D01*
G01X1164873D01*
G02Y1349690I0J1503D01*
G37*
G36*
G01X1152633Y1409998D02*
X1156033D01*
G02Y1406992I0J-1503D01*
G01X1152633D01*
G02Y1409998I0J1503D01*
G37*
G36*
G01Y1398086D02*
X1156033D01*
G02Y1395080I0J-1503D01*
G01X1152633D01*
G02Y1398086I0J1503D01*
G37*
G36*
G01Y1373888D02*
X1156033D01*
G02Y1370882I0J-1503D01*
G01X1152633D01*
G02Y1373888I0J1503D01*
G37*
G36*
G01Y1385800D02*
X1156033D01*
G02Y1382794I0J-1503D01*
G01X1152633D01*
G02Y1385800I0J1503D01*
G37*
G36*
G01Y1361602D02*
X1156033D01*
G02Y1358596I0J-1503D01*
G01X1152633D01*
G02Y1361602I0J1503D01*
G37*
G36*
G01Y1349690D02*
X1156033D01*
G02Y1346684I0J-1503D01*
G01X1152633D01*
G02Y1349690I0J1503D01*
G37*
G36*
G01X1128153Y1409998D02*
X1131553D01*
G02Y1406992I0J-1503D01*
G01X1128153D01*
G02Y1409998I0J1503D01*
G37*
G36*
G01X1140393D02*
X1143793D01*
G02Y1406992I0J-1503D01*
G01X1140393D01*
G02Y1409998I0J1503D01*
G37*
G36*
G01X1128153Y1398086D02*
X1131553D01*
G02Y1395080I0J-1503D01*
G01X1128153D01*
G02Y1398086I0J1503D01*
G37*
G36*
G01X1140393D02*
X1143793D01*
G02Y1395080I0J-1503D01*
G01X1140393D01*
G02Y1398086I0J1503D01*
G37*
G36*
G01X1128153Y1373888D02*
X1131553D01*
G02Y1370882I0J-1503D01*
G01X1128153D01*
G02Y1373888I0J1503D01*
G37*
G36*
G01Y1385800D02*
X1131553D01*
G02Y1382794I0J-1503D01*
G01X1128153D01*
G02Y1385800I0J1503D01*
G37*
G36*
G01X1140393D02*
X1143793D01*
G02Y1382794I0J-1503D01*
G01X1140393D01*
G02Y1385800I0J1503D01*
G37*
G36*
G01Y1373888D02*
X1143793D01*
G02Y1370882I0J-1503D01*
G01X1140393D01*
G02Y1373888I0J1503D01*
G37*
G36*
G01X1128153Y1361602D02*
X1131553D01*
G02Y1358596I0J-1503D01*
G01X1128153D01*
G02Y1361602I0J1503D01*
G37*
G36*
G01X1140393D02*
X1143793D01*
G02Y1358596I0J-1503D01*
G01X1140393D01*
G02Y1361602I0J1503D01*
G37*
G36*
G01X1128153Y1349690D02*
X1131553D01*
G02Y1346684I0J-1503D01*
G01X1128153D01*
G02Y1349690I0J1503D01*
G37*
G36*
G01X1140393D02*
X1143793D01*
G02Y1346684I0J-1503D01*
G01X1140393D01*
G02Y1349690I0J1503D01*
G37*
G36*
G01X1115913Y1409998D02*
X1119313D01*
G02Y1406992I0J-1503D01*
G01X1115913D01*
G02Y1409998I0J1503D01*
G37*
G36*
G01Y1398086D02*
X1119313D01*
G02Y1395080I0J-1503D01*
G01X1115913D01*
G02Y1398086I0J1503D01*
G37*
G36*
G01Y1373888D02*
X1119313D01*
G02Y1370882I0J-1503D01*
G01X1115913D01*
G02Y1373888I0J1503D01*
G37*
G36*
G01Y1385800D02*
X1119313D01*
G02Y1382794I0J-1503D01*
G01X1115913D01*
G02Y1385800I0J1503D01*
G37*
G36*
G01Y1361602D02*
X1119313D01*
G02Y1358596I0J-1503D01*
G01X1115913D01*
G02Y1361602I0J1503D01*
G37*
G36*
G01Y1349690D02*
X1119313D01*
G02Y1346684I0J-1503D01*
G01X1115913D01*
G02Y1349690I0J1503D01*
G37*
G36*
G01X1103673Y1409998D02*
X1107073D01*
G02Y1406992I0J-1503D01*
G01X1103673D01*
G02Y1409998I0J1503D01*
G37*
G36*
G01Y1398086D02*
X1107073D01*
G02Y1395080I0J-1503D01*
G01X1103673D01*
G02Y1398086I0J1503D01*
G37*
G36*
G01Y1385800D02*
X1107073D01*
G02Y1382794I0J-1503D01*
G01X1103673D01*
G02Y1385800I0J1503D01*
G37*
G36*
G01Y1373888D02*
X1107073D01*
G02Y1370882I0J-1503D01*
G01X1103673D01*
G02Y1373888I0J1503D01*
G37*
G36*
G01Y1361602D02*
X1107073D01*
G02Y1358596I0J-1503D01*
G01X1103673D01*
G02Y1361602I0J1503D01*
G37*
G36*
G01Y1349690D02*
X1107073D01*
G02Y1346684I0J-1503D01*
G01X1103673D01*
G02Y1349690I0J1503D01*
G37*
G36*
G01X1079193Y1409998D02*
X1082593D01*
G02Y1406992I0J-1503D01*
G01X1079193D01*
G02Y1409998I0J1503D01*
G37*
G36*
G01X1091433D02*
X1094833D01*
G02Y1406992I0J-1503D01*
G01X1091433D01*
G02Y1409998I0J1503D01*
G37*
G36*
G01X1079193Y1398086D02*
X1082593D01*
G02Y1395080I0J-1503D01*
G01X1079193D01*
G02Y1398086I0J1503D01*
G37*
G36*
G01X1091433D02*
X1094833D01*
G02Y1395080I0J-1503D01*
G01X1091433D01*
G02Y1398086I0J1503D01*
G37*
G36*
G01X1079193Y1385800D02*
X1082593D01*
G02Y1382794I0J-1503D01*
G01X1079193D01*
G02Y1385800I0J1503D01*
G37*
G36*
G01Y1373888D02*
X1082593D01*
G02Y1370882I0J-1503D01*
G01X1079193D01*
G02Y1373888I0J1503D01*
G37*
G36*
G01X1091433Y1385800D02*
X1094833D01*
G02Y1382794I0J-1503D01*
G01X1091433D01*
G02Y1385800I0J1503D01*
G37*
G36*
G01Y1373888D02*
X1094833D01*
G02Y1370882I0J-1503D01*
G01X1091433D01*
G02Y1373888I0J1503D01*
G37*
G36*
G01X1079193Y1361602D02*
X1082593D01*
G02Y1358596I0J-1503D01*
G01X1079193D01*
G02Y1361602I0J1503D01*
G37*
G36*
G01X1091433D02*
X1094833D01*
G02Y1358596I0J-1503D01*
G01X1091433D01*
G02Y1361602I0J1503D01*
G37*
G36*
G01X1079193Y1349690D02*
X1082593D01*
G02Y1346684I0J-1503D01*
G01X1079193D01*
G02Y1349690I0J1503D01*
G37*
G36*
G01X1091433D02*
X1094833D01*
G02Y1346684I0J-1503D01*
G01X1091433D01*
G02Y1349690I0J1503D01*
G37*
G36*
G01X1066953Y1409998D02*
X1070353D01*
G02Y1406992I0J-1503D01*
G01X1066953D01*
G02Y1409998I0J1503D01*
G37*
G36*
G01Y1398086D02*
X1070353D01*
G02Y1395080I0J-1503D01*
G01X1066953D01*
G02Y1398086I0J1503D01*
G37*
G36*
G01X290583Y1349690D02*
X293983D01*
G02Y1346684I0J-1503D01*
G01X290583D01*
G02Y1349690I0J1503D01*
G37*
G36*
G01X241623Y1385800D02*
X245023D01*
G02Y1382794I0J-1503D01*
G01X241623D01*
G02Y1385800I0J1503D01*
G37*
G36*
G01X253863Y1361602D02*
X257263D01*
G02Y1358596I0J-1503D01*
G01X253863D01*
G02Y1361602I0J1503D01*
G37*
G36*
G01Y1349690D02*
X257263D01*
G02Y1346684I0J-1503D01*
G01X253863D01*
G02Y1349690I0J1503D01*
G37*
G36*
G01X1547050Y1409998D02*
X1550450D01*
G02Y1406992I0J-1503D01*
G01X1547050D01*
G02Y1409998I0J1503D01*
G37*
G36*
G01X1559290Y1385800D02*
X1562690D01*
G02Y1382794I0J-1503D01*
G01X1559290D01*
G02Y1385800I0J1503D01*
G37*
G36*
G01X1230326Y1349690D02*
X1233726D01*
G02Y1346684I0J-1503D01*
G01X1230326D01*
G02Y1349690I0J1503D01*
G37*
G36*
G01Y1361602D02*
X1233726D01*
G02Y1358596I0J-1503D01*
G01X1230326D01*
G02Y1361602I0J1503D01*
G37*
G36*
G01Y1373888D02*
X1233726D01*
G02Y1370882I0J-1503D01*
G01X1230326D01*
G02Y1373888I0J1503D01*
G37*
G36*
G01Y1385800D02*
X1233726D01*
G02Y1382794I0J-1503D01*
G01X1230326D01*
G02Y1385800I0J1503D01*
G37*
G36*
G01X1242566Y1349690D02*
X1245966D01*
G02Y1346684I0J-1503D01*
G01X1242566D01*
G02Y1349690I0J1503D01*
G37*
G36*
G01Y1361602D02*
X1245966D01*
G02Y1358596I0J-1503D01*
G01X1242566D01*
G02Y1361602I0J1503D01*
G37*
G36*
G01Y1385800D02*
X1245966D01*
G02Y1382794I0J-1503D01*
G01X1242566D01*
G02Y1385800I0J1503D01*
G37*
G36*
G01Y1373888D02*
X1245966D01*
G02Y1370882I0J-1503D01*
G01X1242566D01*
G02Y1373888I0J1503D01*
G37*
G36*
G01Y1398086D02*
X1245966D01*
G02Y1395080I0J-1503D01*
G01X1242566D01*
G02Y1398086I0J1503D01*
G37*
G36*
G01Y1409998D02*
X1245966D01*
G02Y1406992I0J-1503D01*
G01X1242566D01*
G02Y1409998I0J1503D01*
G37*
G36*
G01X1267046Y1349690D02*
X1270446D01*
G02Y1346684I0J-1503D01*
G01X1267046D01*
G02Y1349690I0J1503D01*
G37*
G36*
G01X1254806D02*
X1258206D01*
G02Y1346684I0J-1503D01*
G01X1254806D01*
G02Y1349690I0J1503D01*
G37*
G36*
G01X1267046Y1361602D02*
X1270446D01*
G02Y1358596I0J-1503D01*
G01X1267046D01*
G02Y1361602I0J1503D01*
G37*
G36*
G01X1254806D02*
X1258206D01*
G02Y1358596I0J-1503D01*
G01X1254806D01*
G02Y1361602I0J1503D01*
G37*
G36*
G01X1267046Y1385800D02*
X1270446D01*
G02Y1382794I0J-1503D01*
G01X1267046D01*
G02Y1385800I0J1503D01*
G37*
G36*
G01Y1373888D02*
X1270446D01*
G02Y1370882I0J-1503D01*
G01X1267046D01*
G02Y1373888I0J1503D01*
G37*
G36*
G01X1254806D02*
X1258206D01*
G02Y1370882I0J-1503D01*
G01X1254806D01*
G02Y1373888I0J1503D01*
G37*
G36*
G01Y1385800D02*
X1258206D01*
G02Y1382794I0J-1503D01*
G01X1254806D01*
G02Y1385800I0J1503D01*
G37*
G36*
G01X1267046Y1398086D02*
X1270446D01*
G02Y1395080I0J-1503D01*
G01X1267046D01*
G02Y1398086I0J1503D01*
G37*
G36*
G01X1254806D02*
X1258206D01*
G02Y1395080I0J-1503D01*
G01X1254806D01*
G02Y1398086I0J1503D01*
G37*
G36*
G01X1267046Y1409998D02*
X1270446D01*
G02Y1406992I0J-1503D01*
G01X1267046D01*
G02Y1409998I0J1503D01*
G37*
G36*
G01X1254806D02*
X1258206D01*
G02Y1406992I0J-1503D01*
G01X1254806D01*
G02Y1409998I0J1503D01*
G37*
G36*
G01X1279286Y1349690D02*
X1282686D01*
G02Y1346684I0J-1503D01*
G01X1279286D01*
G02Y1349690I0J1503D01*
G37*
G36*
G01Y1361602D02*
X1282686D01*
G02Y1358596I0J-1503D01*
G01X1279286D01*
G02Y1361602I0J1503D01*
G37*
G36*
G01X1510330D02*
X1513730D01*
G02Y1358596I0J-1503D01*
G01X1510330D01*
G02Y1361602I0J1503D01*
G37*
G36*
G01X1279286Y1373888D02*
X1282686D01*
G02Y1370882I0J-1503D01*
G01X1279286D01*
G02Y1373888I0J1503D01*
G37*
G36*
G01Y1385800D02*
X1282686D01*
G02Y1382794I0J-1503D01*
G01X1279286D01*
G02Y1385800I0J1503D01*
G37*
G36*
G01X1648118Y1409998D02*
X1651518D01*
G02Y1406992I0J-1503D01*
G01X1648118D01*
G02Y1409998I0J1503D01*
G37*
G36*
G01X1279286Y1398086D02*
X1282686D01*
G02Y1395080I0J-1503D01*
G01X1279286D01*
G02Y1398086I0J1503D01*
G37*
G36*
G01Y1409998D02*
X1282686D01*
G02Y1406992I0J-1503D01*
G01X1279286D01*
G02Y1409998I0J1503D01*
G37*
G36*
G01X1291526Y1349690D02*
X1294926D01*
G02Y1346684I0J-1503D01*
G01X1291526D01*
G02Y1349690I0J1503D01*
G37*
G36*
G01X1559290Y1398086D02*
X1562690D01*
G02Y1395080I0J-1503D01*
G01X1559290D01*
G02Y1398086I0J1503D01*
G37*
G36*
G01X161792Y1409998D02*
X165192D01*
G02Y1406992I0J-1503D01*
G01X161792D01*
G02Y1409998I0J1503D01*
G37*
G36*
G01X186272Y1349690D02*
X189672D01*
G02Y1346684I0J-1503D01*
G01X186272D01*
G02Y1349690I0J1503D01*
G37*
G36*
G01X315063Y1409998D02*
X318463D01*
G02Y1406992I0J-1503D01*
G01X315063D01*
G02Y1409998I0J1503D01*
G37*
G36*
G01X1534810Y1373888D02*
X1538210D01*
G02Y1370882I0J-1503D01*
G01X1534810D01*
G02Y1373888I0J1503D01*
G37*
G36*
G01X1559290Y1409998D02*
X1562690D01*
G02Y1406992I0J-1503D01*
G01X1559290D01*
G02Y1409998I0J1503D01*
G37*
G36*
G01X351783Y1361602D02*
X355183D01*
G02Y1358596I0J-1503D01*
G01X351783D01*
G02Y1361602I0J1503D01*
G37*
G36*
G01X198512Y1385800D02*
X201912D01*
G02Y1382794I0J-1503D01*
G01X198512D01*
G02Y1385800I0J1503D01*
G37*
G36*
G01X1291526Y1361602D02*
X1294926D01*
G02Y1358596I0J-1503D01*
G01X1291526D01*
G02Y1361602I0J1503D01*
G37*
G36*
G01X1635878Y1349690D02*
X1639278D01*
G02Y1346684I0J-1503D01*
G01X1635878D01*
G02Y1349690I0J1503D01*
G37*
G36*
G01Y1361602D02*
X1639278D01*
G02Y1358596I0J-1503D01*
G01X1635878D01*
G02Y1361602I0J1503D01*
G37*
G36*
G01X1291526Y1385800D02*
X1294926D01*
G02Y1382794I0J-1503D01*
G01X1291526D01*
G02Y1385800I0J1503D01*
G37*
G36*
G01Y1373888D02*
X1294926D01*
G02Y1370882I0J-1503D01*
G01X1291526D01*
G02Y1373888I0J1503D01*
G37*
G36*
G01X1635878Y1385800D02*
X1639278D01*
G02Y1382794I0J-1503D01*
G01X1635878D01*
G02Y1385800I0J1503D01*
G37*
G36*
G01Y1373888D02*
X1639278D01*
G02Y1370882I0J-1503D01*
G01X1635878D01*
G02Y1373888I0J1503D01*
G37*
G36*
G01Y1398086D02*
X1639278D01*
G02Y1395080I0J-1503D01*
G01X1635878D01*
G02Y1398086I0J1503D01*
G37*
G36*
G01X1623638Y1349690D02*
X1627038D01*
G02Y1346684I0J-1503D01*
G01X1623638D01*
G02Y1349690I0J1503D01*
G37*
G36*
G01X1611398D02*
X1614798D01*
G02Y1346684I0J-1503D01*
G01X1611398D01*
G02Y1349690I0J1503D01*
G37*
G36*
G01X1623638Y1361602D02*
X1627038D01*
G02Y1358596I0J-1503D01*
G01X1623638D01*
G02Y1361602I0J1503D01*
G37*
G36*
G01X1291526Y1398086D02*
X1294926D01*
G02Y1395080I0J-1503D01*
G01X1291526D01*
G02Y1398086I0J1503D01*
G37*
G36*
G01Y1409998D02*
X1294926D01*
G02Y1406992I0J-1503D01*
G01X1291526D01*
G02Y1409998I0J1503D01*
G37*
G36*
G01X1316006Y1349690D02*
X1319406D01*
G02Y1346684I0J-1503D01*
G01X1316006D01*
G02Y1349690I0J1503D01*
G37*
G36*
G01X1303766D02*
X1307166D01*
G02Y1346684I0J-1503D01*
G01X1303766D01*
G02Y1349690I0J1503D01*
G37*
G36*
G01X1316006Y1361602D02*
X1319406D01*
G02Y1358596I0J-1503D01*
G01X1316006D01*
G02Y1361602I0J1503D01*
G37*
G36*
G01X1303766D02*
X1307166D01*
G02Y1358596I0J-1503D01*
G01X1303766D01*
G02Y1361602I0J1503D01*
G37*
G36*
G01X1316006Y1385800D02*
X1319406D01*
G02Y1382794I0J-1503D01*
G01X1316006D01*
G02Y1385800I0J1503D01*
G37*
G36*
G01X1611398Y1373888D02*
X1614798D01*
G02Y1370882I0J-1503D01*
G01X1611398D01*
G02Y1373888I0J1503D01*
G37*
G36*
G01Y1385800D02*
X1614798D01*
G02Y1382794I0J-1503D01*
G01X1611398D01*
G02Y1385800I0J1503D01*
G37*
G36*
G01X1623638Y1398086D02*
X1627038D01*
G02Y1395080I0J-1503D01*
G01X1623638D01*
G02Y1398086I0J1503D01*
G37*
G36*
G01X1316006Y1373888D02*
X1319406D01*
G02Y1370882I0J-1503D01*
G01X1316006D01*
G02Y1373888I0J1503D01*
G37*
G36*
G01X1303766D02*
X1307166D01*
G02Y1370882I0J-1503D01*
G01X1303766D01*
G02Y1373888I0J1503D01*
G37*
G36*
G01Y1385800D02*
X1307166D01*
G02Y1382794I0J-1503D01*
G01X1303766D01*
G02Y1385800I0J1503D01*
G37*
G36*
G01X1316006Y1398086D02*
X1319406D01*
G02Y1395080I0J-1503D01*
G01X1316006D01*
G02Y1398086I0J1503D01*
G37*
G36*
G01X1303766D02*
X1307166D01*
G02Y1395080I0J-1503D01*
G01X1303766D01*
G02Y1398086I0J1503D01*
G37*
G36*
G01X1316006Y1409998D02*
X1319406D01*
G02Y1406992I0J-1503D01*
G01X1316006D01*
G02Y1409998I0J1503D01*
G37*
G36*
G01X1303766D02*
X1307166D01*
G02Y1406992I0J-1503D01*
G01X1303766D01*
G02Y1409998I0J1503D01*
G37*
G36*
G01X1623638D02*
X1627038D01*
G02Y1406992I0J-1503D01*
G01X1623638D01*
G02Y1409998I0J1503D01*
G37*
G36*
G01X1328246Y1349690D02*
X1331646D01*
G02Y1346684I0J-1503D01*
G01X1328246D01*
G02Y1349690I0J1503D01*
G37*
G36*
G01Y1361602D02*
X1331646D01*
G02Y1358596I0J-1503D01*
G01X1328246D01*
G02Y1361602I0J1503D01*
G37*
G36*
G01X1648118Y1398086D02*
X1651518D01*
G02Y1395080I0J-1503D01*
G01X1648118D01*
G02Y1398086I0J1503D01*
G37*
G36*
G01Y1373888D02*
X1651518D01*
G02Y1370882I0J-1503D01*
G01X1648118D01*
G02Y1373888I0J1503D01*
G37*
G36*
G01Y1385800D02*
X1651518D01*
G02Y1382794I0J-1503D01*
G01X1648118D01*
G02Y1385800I0J1503D01*
G37*
G36*
G01X1328246Y1373888D02*
X1331646D01*
G02Y1370882I0J-1503D01*
G01X1328246D01*
G02Y1373888I0J1503D01*
G37*
G36*
G01X1648118Y1361602D02*
X1651518D01*
G02Y1358596I0J-1503D01*
G01X1648118D01*
G02Y1361602I0J1503D01*
G37*
G36*
G01Y1349690D02*
X1651518D01*
G02Y1346684I0J-1503D01*
G01X1648118D01*
G02Y1349690I0J1503D01*
G37*
G36*
G01X1635878Y1409998D02*
X1639278D01*
G02Y1406992I0J-1503D01*
G01X1635878D01*
G02Y1409998I0J1503D01*
G37*
G36*
G01X1660358D02*
X1663758D01*
G02Y1406992I0J-1503D01*
G01X1660358D01*
G02Y1409998I0J1503D01*
G37*
G36*
G01X1672598D02*
X1675998D01*
G02Y1406992I0J-1503D01*
G01X1672598D01*
G02Y1409998I0J1503D01*
G37*
G36*
G01X1660358Y1398086D02*
X1663758D01*
G02Y1395080I0J-1503D01*
G01X1660358D01*
G02Y1398086I0J1503D01*
G37*
G36*
G01X1672598D02*
X1675998D01*
G02Y1395080I0J-1503D01*
G01X1672598D01*
G02Y1398086I0J1503D01*
G37*
G36*
G01X1660358Y1373888D02*
X1663758D01*
G02Y1370882I0J-1503D01*
G01X1660358D01*
G02Y1373888I0J1503D01*
G37*
G36*
G01Y1385800D02*
X1663758D01*
G02Y1382794I0J-1503D01*
G01X1660358D01*
G02Y1385800I0J1503D01*
G37*
G36*
G01X1672598Y1373888D02*
X1675998D01*
G02Y1370882I0J-1503D01*
G01X1672598D01*
G02Y1373888I0J1503D01*
G37*
G36*
G01X1328246Y1385800D02*
X1331646D01*
G02Y1382794I0J-1503D01*
G01X1328246D01*
G02Y1385800I0J1503D01*
G37*
G36*
G01X1672598D02*
X1675998D01*
G02Y1382794I0J-1503D01*
G01X1672598D01*
G02Y1385800I0J1503D01*
G37*
G36*
G01X174032Y1409998D02*
X177432D01*
G02Y1406992I0J-1503D01*
G01X174032D01*
G02Y1409998I0J1503D01*
G37*
G36*
G01X266103Y1385800D02*
X269503D01*
G02Y1382794I0J-1503D01*
G01X266103D01*
G02Y1385800I0J1503D01*
G37*
G36*
G01X315063D02*
X318463D01*
G02Y1382794I0J-1503D01*
G01X315063D01*
G02Y1385800I0J1503D01*
G37*
G36*
G01X278343Y1409998D02*
X281743D01*
G02Y1406992I0J-1503D01*
G01X278343D01*
G02Y1409998I0J1503D01*
G37*
G36*
G01X1328246Y1398086D02*
X1331646D01*
G02Y1395080I0J-1503D01*
G01X1328246D01*
G02Y1398086I0J1503D01*
G37*
G36*
G01X364023Y1409998D02*
X367423D01*
G02Y1406992I0J-1503D01*
G01X364023D01*
G02Y1409998I0J1503D01*
G37*
G36*
G01X266103D02*
X269503D01*
G02Y1406992I0J-1503D01*
G01X266103D01*
G02Y1409998I0J1503D01*
G37*
G36*
G01X1733798Y1385800D02*
X1737198D01*
G02Y1382794I0J-1503D01*
G01X1733798D01*
G02Y1385800I0J1503D01*
G37*
G36*
G01Y1373888D02*
X1737198D01*
G02Y1370882I0J-1503D01*
G01X1733798D01*
G02Y1373888I0J1503D01*
G37*
G36*
G01Y1398086D02*
X1737198D01*
G02Y1395080I0J-1503D01*
G01X1733798D01*
G02Y1398086I0J1503D01*
G37*
G36*
G01X1721558Y1373888D02*
X1724958D01*
G02Y1370882I0J-1503D01*
G01X1721558D01*
G02Y1373888I0J1503D01*
G37*
G36*
G01X290583D02*
X293983D01*
G02Y1370882I0J-1503D01*
G01X290583D01*
G02Y1373888I0J1503D01*
G37*
G36*
G01X1328246Y1409998D02*
X1331646D01*
G02Y1406992I0J-1503D01*
G01X1328246D01*
G02Y1409998I0J1503D01*
G37*
G36*
G01X1340486Y1349690D02*
X1343886D01*
G02Y1346684I0J-1503D01*
G01X1340486D01*
G02Y1349690I0J1503D01*
G37*
G36*
G01X1583770Y1373888D02*
X1587170D01*
G02Y1370882I0J-1503D01*
G01X1583770D01*
G02Y1373888I0J1503D01*
G37*
G36*
G01X1485850Y1349690D02*
X1489250D01*
G02Y1346684I0J-1503D01*
G01X1485850D01*
G02Y1349690I0J1503D01*
G37*
G36*
G01X1340486Y1361602D02*
X1343886D01*
G02Y1358596I0J-1503D01*
G01X1340486D01*
G02Y1361602I0J1503D01*
G37*
G36*
G01X1733798Y1409998D02*
X1737198D01*
G02Y1406992I0J-1503D01*
G01X1733798D01*
G02Y1409998I0J1503D01*
G37*
G36*
G01X278343Y1373888D02*
X281743D01*
G02Y1370882I0J-1503D01*
G01X278343D01*
G02Y1373888I0J1503D01*
G37*
G36*
G01X266103Y1398086D02*
X269503D01*
G02Y1395080I0J-1503D01*
G01X266103D01*
G02Y1398086I0J1503D01*
G37*
G36*
G01X1733798Y1349690D02*
X1737198D01*
G02Y1346684I0J-1503D01*
G01X1733798D01*
G02Y1349690I0J1503D01*
G37*
G36*
G01X137312Y1385800D02*
X140712D01*
G02Y1382794I0J-1503D01*
G01X137312D01*
G02Y1385800I0J1503D01*
G37*
G36*
G01X1721558Y1398086D02*
X1724958D01*
G02Y1395080I0J-1503D01*
G01X1721558D01*
G02Y1398086I0J1503D01*
G37*
G36*
G01X1340486Y1385800D02*
X1343886D01*
G02Y1382794I0J-1503D01*
G01X1340486D01*
G02Y1385800I0J1503D01*
G37*
G36*
G01Y1373888D02*
X1343886D01*
G02Y1370882I0J-1503D01*
G01X1340486D01*
G02Y1373888I0J1503D01*
G37*
G36*
G01X1721558Y1385800D02*
X1724958D01*
G02Y1382794I0J-1503D01*
G01X1721558D01*
G02Y1385800I0J1503D01*
G37*
G36*
G01X339543Y1398086D02*
X342943D01*
G02Y1395080I0J-1503D01*
G01X339543D01*
G02Y1398086I0J1503D01*
G37*
G36*
G01X327303Y1385800D02*
X330703D01*
G02Y1382794I0J-1503D01*
G01X327303D01*
G02Y1385800I0J1503D01*
G37*
G36*
G01X315063Y1373888D02*
X318463D01*
G02Y1370882I0J-1503D01*
G01X315063D01*
G02Y1373888I0J1503D01*
G37*
G36*
G01X339543D02*
X342943D01*
G02Y1370882I0J-1503D01*
G01X339543D01*
G02Y1373888I0J1503D01*
G37*
G36*
G01X351783Y1385800D02*
X355183D01*
G02Y1382794I0J-1503D01*
G01X351783D01*
G02Y1385800I0J1503D01*
G37*
G36*
G01Y1373888D02*
X355183D01*
G02Y1370882I0J-1503D01*
G01X351783D01*
G02Y1373888I0J1503D01*
G37*
G36*
G01Y1398086D02*
X355183D01*
G02Y1395080I0J-1503D01*
G01X351783D01*
G02Y1398086I0J1503D01*
G37*
G36*
G01Y1409998D02*
X355183D01*
G02Y1406992I0J-1503D01*
G01X351783D01*
G02Y1409998I0J1503D01*
G37*
G36*
G01X315063Y1398086D02*
X318463D01*
G02Y1395080I0J-1503D01*
G01X315063D01*
G02Y1398086I0J1503D01*
G37*
G36*
G01X278343Y1361602D02*
X281743D01*
G02Y1358596I0J-1503D01*
G01X278343D01*
G02Y1361602I0J1503D01*
G37*
G36*
G01X1498090Y1349690D02*
X1501490D01*
G02Y1346684I0J-1503D01*
G01X1498090D01*
G02Y1349690I0J1503D01*
G37*
G36*
G01X266103Y1361602D02*
X269503D01*
G02Y1358596I0J-1503D01*
G01X266103D01*
G02Y1361602I0J1503D01*
G37*
G36*
G01X35825Y1466648D02*
X39225D01*
G02Y1463044I0J-1802D01*
G01X35825D01*
G02Y1466648I0J1802D01*
G37*
G36*
G01X942699Y344560D02*
X939299D01*
G02Y348166I0J1803D01*
G01X942699D01*
G02Y344560I0J-1803D01*
G37*
G36*
G01X942730Y322242D02*
X939330D01*
G02Y325846I0J1802D01*
G01X942730D01*
G02Y322242I0J-1802D01*
G37*
G36*
G01X927963Y342238D02*
X924563D01*
G02Y345844I0J1803D01*
G01X927963D01*
G02Y342238I0J-1803D01*
G37*
G36*
G01X919353Y342348D02*
X915953D01*
G02Y345952I0J1802D01*
G01X919353D01*
G02Y342348I0J-1802D01*
G37*
G36*
G01X302823Y1398086D02*
X306223D01*
G02Y1395080I0J-1503D01*
G01X302823D01*
G02Y1398086I0J1503D01*
G37*
G36*
G01X389015Y794228D02*
X392415D01*
G02Y791222I0J-1503D01*
G01X389015D01*
G02Y794228I0J1503D01*
G37*
G36*
G01X302823Y1373888D02*
X306223D01*
G02Y1370882I0J-1503D01*
G01X302823D01*
G02Y1373888I0J1503D01*
G37*
G36*
G01X1534810Y1385800D02*
X1538210D01*
G02Y1382794I0J-1503D01*
G01X1534810D01*
G02Y1385800I0J1503D01*
G37*
G36*
G01X327303Y1398086D02*
X330703D01*
G02Y1395080I0J-1503D01*
G01X327303D01*
G02Y1398086I0J1503D01*
G37*
G36*
G01X339543Y1409998D02*
X342943D01*
G02Y1406992I0J-1503D01*
G01X339543D01*
G02Y1409998I0J1503D01*
G37*
G36*
G01X302823Y1385800D02*
X306223D01*
G02Y1382794I0J-1503D01*
G01X302823D01*
G02Y1385800I0J1503D01*
G37*
G36*
G01X278343D02*
X281743D01*
G02Y1382794I0J-1503D01*
G01X278343D01*
G02Y1385800I0J1503D01*
G37*
G36*
G01X1340486Y1398086D02*
X1343886D01*
G02Y1395080I0J-1503D01*
G01X1340486D01*
G02Y1398086I0J1503D01*
G37*
G36*
G01Y1409998D02*
X1343886D01*
G02Y1406992I0J-1503D01*
G01X1340486D01*
G02Y1409998I0J1503D01*
G37*
G36*
G01X1583770Y1385800D02*
X1587170D01*
G02Y1382794I0J-1503D01*
G01X1583770D01*
G02Y1385800I0J1503D01*
G37*
G36*
G01X1571530Y1349690D02*
X1574930D01*
G02Y1346684I0J-1503D01*
G01X1571530D01*
G02Y1349690I0J1503D01*
G37*
G36*
G01Y1373888D02*
X1574930D01*
G02Y1370882I0J-1503D01*
G01X1571530D01*
G02Y1373888I0J1503D01*
G37*
G36*
G01Y1385800D02*
X1574930D01*
G02Y1382794I0J-1503D01*
G01X1571530D01*
G02Y1385800I0J1503D01*
G37*
G36*
G01X1473610Y1398086D02*
X1477010D01*
G02Y1395080I0J-1503D01*
G01X1473610D01*
G02Y1398086I0J1503D01*
G37*
G36*
G01Y1409998D02*
X1477010D01*
G02Y1406992I0J-1503D01*
G01X1473610D01*
G02Y1409998I0J1503D01*
G37*
G36*
G01X1583770Y1398086D02*
X1587170D01*
G02Y1395080I0J-1503D01*
G01X1583770D01*
G02Y1398086I0J1503D01*
G37*
G36*
G01Y1409998D02*
X1587170D01*
G02Y1406992I0J-1503D01*
G01X1583770D01*
G02Y1409998I0J1503D01*
G37*
G36*
G01X1485850Y1398086D02*
X1489250D01*
G02Y1395080I0J-1503D01*
G01X1485850D01*
G02Y1398086I0J1503D01*
G37*
G36*
G01X1498090Y1373888D02*
X1501490D01*
G02Y1370882I0J-1503D01*
G01X1498090D01*
G02Y1373888I0J1503D01*
G37*
G36*
G01X1522570Y1361602D02*
X1525970D01*
G02Y1358596I0J-1503D01*
G01X1522570D01*
G02Y1361602I0J1503D01*
G37*
G36*
G01X1498090Y1409998D02*
X1501490D01*
G02Y1406992I0J-1503D01*
G01X1498090D01*
G02Y1409998I0J1503D01*
G37*
G36*
G01X1352726Y1349690D02*
X1356126D01*
G02Y1346684I0J-1503D01*
G01X1352726D01*
G02Y1349690I0J1503D01*
G37*
G36*
G01X1510330Y1398086D02*
X1513730D01*
G02Y1395080I0J-1503D01*
G01X1510330D01*
G02Y1398086I0J1503D01*
G37*
G36*
G01X1611398Y1361602D02*
X1614798D01*
G02Y1358596I0J-1503D01*
G01X1611398D01*
G02Y1361602I0J1503D01*
G37*
G36*
G01X1623638Y1373888D02*
X1627038D01*
G02Y1370882I0J-1503D01*
G01X1623638D01*
G02Y1373888I0J1503D01*
G37*
G36*
G01X1547050D02*
X1550450D01*
G02Y1370882I0J-1503D01*
G01X1547050D01*
G02Y1373888I0J1503D01*
G37*
G36*
G01X1352726Y1361602D02*
X1356126D01*
G02Y1358596I0J-1503D01*
G01X1352726D01*
G02Y1361602I0J1503D01*
G37*
G36*
G01Y1385800D02*
X1356126D01*
G02Y1382794I0J-1503D01*
G01X1352726D01*
G02Y1385800I0J1503D01*
G37*
G36*
G01Y1373888D02*
X1356126D01*
G02Y1370882I0J-1503D01*
G01X1352726D01*
G02Y1373888I0J1503D01*
G37*
G36*
G01X1684838Y1409998D02*
X1688238D01*
G02Y1406992I0J-1503D01*
G01X1684838D01*
G02Y1409998I0J1503D01*
G37*
G36*
G01X1709318Y1373888D02*
X1712718D01*
G02Y1370882I0J-1503D01*
G01X1709318D01*
G02Y1373888I0J1503D01*
G37*
G36*
G01Y1385800D02*
X1712718D01*
G02Y1382794I0J-1503D01*
G01X1709318D01*
G02Y1385800I0J1503D01*
G37*
G36*
G01X1733798Y1361602D02*
X1737198D01*
G02Y1358596I0J-1503D01*
G01X1733798D01*
G02Y1361602I0J1503D01*
G37*
G36*
G01X1697078Y1373888D02*
X1700478D01*
G02Y1370882I0J-1503D01*
G01X1697078D01*
G02Y1373888I0J1503D01*
G37*
G36*
G01X1709318Y1409998D02*
X1712718D01*
G02Y1406992I0J-1503D01*
G01X1709318D01*
G02Y1409998I0J1503D01*
G37*
G36*
G01X1697078Y1398086D02*
X1700478D01*
G02Y1395080I0J-1503D01*
G01X1697078D01*
G02Y1398086I0J1503D01*
G37*
G36*
G01X1709318D02*
X1712718D01*
G02Y1395080I0J-1503D01*
G01X1709318D01*
G02Y1398086I0J1503D01*
G37*
G36*
G01X1721558Y1349690D02*
X1724958D01*
G02Y1346684I0J-1503D01*
G01X1721558D01*
G02Y1349690I0J1503D01*
G37*
G36*
G01Y1361602D02*
X1724958D01*
G02Y1358596I0J-1503D01*
G01X1721558D01*
G02Y1361602I0J1503D01*
G37*
G36*
G01Y1409998D02*
X1724958D01*
G02Y1406992I0J-1503D01*
G01X1721558D01*
G02Y1409998I0J1503D01*
G37*
G36*
G01X1352726Y1398086D02*
X1356126D01*
G02Y1395080I0J-1503D01*
G01X1352726D01*
G02Y1398086I0J1503D01*
G37*
G36*
G01X174032Y1361602D02*
X177432D01*
G02Y1358596I0J-1503D01*
G01X174032D01*
G02Y1361602I0J1503D01*
G37*
G36*
G01X198512Y1349690D02*
X201912D01*
G02Y1346684I0J-1503D01*
G01X198512D01*
G02Y1349690I0J1503D01*
G37*
G36*
G01Y1398086D02*
X201912D01*
G02Y1395080I0J-1503D01*
G01X198512D01*
G02Y1398086I0J1503D01*
G37*
G36*
G01X186272D02*
X189672D01*
G02Y1395080I0J-1503D01*
G01X186272D01*
G02Y1398086I0J1503D01*
G37*
G36*
G01X161792Y1349690D02*
X165192D01*
G02Y1346684I0J-1503D01*
G01X161792D01*
G02Y1349690I0J1503D01*
G37*
G36*
G01X186272Y1361602D02*
X189672D01*
G02Y1358596I0J-1503D01*
G01X186272D01*
G02Y1361602I0J1503D01*
G37*
G36*
G01X100592Y1349690D02*
X103992D01*
G02Y1346684I0J-1503D01*
G01X100592D01*
G02Y1349690I0J1503D01*
G37*
G36*
G01X112832D02*
X116232D01*
G02Y1346684I0J-1503D01*
G01X112832D01*
G02Y1349690I0J1503D01*
G37*
G36*
G01X149552Y1398086D02*
X152952D01*
G02Y1395080I0J-1503D01*
G01X149552D01*
G02Y1398086I0J1503D01*
G37*
G36*
G01X161792D02*
X165192D01*
G02Y1395080I0J-1503D01*
G01X161792D01*
G02Y1398086I0J1503D01*
G37*
G36*
G01Y1373888D02*
X165192D01*
G02Y1370882I0J-1503D01*
G01X161792D01*
G02Y1373888I0J1503D01*
G37*
G36*
G01Y1385800D02*
X165192D01*
G02Y1382794I0J-1503D01*
G01X161792D01*
G02Y1385800I0J1503D01*
G37*
G36*
G01X198512Y1361602D02*
X201912D01*
G02Y1358596I0J-1503D01*
G01X198512D01*
G02Y1361602I0J1503D01*
G37*
G36*
G01X137312D02*
X140712D01*
G02Y1358596I0J-1503D01*
G01X137312D01*
G02Y1361602I0J1503D01*
G37*
G36*
G01X161792D02*
X165192D01*
G02Y1358596I0J-1503D01*
G01X161792D01*
G02Y1361602I0J1503D01*
G37*
G36*
G01X149552Y1349690D02*
X152952D01*
G02Y1346684I0J-1503D01*
G01X149552D01*
G02Y1349690I0J1503D01*
G37*
G36*
G01X137312D02*
X140712D01*
G02Y1346684I0J-1503D01*
G01X137312D01*
G02Y1349690I0J1503D01*
G37*
G36*
G01X76112Y1361602D02*
X79512D01*
G02Y1358596I0J-1503D01*
G01X76112D01*
G02Y1361602I0J1503D01*
G37*
G36*
G01X174032Y1385800D02*
X177432D01*
G02Y1382794I0J-1503D01*
G01X174032D01*
G02Y1385800I0J1503D01*
G37*
G36*
G01X125072Y1409998D02*
X128472D01*
G02Y1406992I0J-1503D01*
G01X125072D01*
G02Y1409998I0J1503D01*
G37*
G36*
G01Y1398086D02*
X128472D01*
G02Y1395080I0J-1503D01*
G01X125072D01*
G02Y1398086I0J1503D01*
G37*
G36*
G01Y1373888D02*
X128472D01*
G02Y1370882I0J-1503D01*
G01X125072D01*
G02Y1373888I0J1503D01*
G37*
G36*
G01Y1385800D02*
X128472D01*
G02Y1382794I0J-1503D01*
G01X125072D01*
G02Y1385800I0J1503D01*
G37*
G36*
G01X1571530Y1361602D02*
X1574930D01*
G02Y1358596I0J-1503D01*
G01X1571530D01*
G02Y1361602I0J1503D01*
G37*
G36*
G01X100592Y1385800D02*
X103992D01*
G02Y1382794I0J-1503D01*
G01X100592D01*
G02Y1385800I0J1503D01*
G37*
G36*
G01X76112Y1373888D02*
X79512D01*
G02Y1370882I0J-1503D01*
G01X76112D01*
G02Y1373888I0J1503D01*
G37*
G36*
G01X88352Y1409998D02*
X91752D01*
G02Y1406992I0J-1503D01*
G01X88352D01*
G02Y1409998I0J1503D01*
G37*
G36*
G01X149552D02*
X152952D01*
G02Y1406992I0J-1503D01*
G01X149552D01*
G02Y1409998I0J1503D01*
G37*
G36*
G01X137312Y1373888D02*
X140712D01*
G02Y1370882I0J-1503D01*
G01X137312D01*
G02Y1373888I0J1503D01*
G37*
G36*
G01X253863Y1385800D02*
X257263D01*
G02Y1382794I0J-1503D01*
G01X253863D01*
G02Y1385800I0J1503D01*
G37*
G36*
G01X186272Y1409998D02*
X189672D01*
G02Y1406992I0J-1503D01*
G01X186272D01*
G02Y1409998I0J1503D01*
G37*
G36*
G01X125072Y1361602D02*
X128472D01*
G02Y1358596I0J-1503D01*
G01X125072D01*
G02Y1361602I0J1503D01*
G37*
G36*
G01Y1349690D02*
X128472D01*
G02Y1346684I0J-1503D01*
G01X125072D01*
G02Y1349690I0J1503D01*
G37*
G36*
G01X149552Y1373888D02*
X152952D01*
G02Y1370882I0J-1503D01*
G01X149552D01*
G02Y1373888I0J1503D01*
G37*
G36*
G01X174032Y1349690D02*
X177432D01*
G02Y1346684I0J-1503D01*
G01X174032D01*
G02Y1349690I0J1503D01*
G37*
G36*
G01Y1373888D02*
X177432D01*
G02Y1370882I0J-1503D01*
G01X174032D01*
G02Y1373888I0J1503D01*
G37*
G36*
G01X76112Y1385800D02*
X79512D01*
G02Y1382794I0J-1503D01*
G01X76112D01*
G02Y1385800I0J1503D01*
G37*
G36*
G01X1583770Y1349690D02*
X1587170D01*
G02Y1346684I0J-1503D01*
G01X1583770D01*
G02Y1349690I0J1503D01*
G37*
G36*
G01X1697078Y1385800D02*
X1700478D01*
G02Y1382794I0J-1503D01*
G01X1697078D01*
G02Y1385800I0J1503D01*
G37*
G36*
G01X88352Y1361602D02*
X91752D01*
G02Y1358596I0J-1503D01*
G01X88352D01*
G02Y1361602I0J1503D01*
G37*
G36*
G01Y1349690D02*
X91752D01*
G02Y1346684I0J-1503D01*
G01X88352D01*
G02Y1349690I0J1503D01*
G37*
G36*
G01X1697078Y1409998D02*
X1700478D01*
G02Y1406992I0J-1503D01*
G01X1697078D01*
G02Y1409998I0J1503D01*
G37*
G36*
G01X112832Y1373888D02*
X116232D01*
G02Y1370882I0J-1503D01*
G01X112832D01*
G02Y1373888I0J1503D01*
G37*
G36*
G01Y1409998D02*
X116232D01*
G02Y1406992I0J-1503D01*
G01X112832D01*
G02Y1409998I0J1503D01*
G37*
G36*
G01X100592D02*
X103992D01*
G02Y1406992I0J-1503D01*
G01X100592D01*
G02Y1409998I0J1503D01*
G37*
G36*
G01X724208Y1385800D02*
X727608D01*
G02Y1382794I0J-1503D01*
G01X724208D01*
G02Y1385800I0J1503D01*
G37*
G36*
G01X88352D02*
X91752D01*
G02Y1382794I0J-1503D01*
G01X88352D01*
G02Y1385800I0J1503D01*
G37*
G36*
G01X760928Y1361602D02*
X764328D01*
G02Y1358596I0J-1503D01*
G01X760928D01*
G02Y1361602I0J1503D01*
G37*
G36*
G01X100592Y1373888D02*
X103992D01*
G02Y1370882I0J-1503D01*
G01X100592D01*
G02Y1373888I0J1503D01*
G37*
G36*
G01X137312Y1398086D02*
X140712D01*
G02Y1395080I0J-1503D01*
G01X137312D01*
G02Y1398086I0J1503D01*
G37*
G36*
G01Y1409998D02*
X140712D01*
G02Y1406992I0J-1503D01*
G01X137312D01*
G02Y1409998I0J1503D01*
G37*
G36*
G01X112832Y1385800D02*
X116232D01*
G02Y1382794I0J-1503D01*
G01X112832D01*
G02Y1385800I0J1503D01*
G37*
G36*
G01X663008Y1361602D02*
X666408D01*
G02Y1358596I0J-1503D01*
G01X663008D01*
G02Y1361602I0J1503D01*
G37*
G36*
G01X100592Y1398086D02*
X103992D01*
G02Y1395080I0J-1503D01*
G01X100592D01*
G02Y1398086I0J1503D01*
G37*
G36*
G01X748688Y1385800D02*
X752088D01*
G02Y1382794I0J-1503D01*
G01X748688D01*
G02Y1385800I0J1503D01*
G37*
G36*
G01X1352726Y1409998D02*
X1356126D01*
G02Y1406992I0J-1503D01*
G01X1352726D01*
G02Y1409998I0J1503D01*
G37*
G36*
G01X100592Y1361602D02*
X103992D01*
G02Y1358596I0J-1503D01*
G01X100592D01*
G02Y1361602I0J1503D01*
G37*
G36*
G01X112832D02*
X116232D01*
G02Y1358596I0J-1503D01*
G01X112832D01*
G02Y1361602I0J1503D01*
G37*
G36*
G01X88352Y1398086D02*
X91752D01*
G02Y1395080I0J-1503D01*
G01X88352D01*
G02Y1398086I0J1503D01*
G37*
G36*
G01X1660358Y1361602D02*
X1663758D01*
G02Y1358596I0J-1503D01*
G01X1660358D01*
G02Y1361602I0J1503D01*
G37*
G36*
G01X1066953Y1349690D02*
X1070353D01*
G02Y1346684I0J-1503D01*
G01X1066953D01*
G02Y1349690I0J1503D01*
G37*
G36*
G01X663008D02*
X666408D01*
G02Y1346684I0J-1503D01*
G01X663008D01*
G02Y1349690I0J1503D01*
G37*
G36*
G01X1583770Y1361602D02*
X1587170D01*
G02Y1358596I0J-1503D01*
G01X1583770D01*
G02Y1361602I0J1503D01*
G37*
G36*
G01X1571530Y1398086D02*
X1574930D01*
G02Y1395080I0J-1503D01*
G01X1571530D01*
G02Y1398086I0J1503D01*
G37*
G36*
G01X1559290Y1361602D02*
X1562690D01*
G02Y1358596I0J-1503D01*
G01X1559290D01*
G02Y1361602I0J1503D01*
G37*
G36*
G01Y1373888D02*
X1562690D01*
G02Y1370882I0J-1503D01*
G01X1559290D01*
G02Y1373888I0J1503D01*
G37*
G36*
G01X1623638Y1385800D02*
X1627038D01*
G02Y1382794I0J-1503D01*
G01X1623638D01*
G02Y1385800I0J1503D01*
G37*
G36*
G01X76112Y1349690D02*
X79512D01*
G02Y1346684I0J-1503D01*
G01X76112D01*
G02Y1349690I0J1503D01*
G37*
G36*
G01X1066953Y1361602D02*
X1070353D01*
G02Y1358596I0J-1503D01*
G01X1066953D01*
G02Y1361602I0J1503D01*
G37*
G36*
G01X1547050Y1385800D02*
X1550450D01*
G02Y1382794I0J-1503D01*
G01X1547050D01*
G02Y1385800I0J1503D01*
G37*
G36*
G01X1672598Y1349690D02*
X1675998D01*
G02Y1346684I0J-1503D01*
G01X1672598D01*
G02Y1349690I0J1503D01*
G37*
G36*
G01X1660358D02*
X1663758D01*
G02Y1346684I0J-1503D01*
G01X1660358D01*
G02Y1349690I0J1503D01*
G37*
G36*
G01X1672598Y1361602D02*
X1675998D01*
G02Y1358596I0J-1503D01*
G01X1672598D01*
G02Y1361602I0J1503D01*
G37*
G36*
G01X1709318Y1349690D02*
X1712718D01*
G02Y1346684I0J-1503D01*
G01X1709318D01*
G02Y1349690I0J1503D01*
G37*
G36*
G01X1697078D02*
X1700478D01*
G02Y1346684I0J-1503D01*
G01X1697078D01*
G02Y1349690I0J1503D01*
G37*
G36*
G01X1684838Y1385800D02*
X1688238D01*
G02Y1382794I0J-1503D01*
G01X1684838D01*
G02Y1385800I0J1503D01*
G37*
G36*
G01X1709318Y1361602D02*
X1712718D01*
G02Y1358596I0J-1503D01*
G01X1709318D01*
G02Y1361602I0J1503D01*
G37*
G36*
G01X1697078D02*
X1700478D01*
G02Y1358596I0J-1503D01*
G01X1697078D01*
G02Y1361602I0J1503D01*
G37*
G36*
G01X1684838D02*
X1688238D01*
G02Y1358596I0J-1503D01*
G01X1684838D01*
G02Y1361602I0J1503D01*
G37*
G36*
G01Y1373888D02*
X1688238D01*
G02Y1370882I0J-1503D01*
G01X1684838D01*
G02Y1373888I0J1503D01*
G37*
G36*
G01Y1398086D02*
X1688238D01*
G02Y1395080I0J-1503D01*
G01X1684838D01*
G02Y1398086I0J1503D01*
G37*
G36*
G01X1066953Y1373888D02*
X1070353D01*
G02Y1370882I0J-1503D01*
G01X1066953D01*
G02Y1373888I0J1503D01*
G37*
G36*
G01Y1385800D02*
X1070353D01*
G02Y1382794I0J-1503D01*
G01X1066953D01*
G02Y1385800I0J1503D01*
G37*
G36*
G01X1547050Y1398086D02*
X1550450D01*
G02Y1395080I0J-1503D01*
G01X1547050D01*
G02Y1398086I0J1503D01*
G37*
G36*
G01X549168Y783102D02*
G02Y780098I0J-1502D01*
G01X545813D01*
X545808D01*
G02X545944Y783092I-38J1502D01*
G01X545956Y783090D01*
X548978D01*
X548990Y783092D01*
G02X549168Y783102I173J-1492D01*
G37*
G36*
G01X278343Y1349690D02*
X281743D01*
G02Y1346684I0J-1503D01*
G01X278343D01*
G02Y1349690I0J1503D01*
G37*
G36*
G01X945982Y888540D02*
X949382D01*
G02Y884936I0J-1802D01*
G01X945982D01*
G02Y888540I0J1802D01*
G37*
G36*
G01X1684838Y1349690D02*
X1688238D01*
G02Y1346684I0J-1503D01*
G01X1684838D01*
G02Y1349690I0J1503D01*
G37*
G36*
G01X1571530Y1409998D02*
X1574930D01*
G02Y1406992I0J-1503D01*
G01X1571530D01*
G02Y1409998I0J1503D01*
G37*
G36*
G01X1473610Y1373888D02*
X1477010D01*
G02Y1370882I0J-1503D01*
G01X1473610D01*
G02Y1373888I0J1503D01*
G37*
G36*
G01X1498090Y1398086D02*
X1501490D01*
G02Y1395080I0J-1503D01*
G01X1498090D01*
G02Y1398086I0J1503D01*
G37*
G36*
G01Y1385800D02*
X1501490D01*
G02Y1382794I0J-1503D01*
G01X1498090D01*
G02Y1385800I0J1503D01*
G37*
G36*
G01X1510330Y1409998D02*
X1513730D01*
G02Y1406992I0J-1503D01*
G01X1510330D01*
G02Y1409998I0J1503D01*
G37*
G36*
G01X1522570Y1349690D02*
X1525970D01*
G02Y1346684I0J-1503D01*
G01X1522570D01*
G02Y1349690I0J1503D01*
G37*
G36*
G01X146948Y1135604D02*
X143208D01*
G02Y1138210I0J1303D01*
G01X146948D01*
G02Y1135604I0J-1303D01*
G37*
G36*
G01X165649Y1131864D02*
X161909D01*
G02Y1134470I0J1303D01*
G01X165649D01*
G02Y1131864I0J-1303D01*
G37*
G36*
G01X154429D02*
X150689D01*
G02Y1134470I0J1303D01*
G01X154429D01*
G02Y1131864I0J-1303D01*
G37*
G36*
G01X173129Y1135604D02*
X169389D01*
G02Y1138210I0J1303D01*
G01X173129D01*
G02Y1135604I0J-1303D01*
G37*
G36*
G01X440402Y1361602D02*
X443802D01*
G02Y1358596I0J-1503D01*
G01X440402D01*
G02Y1361602I0J1503D01*
G37*
G36*
G01Y1349690D02*
X443802D01*
G02Y1346684I0J-1503D01*
G01X440402D01*
G02Y1349690I0J1503D01*
G37*
G36*
G01X452642Y1361602D02*
X456042D01*
G02Y1358596I0J-1503D01*
G01X452642D01*
G02Y1361602I0J1503D01*
G37*
G36*
G01Y1349690D02*
X456042D01*
G02Y1346684I0J-1503D01*
G01X452642D01*
G02Y1349690I0J1503D01*
G37*
G36*
G01X501602Y1385800D02*
X505002D01*
G02Y1382794I0J-1503D01*
G01X501602D01*
G02Y1385800I0J1503D01*
G37*
G36*
G01X513842D02*
X517242D01*
G02Y1382794I0J-1503D01*
G01X513842D01*
G02Y1385800I0J1503D01*
G37*
G36*
G01Y1373888D02*
X517242D01*
G02Y1370882I0J-1503D01*
G01X513842D01*
G02Y1373888I0J1503D01*
G37*
G36*
G01X501602D02*
X505002D01*
G02Y1370882I0J-1503D01*
G01X501602D01*
G02Y1373888I0J1503D01*
G37*
G36*
G01X464882Y1349690D02*
X468282D01*
G02Y1346684I0J-1503D01*
G01X464882D01*
G02Y1349690I0J1503D01*
G37*
G36*
G01X477122D02*
X480522D01*
G02Y1346684I0J-1503D01*
G01X477122D01*
G02Y1349690I0J1503D01*
G37*
G36*
G01X526082Y1385800D02*
X529482D01*
G02Y1382794I0J-1503D01*
G01X526082D01*
G02Y1385800I0J1503D01*
G37*
G36*
G01X538322D02*
X541722D01*
G02Y1382794I0J-1503D01*
G01X538322D01*
G02Y1385800I0J1503D01*
G37*
G36*
G01X526082Y1373888D02*
X529482D01*
G02Y1370882I0J-1503D01*
G01X526082D01*
G02Y1373888I0J1503D01*
G37*
G36*
G01X538322D02*
X541722D01*
G02Y1370882I0J-1503D01*
G01X538322D01*
G02Y1373888I0J1503D01*
G37*
G36*
G01X464882Y1361602D02*
X468282D01*
G02Y1358596I0J-1503D01*
G01X464882D01*
G02Y1361602I0J1503D01*
G37*
G36*
G01X477122D02*
X480522D01*
G02Y1358596I0J-1503D01*
G01X477122D01*
G02Y1361602I0J1503D01*
G37*
G36*
G01X489362Y1349690D02*
X492762D01*
G02Y1346684I0J-1503D01*
G01X489362D01*
G02Y1349690I0J1503D01*
G37*
G36*
G01X440402Y1373888D02*
X443802D01*
G02Y1370882I0J-1503D01*
G01X440402D01*
G02Y1373888I0J1503D01*
G37*
G36*
G01X550562Y1385800D02*
X553962D01*
G02Y1382794I0J-1503D01*
G01X550562D01*
G02Y1385800I0J1503D01*
G37*
G36*
G01Y1373888D02*
X553962D01*
G02Y1370882I0J-1503D01*
G01X550562D01*
G02Y1373888I0J1503D01*
G37*
G36*
G01X489362Y1361602D02*
X492762D01*
G02Y1358596I0J-1503D01*
G01X489362D01*
G02Y1361602I0J1503D01*
G37*
G36*
G01X440402Y1385800D02*
X443802D01*
G02Y1382794I0J-1503D01*
G01X440402D01*
G02Y1385800I0J1503D01*
G37*
G36*
G01X452642Y1373888D02*
X456042D01*
G02Y1370882I0J-1503D01*
G01X452642D01*
G02Y1373888I0J1503D01*
G37*
G36*
G01X562802Y1385800D02*
X566202D01*
G02Y1382794I0J-1503D01*
G01X562802D01*
G02Y1385800I0J1503D01*
G37*
G36*
G01X452642Y1409998D02*
X456042D01*
G02Y1406992I0J-1503D01*
G01X452642D01*
G02Y1409998I0J1503D01*
G37*
G36*
G01Y1398086D02*
X456042D01*
G02Y1395080I0J-1503D01*
G01X452642D01*
G02Y1398086I0J1503D01*
G37*
G36*
G01X562802Y1373888D02*
X566202D01*
G02Y1370882I0J-1503D01*
G01X562802D01*
G02Y1373888I0J1503D01*
G37*
G36*
G01X452642Y1385800D02*
X456042D01*
G02Y1382794I0J-1503D01*
G01X452642D01*
G02Y1385800I0J1503D01*
G37*
G36*
G01X464882Y1409998D02*
X468282D01*
G02Y1406992I0J-1503D01*
G01X464882D01*
G02Y1409998I0J1503D01*
G37*
G36*
G01Y1398086D02*
X468282D01*
G02Y1395080I0J-1503D01*
G01X464882D01*
G02Y1398086I0J1503D01*
G37*
G36*
G01Y1385800D02*
X468282D01*
G02Y1382794I0J-1503D01*
G01X464882D01*
G02Y1385800I0J1503D01*
G37*
G36*
G01X477122D02*
X480522D01*
G02Y1382794I0J-1503D01*
G01X477122D01*
G02Y1385800I0J1503D01*
G37*
G36*
G01Y1373888D02*
X480522D01*
G02Y1370882I0J-1503D01*
G01X477122D01*
G02Y1373888I0J1503D01*
G37*
G36*
G01X464882D02*
X468282D01*
G02Y1370882I0J-1503D01*
G01X464882D01*
G02Y1373888I0J1503D01*
G37*
G36*
G01X489362D02*
X492762D01*
G02Y1370882I0J-1503D01*
G01X489362D01*
G02Y1373888I0J1503D01*
G37*
G36*
G01Y1409998D02*
X492762D01*
G02Y1406992I0J-1503D01*
G01X489362D01*
G02Y1409998I0J1503D01*
G37*
G36*
G01Y1398086D02*
X492762D01*
G02Y1395080I0J-1503D01*
G01X489362D01*
G02Y1398086I0J1503D01*
G37*
G36*
G01X477122Y1409998D02*
X480522D01*
G02Y1406992I0J-1503D01*
G01X477122D01*
G02Y1409998I0J1503D01*
G37*
G36*
G01Y1398086D02*
X480522D01*
G02Y1395080I0J-1503D01*
G01X477122D01*
G02Y1398086I0J1503D01*
G37*
G36*
G01X489362Y1385800D02*
X492762D01*
G02Y1382794I0J-1503D01*
G01X489362D01*
G02Y1385800I0J1503D01*
G37*
G36*
G01X501602Y1361602D02*
X505002D01*
G02Y1358596I0J-1503D01*
G01X501602D01*
G02Y1361602I0J1503D01*
G37*
G36*
G01X513842D02*
X517242D01*
G02Y1358596I0J-1503D01*
G01X513842D01*
G02Y1361602I0J1503D01*
G37*
G36*
G01X501602Y1349690D02*
X505002D01*
G02Y1346684I0J-1503D01*
G01X501602D01*
G02Y1349690I0J1503D01*
G37*
G36*
G01X513842D02*
X517242D01*
G02Y1346684I0J-1503D01*
G01X513842D01*
G02Y1349690I0J1503D01*
G37*
G36*
G01X501602Y1398086D02*
X505002D01*
G02Y1395080I0J-1503D01*
G01X501602D01*
G02Y1398086I0J1503D01*
G37*
G36*
G01Y1409998D02*
X505002D01*
G02Y1406992I0J-1503D01*
G01X501602D01*
G02Y1409998I0J1503D01*
G37*
G36*
G01X526082Y1361602D02*
X529482D01*
G02Y1358596I0J-1503D01*
G01X526082D01*
G02Y1361602I0J1503D01*
G37*
G36*
G01Y1349690D02*
X529482D01*
G02Y1346684I0J-1503D01*
G01X526082D01*
G02Y1349690I0J1503D01*
G37*
G36*
G01X513842Y1398086D02*
X517242D01*
G02Y1395080I0J-1503D01*
G01X513842D01*
G02Y1398086I0J1503D01*
G37*
G36*
G01X526082Y1409998D02*
X529482D01*
G02Y1406992I0J-1503D01*
G01X526082D01*
G02Y1409998I0J1503D01*
G37*
G36*
G01X513842D02*
X517242D01*
G02Y1406992I0J-1503D01*
G01X513842D01*
G02Y1409998I0J1503D01*
G37*
G36*
G01X526082Y1398086D02*
X529482D01*
G02Y1395080I0J-1503D01*
G01X526082D01*
G02Y1398086I0J1503D01*
G37*
G36*
G01X538322Y1361602D02*
X541722D01*
G02Y1358596I0J-1503D01*
G01X538322D01*
G02Y1361602I0J1503D01*
G37*
G36*
G01X550562D02*
X553962D01*
G02Y1358596I0J-1503D01*
G01X550562D01*
G02Y1361602I0J1503D01*
G37*
G36*
G01X538322Y1349690D02*
X541722D01*
G02Y1346684I0J-1503D01*
G01X538322D01*
G02Y1349690I0J1503D01*
G37*
G36*
G01X550562D02*
X553962D01*
G02Y1346684I0J-1503D01*
G01X550562D01*
G02Y1349690I0J1503D01*
G37*
G36*
G01X538322Y1398086D02*
X541722D01*
G02Y1395080I0J-1503D01*
G01X538322D01*
G02Y1398086I0J1503D01*
G37*
G36*
G01Y1409998D02*
X541722D01*
G02Y1406992I0J-1503D01*
G01X538322D01*
G02Y1409998I0J1503D01*
G37*
G36*
G01X562802Y1361602D02*
X566202D01*
G02Y1358596I0J-1503D01*
G01X562802D01*
G02Y1361602I0J1503D01*
G37*
G36*
G01Y1349690D02*
X566202D01*
G02Y1346684I0J-1503D01*
G01X562802D01*
G02Y1349690I0J1503D01*
G37*
G36*
G01X550562Y1398086D02*
X553962D01*
G02Y1395080I0J-1503D01*
G01X550562D01*
G02Y1398086I0J1503D01*
G37*
G36*
G01X562802D02*
X566202D01*
G02Y1395080I0J-1503D01*
G01X562802D01*
G02Y1398086I0J1503D01*
G37*
G36*
G01X550562Y1409998D02*
X553962D01*
G02Y1406992I0J-1503D01*
G01X550562D01*
G02Y1409998I0J1503D01*
G37*
G36*
G01X562802D02*
X566202D01*
G02Y1406992I0J-1503D01*
G01X562802D01*
G02Y1409998I0J1503D01*
G37*
G36*
G01X650768Y1361602D02*
X654168D01*
G02Y1358596I0J-1503D01*
G01X650768D01*
G02Y1361602I0J1503D01*
G37*
G36*
G01Y1349690D02*
X654168D01*
G02Y1346684I0J-1503D01*
G01X650768D01*
G02Y1349690I0J1503D01*
G37*
G36*
G01X626288Y1409998D02*
X629688D01*
G02Y1406992I0J-1503D01*
G01X626288D01*
G02Y1409998I0J1503D01*
G37*
G36*
G01X638528Y1385800D02*
X641928D01*
G02Y1382794I0J-1503D01*
G01X638528D01*
G02Y1385800I0J1503D01*
G37*
G36*
G01Y1373888D02*
X641928D01*
G02Y1370882I0J-1503D01*
G01X638528D01*
G02Y1373888I0J1503D01*
G37*
G36*
G01X626288Y1398086D02*
X629688D01*
G02Y1395080I0J-1503D01*
G01X626288D01*
G02Y1398086I0J1503D01*
G37*
G36*
G01X675248Y1361602D02*
X678648D01*
G02Y1358596I0J-1503D01*
G01X675248D01*
G02Y1361602I0J1503D01*
G37*
G36*
G01X650768Y1385800D02*
X654168D01*
G02Y1382794I0J-1503D01*
G01X650768D01*
G02Y1385800I0J1503D01*
G37*
G36*
G01X675248Y1349690D02*
X678648D01*
G02Y1346684I0J-1503D01*
G01X675248D01*
G02Y1349690I0J1503D01*
G37*
G36*
G01X650768Y1373888D02*
X654168D01*
G02Y1370882I0J-1503D01*
G01X650768D01*
G02Y1373888I0J1503D01*
G37*
G36*
G01X638528Y1409998D02*
X641928D01*
G02Y1406992I0J-1503D01*
G01X638528D01*
G02Y1409998I0J1503D01*
G37*
G36*
G01Y1398086D02*
X641928D01*
G02Y1395080I0J-1503D01*
G01X638528D01*
G02Y1398086I0J1503D01*
G37*
G36*
G01X687488Y1361602D02*
X690888D01*
G02Y1358596I0J-1503D01*
G01X687488D01*
G02Y1361602I0J1503D01*
G37*
G36*
G01Y1349690D02*
X690888D01*
G02Y1346684I0J-1503D01*
G01X687488D01*
G02Y1349690I0J1503D01*
G37*
G36*
G01X663008Y1385800D02*
X666408D01*
G02Y1382794I0J-1503D01*
G01X663008D01*
G02Y1385800I0J1503D01*
G37*
G36*
G01X650768Y1409998D02*
X654168D01*
G02Y1406992I0J-1503D01*
G01X650768D01*
G02Y1409998I0J1503D01*
G37*
G36*
G01X663008Y1373888D02*
X666408D01*
G02Y1370882I0J-1503D01*
G01X663008D01*
G02Y1373888I0J1503D01*
G37*
G36*
G01X650768Y1398086D02*
X654168D01*
G02Y1395080I0J-1503D01*
G01X650768D01*
G02Y1398086I0J1503D01*
G37*
G36*
G01X699728Y1361602D02*
X703128D01*
G02Y1358596I0J-1503D01*
G01X699728D01*
G02Y1361602I0J1503D01*
G37*
G36*
G01X687488Y1385800D02*
X690888D01*
G02Y1382794I0J-1503D01*
G01X687488D01*
G02Y1385800I0J1503D01*
G37*
G36*
G01X699728Y1349690D02*
X703128D01*
G02Y1346684I0J-1503D01*
G01X699728D01*
G02Y1349690I0J1503D01*
G37*
G36*
G01X687488Y1373888D02*
X690888D01*
G02Y1370882I0J-1503D01*
G01X687488D01*
G02Y1373888I0J1503D01*
G37*
G36*
G01X675248Y1385800D02*
X678648D01*
G02Y1382794I0J-1503D01*
G01X675248D01*
G02Y1385800I0J1503D01*
G37*
G36*
G01Y1373888D02*
X678648D01*
G02Y1370882I0J-1503D01*
G01X675248D01*
G02Y1373888I0J1503D01*
G37*
G36*
G01X711968Y1349690D02*
X715368D01*
G02Y1346684I0J-1503D01*
G01X711968D01*
G02Y1349690I0J1503D01*
G37*
G36*
G01Y1361602D02*
X715368D01*
G02Y1358596I0J-1503D01*
G01X711968D01*
G02Y1361602I0J1503D01*
G37*
G36*
G01X663008Y1409998D02*
X666408D01*
G02Y1406992I0J-1503D01*
G01X663008D01*
G02Y1409998I0J1503D01*
G37*
G36*
G01X699728Y1385800D02*
X703128D01*
G02Y1382794I0J-1503D01*
G01X699728D01*
G02Y1385800I0J1503D01*
G37*
G36*
G01Y1373888D02*
X703128D01*
G02Y1370882I0J-1503D01*
G01X699728D01*
G02Y1373888I0J1503D01*
G37*
G36*
G01X663008Y1398086D02*
X666408D01*
G02Y1395080I0J-1503D01*
G01X663008D01*
G02Y1398086I0J1503D01*
G37*
G36*
G01X724208Y1397992D02*
X727608D01*
G02Y1394986I0J-1503D01*
G01X724208D01*
G02Y1397992I0J1503D01*
G37*
G36*
G01Y1349690D02*
X727608D01*
G02Y1346684I0J-1503D01*
G01X724208D01*
G02Y1349690I0J1503D01*
G37*
G36*
G01X675248Y1409998D02*
X678648D01*
G02Y1406992I0J-1503D01*
G01X675248D01*
G02Y1409998I0J1503D01*
G37*
G36*
G01Y1398086D02*
X678648D01*
G02Y1395080I0J-1503D01*
G01X675248D01*
G02Y1398086I0J1503D01*
G37*
G36*
G01X724208Y1361602D02*
X727608D01*
G02Y1358596I0J-1503D01*
G01X724208D01*
G02Y1361602I0J1503D01*
G37*
G36*
G01Y1409904D02*
X727608D01*
G02Y1406898I0J-1503D01*
G01X724208D01*
G02Y1409904I0J1503D01*
G37*
G36*
G01X736448Y1349690D02*
X739848D01*
G02Y1346684I0J-1503D01*
G01X736448D01*
G02Y1349690I0J1503D01*
G37*
G36*
G01X711968Y1373888D02*
X715368D01*
G02Y1370882I0J-1503D01*
G01X711968D01*
G02Y1373888I0J1503D01*
G37*
G36*
G01X736448Y1361602D02*
X739848D01*
G02Y1358596I0J-1503D01*
G01X736448D01*
G02Y1361602I0J1503D01*
G37*
G36*
G01X711968Y1385800D02*
X715368D01*
G02Y1382794I0J-1503D01*
G01X711968D01*
G02Y1385800I0J1503D01*
G37*
G36*
G01X687488Y1409998D02*
X690888D01*
G02Y1406992I0J-1503D01*
G01X687488D01*
G02Y1409998I0J1503D01*
G37*
G36*
G01Y1398086D02*
X690888D01*
G02Y1395080I0J-1503D01*
G01X687488D01*
G02Y1398086I0J1503D01*
G37*
G36*
G01X736448Y1373888D02*
X739848D01*
G02Y1370882I0J-1503D01*
G01X736448D01*
G02Y1373888I0J1503D01*
G37*
G36*
G01X748688Y1349690D02*
X752088D01*
G02Y1346684I0J-1503D01*
G01X748688D01*
G02Y1349690I0J1503D01*
G37*
G36*
G01X724208Y1373888D02*
X727608D01*
G02Y1370882I0J-1503D01*
G01X724208D01*
G02Y1373888I0J1503D01*
G37*
G36*
G01X736448Y1385800D02*
X739848D01*
G02Y1382794I0J-1503D01*
G01X736448D01*
G02Y1385800I0J1503D01*
G37*
G36*
G01X748688Y1361602D02*
X752088D01*
G02Y1358596I0J-1503D01*
G01X748688D01*
G02Y1361602I0J1503D01*
G37*
G36*
G01X736448Y1409904D02*
X739848D01*
G02Y1406898I0J-1503D01*
G01X736448D01*
G02Y1409904I0J1503D01*
G37*
G36*
G01Y1397992D02*
X739848D01*
G02Y1394986I0J-1503D01*
G01X736448D01*
G02Y1397992I0J1503D01*
G37*
G36*
G01X699728Y1409998D02*
X703128D01*
G02Y1406992I0J-1503D01*
G01X699728D01*
G02Y1409998I0J1503D01*
G37*
G36*
G01Y1398086D02*
X703128D01*
G02Y1395080I0J-1503D01*
G01X699728D01*
G02Y1398086I0J1503D01*
G37*
G36*
G01X748688Y1373888D02*
X752088D01*
G02Y1370882I0J-1503D01*
G01X748688D01*
G02Y1373888I0J1503D01*
G37*
G36*
G01X773168Y1349690D02*
X776568D01*
G02Y1346684I0J-1503D01*
G01X773168D01*
G02Y1349690I0J1503D01*
G37*
G36*
G01X760928D02*
X764328D01*
G02Y1346684I0J-1503D01*
G01X760928D01*
G02Y1349690I0J1503D01*
G37*
G36*
G01X711968Y1409998D02*
X715368D01*
G02Y1406992I0J-1503D01*
G01X711968D01*
G02Y1409998I0J1503D01*
G37*
G36*
G01Y1398086D02*
X715368D01*
G02Y1395080I0J-1503D01*
G01X711968D01*
G02Y1398086I0J1503D01*
G37*
G36*
G01X773168Y1361602D02*
X776568D01*
G02Y1358596I0J-1503D01*
G01X773168D01*
G02Y1361602I0J1503D01*
G37*
G36*
G01X760928Y1373888D02*
X764328D01*
G02Y1370882I0J-1503D01*
G01X760928D01*
G02Y1373888I0J1503D01*
G37*
G36*
G01Y1385800D02*
X764328D01*
G02Y1382794I0J-1503D01*
G01X760928D01*
G02Y1385800I0J1503D01*
G37*
G36*
G01X149552D02*
X152952D01*
G02Y1382794I0J-1503D01*
G01X149552D01*
G02Y1385800I0J1503D01*
G37*
G36*
G01Y1361602D02*
X152952D01*
G02Y1358596I0J-1503D01*
G01X149552D01*
G02Y1361602I0J1503D01*
G37*
G36*
G01X253863Y1373888D02*
X257263D01*
G02Y1370882I0J-1503D01*
G01X253863D01*
G02Y1373888I0J1503D01*
G37*
G36*
G01X198512D02*
X201912D01*
G02Y1370882I0J-1503D01*
G01X198512D01*
G02Y1373888I0J1503D01*
G37*
G36*
G01Y1409998D02*
X201912D01*
G02Y1406992I0J-1503D01*
G01X198512D01*
G02Y1409998I0J1503D01*
G37*
G36*
G01X364023Y1349690D02*
X367423D01*
G02Y1346684I0J-1503D01*
G01X364023D01*
G02Y1349690I0J1503D01*
G37*
G54D76*
X978614Y1210568D03*
Y1214838D03*
X914637Y1210568D03*
Y1214838D03*
X70947Y1201565D03*
Y1205835D03*
X1822594Y1211054D03*
Y1215324D03*
G54D82*
X665748Y1101376D03*
X658268D03*
X320866Y1221062D03*
X313385Y1209842D03*
X320866Y1213582D03*
X324606Y1221062D03*
X313385Y1217322D03*
X317125Y1236023D03*
X313385Y1224803D03*
X324606Y1228543D03*
X317125Y1232283D03*
X313385Y1228543D03*
X320866D03*
X324606Y1239763D03*
X313385Y1247243D03*
X320866D03*
X317125Y1250984D03*
X320866Y1239763D03*
X313385Y1243503D03*
X324606Y1247243D03*
X317125Y1254724D03*
X320866Y1198621D03*
X313385Y1202362D03*
X324606Y1198621D03*
X317125Y1202362D03*
X320866Y1206102D03*
X324606D03*
X317125Y1217322D03*
Y1209842D03*
X324606Y1213582D03*
X305905Y1224803D03*
X302165Y1236023D03*
X294685Y1250984D03*
X298425Y1247243D03*
X309645Y1250984D03*
X298425Y1243503D03*
X305905D03*
Y1247243D03*
X302165Y1250984D03*
X294685Y1254724D03*
X309645D03*
X302165D03*
X298425Y1213582D03*
X305905Y1209842D03*
Y1217322D03*
X302165Y1209842D03*
X298425Y1206102D03*
X302165Y1217322D03*
Y1232283D03*
X309645D03*
X294685Y1236023D03*
X298425Y1224803D03*
X294685Y1232283D03*
X298425Y1228543D03*
X309645Y1236023D03*
X305905Y1228543D03*
X298425Y1198621D03*
X305905Y1202362D03*
X302165D03*
X290944Y1247243D03*
Y1243503D03*
X294685Y1213582D03*
Y1206102D03*
X290944Y1224803D03*
Y1228543D03*
X294685Y1198621D03*
X219881Y1232283D03*
Y1236023D03*
X223622Y1224803D03*
X227362Y1232283D03*
X223622Y1228543D03*
X227362Y1236023D03*
Y1093897D03*
X219881D03*
X231102Y1101376D03*
X219881Y1097637D03*
X223621Y1101376D03*
Y1105117D03*
X227362Y1097637D03*
X231102Y1105117D03*
X204921Y1232283D03*
X201181Y1224803D03*
X212401Y1232283D03*
X208661Y1228543D03*
X212401Y1236023D03*
X216141Y1224803D03*
X208661D03*
X201181Y1228543D03*
X216141D03*
X204921Y1236023D03*
Y1097637D03*
X216141Y1101376D03*
X208661D03*
X212401Y1097637D03*
X208661Y1105117D03*
X216141D03*
X201181Y1101376D03*
Y1105117D03*
X212401Y1093897D03*
X204921D03*
X197440Y1236023D03*
X186220Y1224803D03*
X193700Y1228543D03*
X197440Y1232283D03*
X189960Y1236023D03*
X186220Y1228543D03*
X193700Y1224803D03*
X189960Y1232283D03*
X197440Y1093897D03*
X189960D03*
X193700Y1105117D03*
X189960Y1097637D03*
X186220Y1105117D03*
X197440Y1097637D03*
X193700Y1101376D03*
X186220D03*
X178740Y1228543D03*
X171259Y1224803D03*
X182480Y1236023D03*
Y1232283D03*
X174999D03*
X171259Y1228543D03*
X178740Y1224803D03*
X174999Y1236023D03*
Y1093897D03*
X182480D03*
Y1097637D03*
X174999D03*
X178740Y1101376D03*
Y1105117D03*
X669488Y1093897D03*
X639567D03*
X635827Y1101376D03*
Y1105117D03*
X639567Y1097637D03*
X632086D03*
X669488D03*
X650787Y1101376D03*
X647047Y1097637D03*
X643307Y1101376D03*
Y1105117D03*
X650787D03*
X662008Y1093897D03*
Y1097637D03*
X658268Y1105117D03*
X632086Y1093897D03*
X1550000Y1105116D03*
X1564960D03*
X1557480D03*
X1572441D03*
X1579921D03*
X1594881D03*
X1587401D03*
X1602362D03*
X1535039Y1187401D03*
Y1194881D03*
Y1202362D03*
Y1217322D03*
Y1209842D03*
X1538779Y1187401D03*
Y1194881D03*
Y1202362D03*
Y1217322D03*
Y1209842D03*
X1546259Y1191141D03*
X1542519D03*
Y1198621D03*
X1546259D03*
X1542519Y1206102D03*
X1546259D03*
X602165Y1228543D03*
X665748Y1105117D03*
X620866Y1187401D03*
Y1202362D03*
Y1194881D03*
Y1209842D03*
X624606Y1187401D03*
X632086Y1206102D03*
X628346D03*
X632086Y1198621D03*
X628346D03*
X624606Y1202362D03*
Y1194881D03*
X628346Y1191141D03*
X632086D03*
Y1213582D03*
X628346D03*
X624606Y1209842D03*
X620866Y1217322D03*
X624606D03*
X1516338Y1228543D03*
X647047Y1093897D03*
X654527Y1097637D03*
Y1093897D03*
X602165Y1239763D03*
X684449Y1097637D03*
Y1093897D03*
X1527559Y1224803D03*
X676968Y1097637D03*
Y1093897D03*
X688189Y1105117D03*
Y1101376D03*
X680708Y1105117D03*
Y1101376D03*
X673228Y1105117D03*
Y1101376D03*
X1516338Y1239763D03*
X1085432Y1224803D03*
Y1228543D03*
X1089172Y1232283D03*
Y1236023D03*
X1092913Y1224803D03*
Y1228543D03*
X1100393Y1224803D03*
Y1228543D03*
X1104133Y1236023D03*
Y1232283D03*
X1107873Y1228543D03*
Y1224803D03*
X1096653Y1232283D03*
Y1236023D03*
X1115354Y1224803D03*
Y1228543D03*
X1119094Y1236023D03*
Y1232283D03*
X1122834Y1228543D03*
Y1224803D03*
X1126574Y1232283D03*
Y1236023D03*
X1111613Y1232283D03*
Y1236023D03*
X1130314Y1224803D03*
Y1228543D03*
X1141535Y1236023D03*
Y1232283D03*
X1134054Y1236023D03*
Y1232283D03*
X1137795Y1228543D03*
Y1224803D03*
X1205117Y1228543D03*
Y1224803D03*
Y1243503D03*
Y1247243D03*
X1212598Y1224803D03*
Y1228543D03*
X1220078Y1224803D03*
Y1228543D03*
X1216338Y1232283D03*
Y1236023D03*
X1223818D03*
Y1232283D03*
X1208858Y1236023D03*
Y1232283D03*
X1220078Y1243503D03*
Y1247243D03*
X1223818Y1250984D03*
Y1254724D03*
X1216338D03*
Y1250984D03*
X1212598Y1247243D03*
Y1243503D03*
X1208858Y1250984D03*
Y1254724D03*
X1227558Y1224803D03*
Y1228543D03*
X1235039D03*
X1238779D03*
X1231298Y1232283D03*
Y1236023D03*
X1238779Y1239763D03*
X1235039D03*
X1238779Y1247243D03*
X1235039D03*
X1231298Y1250984D03*
Y1254724D03*
X1227558Y1247243D03*
Y1243503D03*
X1220078Y1202362D03*
X1216338D03*
X1212598Y1206102D03*
Y1198621D03*
X1208858Y1206102D03*
Y1198621D03*
X1220078Y1217322D03*
X1216338D03*
X1212598Y1213582D03*
X1216338Y1209842D03*
X1220078D03*
X1208858Y1213582D03*
X1238779Y1198621D03*
X1235039D03*
X1231298Y1202362D03*
X1227558D03*
X1235039Y1206102D03*
X1238779D03*
Y1213582D03*
X1235039D03*
X1238779Y1221062D03*
X1235039D03*
X1231298Y1217322D03*
X1227558D03*
Y1209842D03*
X1231298D03*
X1089172Y1097637D03*
Y1093897D03*
X1092913Y1101376D03*
X1104133Y1093897D03*
Y1097637D03*
X1107873Y1101376D03*
X1100393D03*
X1096653Y1097637D03*
Y1093897D03*
X1126574D03*
Y1097637D03*
X1119094Y1093897D03*
Y1097637D03*
X1115354Y1101376D03*
X1122834D03*
X1111613Y1097637D03*
Y1093897D03*
X1141535Y1097637D03*
Y1093897D03*
X1134054Y1097637D03*
Y1093897D03*
X1137794Y1101376D03*
X1130314D03*
X1145275D03*
X1092913Y1105116D03*
X1107873D03*
X1100393D03*
X1115354D03*
X1122834D03*
X1137794D03*
X1130314D03*
X1145275D03*
X1561220Y1093897D03*
Y1097637D03*
X1564960Y1101376D03*
X1557480D03*
X1553740Y1097637D03*
Y1093897D03*
X1583661D03*
Y1097637D03*
X1576181Y1093897D03*
Y1097637D03*
X1572441Y1101376D03*
X1579921D03*
X1568700Y1097637D03*
Y1093897D03*
X1598622Y1097637D03*
Y1093897D03*
X1591141Y1097637D03*
Y1093897D03*
X1594881Y1101376D03*
X1587401D03*
X1602362D03*
X1546259Y1097637D03*
Y1093897D03*
X1550000Y1101376D03*
X1527559Y1228543D03*
X1535039Y1224803D03*
Y1228543D03*
X1523819Y1232283D03*
Y1236023D03*
X1531299D03*
Y1232283D03*
X1520078Y1228543D03*
Y1239763D03*
X1542519Y1213582D03*
X1546259D03*
X1538779Y1232283D03*
Y1236023D03*
X1542519Y1224803D03*
Y1228543D03*
X1546259Y1232283D03*
Y1236023D03*
Y1250984D03*
Y1254724D03*
X1542519Y1247243D03*
Y1243503D03*
X1550000Y1224803D03*
Y1228543D03*
Y1243503D03*
Y1247243D03*
X1557480Y1224803D03*
Y1228543D03*
X1561220Y1236023D03*
Y1232283D03*
X1564960Y1228543D03*
Y1224803D03*
X1553740Y1232283D03*
Y1236023D03*
X1557480Y1243503D03*
Y1247243D03*
X1561220Y1254724D03*
Y1250984D03*
X1564960Y1247243D03*
Y1243503D03*
X1553740Y1250984D03*
Y1254724D03*
X1568700Y1232283D03*
Y1236023D03*
Y1250984D03*
Y1254724D03*
X1632283Y1224803D03*
Y1228543D03*
Y1247243D03*
Y1243503D03*
X1636023Y1236023D03*
Y1232283D03*
X1639763Y1224803D03*
Y1228543D03*
X1643504Y1236023D03*
Y1232283D03*
X1647244Y1228543D03*
Y1224803D03*
X1636023Y1254724D03*
Y1250984D03*
X1639763Y1243503D03*
Y1247243D03*
X1643504Y1250984D03*
Y1254724D03*
X1647244Y1247243D03*
Y1243503D03*
X1654724Y1224803D03*
Y1228543D03*
X1658464Y1232283D03*
Y1236023D03*
X1650984D03*
Y1232283D03*
X1654724Y1247243D03*
X1658464Y1254724D03*
Y1250984D03*
X1654724Y1243503D03*
X1650984Y1254724D03*
Y1250984D03*
X605905Y1228543D03*
Y1239763D03*
X617126Y1232283D03*
Y1236023D03*
X609646D03*
Y1232283D03*
X620866Y1228543D03*
Y1224803D03*
X613386Y1228543D03*
Y1224803D03*
X639567Y1236023D03*
Y1232283D03*
X632086Y1236023D03*
Y1232283D03*
X635827Y1228543D03*
Y1224803D03*
X628346Y1228543D03*
Y1224803D03*
X624606Y1236023D03*
Y1232283D03*
X639567Y1254724D03*
Y1250984D03*
X628346Y1243503D03*
Y1247243D03*
X632086Y1254724D03*
Y1250984D03*
X635827Y1247243D03*
Y1243503D03*
X654527Y1236023D03*
Y1232283D03*
X650787Y1224803D03*
Y1228543D03*
X647047Y1232283D03*
Y1236023D03*
X643307Y1228543D03*
Y1224803D03*
X654527Y1254724D03*
Y1250984D03*
X650787Y1243503D03*
Y1247243D03*
X647047Y1250984D03*
Y1254724D03*
X643307Y1247243D03*
Y1243503D03*
X718110Y1228543D03*
Y1224803D03*
Y1243503D03*
Y1247243D03*
X733071Y1224803D03*
Y1228543D03*
X736811Y1232283D03*
Y1236023D03*
X729331Y1232283D03*
Y1236023D03*
X725590Y1228543D03*
Y1224803D03*
X721850Y1232283D03*
Y1236023D03*
X733071Y1243503D03*
Y1247243D03*
X736811Y1250984D03*
Y1254724D03*
X729331D03*
Y1250984D03*
X725590Y1247243D03*
Y1243503D03*
X721850Y1250984D03*
Y1254724D03*
X744291Y1236023D03*
Y1232283D03*
X740551Y1228543D03*
Y1224803D03*
Y1243503D03*
X744291Y1250984D03*
Y1254724D03*
X740551Y1247243D03*
G54D80*
X970071Y1409152D03*
Y1365652D03*
G54D73*
X743337Y374862D03*
G54D66*
X1819042Y-27188D03*
Y-37188D03*
Y-47188D03*
X1753686Y-85978D03*
Y-75978D03*
Y-65978D03*
X1564906Y-27086D03*
Y-47086D03*
Y-37086D03*
X1574906Y-66006D03*
Y-86006D03*
Y-76006D03*
X1534542Y-27058D03*
Y-37058D03*
Y-47058D03*
X1499186Y-65978D03*
Y-75978D03*
Y-85978D03*
X1280406Y-26956D03*
Y-46956D03*
Y-36956D03*
X1320406Y-86006D03*
Y-66006D03*
Y-76006D03*
X1248042Y-26928D03*
X1242686Y-65978D03*
Y-75978D03*
Y-85978D03*
X993906Y-26826D03*
Y-46826D03*
Y-36826D03*
X1063906Y-66006D03*
Y-86006D03*
Y-76006D03*
X964542Y-26798D03*
Y-36798D03*
X939542D03*
Y-26798D03*
X989386Y-65978D03*
Y-75978D03*
X964386D03*
Y-65978D03*
X710406Y-26826D03*
Y-36826D03*
X735406D03*
Y-26826D03*
X830406Y-66006D03*
Y-76006D03*
X855406D03*
Y-66006D03*
X1248042Y-36928D03*
Y-46928D03*
X1018906Y-36826D03*
Y-46826D03*
X1217686Y-65978D03*
Y-75978D03*
X1305406Y-36956D03*
Y-46956D03*
Y-26956D03*
X1018906Y-26826D03*
X1217686Y-85978D03*
X1223042Y-26928D03*
Y-36928D03*
X1088906Y-76006D03*
Y-86006D03*
X1345406D03*
Y-76006D03*
Y-66006D03*
X1088906D03*
X1223042Y-46928D03*
X1474186Y-65978D03*
Y-75978D03*
Y-85978D03*
X1509542Y-27058D03*
Y-37058D03*
Y-47058D03*
X1794042Y-27188D03*
Y-37188D03*
Y-47188D03*
X1728686Y-65978D03*
Y-75978D03*
Y-85978D03*
X1589906Y-37086D03*
Y-47086D03*
Y-27086D03*
X1599906Y-76006D03*
Y-86006D03*
Y-66006D03*
G54D79*
X909360Y230906D03*
Y274606D03*
G54D74*
X1729390Y144095D03*
X1627028D03*
X1169941D03*
X1067579D03*
X965217D03*
X815217D03*
G54D72*
X640522Y630650D03*
X1657510Y374862D03*
X1554695Y630650D03*
X1200423Y374862D03*
X1097608Y630650D03*
X286250Y374862D03*
X183435Y630650D03*
G54D78*
X51043Y144095D03*
X57933Y66811D03*
X153405Y144095D03*
X160295Y66811D03*
X255767Y144095D03*
X262657Y66811D03*
X358129Y144095D03*
X365019Y66811D03*
X508130Y144095D03*
X515020Y66811D03*
X610492Y144095D03*
X617382Y66811D03*
X712854Y144095D03*
X719744Y66811D03*
X822106D03*
X972106D03*
X1074468D03*
X1176830D03*
X1272302Y144095D03*
X1279192Y66811D03*
X1422303Y144095D03*
X1429193Y66811D03*
X1524665Y144095D03*
X1531555Y66811D03*
X1633917D03*
X1736279D03*
G54D71*
X736447Y630650D03*
X1650620D03*
X1561585Y374862D03*
X1193533Y630650D03*
X1104498Y374862D03*
X279360Y630650D03*
X190325Y374862D03*
G54D70*
X1817323Y56693D03*
G54D69*
X924650Y1326119D03*
X370202Y1313064D03*
X559070Y686509D03*
X561570Y694509D03*
X559070Y702509D03*
X561570Y710509D03*
X559070Y718509D03*
X460950Y326485D03*
X463950Y334359D03*
X460950Y342233D03*
X463950Y350107D03*
X937000Y313983D03*
X66856Y105949D03*
X169218D03*
X271580D03*
X373942D03*
X893284Y235040D03*
X899352Y310261D03*
X1079748Y321042D03*
X1209184Y461917D03*
X1302896Y342096D03*
X1438116Y105949D03*
X1540478D03*
X1642840D03*
X1745202D03*
X1089096Y543562D03*
X1754906Y822634D03*
X917882Y326517D03*
X212980Y485254D03*
X205680Y478168D03*
X138290Y485260D03*
X148692Y478199D03*
X788482Y476118D03*
X778080Y483179D03*
X721092Y483210D03*
X713792Y476124D03*
X1245568Y476118D03*
X1235166Y483179D03*
X1178178Y483210D03*
X1170878Y476124D03*
X1584240Y485254D03*
X1576940Y478168D03*
X1519952Y478199D03*
X1509550Y485260D03*
X35688Y127128D03*
X28388Y120042D03*
Y134215D03*
X35688Y112955D03*
X130750Y120042D03*
Y134215D03*
X148692Y421047D03*
X138290Y413987D03*
X140690Y399813D03*
X148692Y406874D03*
Y392701D03*
X138050Y127128D03*
Y112955D03*
X138290Y471087D03*
Y442333D03*
Y428160D03*
X148692Y435221D03*
X205680Y399782D03*
X212980Y406868D03*
Y392695D03*
Y471081D03*
Y435215D03*
X205680Y442302D03*
Y428128D03*
Y413955D03*
X212980Y421041D03*
X233112Y134215D03*
Y120042D03*
X240412Y127128D03*
Y112955D03*
X342774Y127128D03*
X335474Y134215D03*
Y120042D03*
X342774Y112955D03*
X533092Y127096D03*
Y112923D03*
X543494Y134209D03*
Y120035D03*
X635454Y127096D03*
Y112923D03*
X645856Y134209D03*
Y120035D03*
X748218Y134209D03*
X737816Y127096D03*
X748218Y120035D03*
X737816Y112923D03*
X721092Y469037D03*
X778080Y469006D03*
X840178Y127096D03*
Y112923D03*
X850580Y134209D03*
Y120035D03*
X990178Y127096D03*
Y112923D03*
X1000580Y134209D03*
Y120035D03*
X1092540Y127096D03*
Y112923D03*
X1102942Y134209D03*
Y120035D03*
X1178178Y469037D03*
X1205304Y134209D03*
X1194902Y127096D03*
X1205304Y120035D03*
X1194902Y112923D03*
X1235166Y469006D03*
X1297264Y127096D03*
Y112923D03*
X1307666Y134209D03*
Y120035D03*
X1399648Y120042D03*
Y134215D03*
X1406948Y127128D03*
Y112955D03*
X1509310D03*
X1509550Y428160D03*
Y413987D03*
X1511950Y399813D03*
X1502010Y134215D03*
X1509310Y127128D03*
X1502010Y120042D03*
X1519952Y421047D03*
Y406874D03*
Y392701D03*
X1509550Y471087D03*
Y442333D03*
X1519952Y435221D03*
X1576940Y442302D03*
Y428128D03*
Y413955D03*
Y399782D03*
X1584240Y421041D03*
Y406868D03*
Y392695D03*
X1604372Y134215D03*
X1611672Y127128D03*
X1604372Y120042D03*
X1611672Y112955D03*
X1584240Y471081D03*
Y435215D03*
X1706734Y134215D03*
Y120042D03*
X1714034Y127128D03*
Y112955D03*
X148692Y536506D03*
Y522333D03*
X138290Y515221D03*
X148692Y492373D03*
X138290Y529394D03*
X205680Y492341D03*
Y536475D03*
X212980Y529388D03*
Y515215D03*
X205680Y522302D03*
X713792Y612817D03*
Y598644D03*
Y584471D03*
Y570297D03*
Y534431D03*
Y520258D03*
Y490297D03*
X721092Y591557D03*
Y577384D03*
Y563210D03*
Y527344D03*
Y513171D03*
Y605730D03*
X778080Y563179D03*
Y527313D03*
Y513139D03*
Y591525D03*
Y605699D03*
Y577352D03*
X788482Y570291D03*
Y534425D03*
Y520252D03*
Y490291D03*
Y612811D03*
Y598638D03*
Y584465D03*
X1170878Y612817D03*
Y598644D03*
Y584471D03*
Y570297D03*
Y534431D03*
Y520258D03*
Y490297D03*
X1178178Y563210D03*
Y527344D03*
Y513171D03*
Y605730D03*
Y591557D03*
Y577384D03*
X1235166Y527313D03*
Y513139D03*
Y605699D03*
Y591525D03*
Y577352D03*
Y563179D03*
X1245568Y570291D03*
Y534425D03*
Y520252D03*
Y490291D03*
Y612811D03*
Y598638D03*
Y584465D03*
X1509550Y529394D03*
Y515221D03*
X1519952Y536506D03*
Y522333D03*
Y492373D03*
X1576940Y536475D03*
Y522302D03*
Y492341D03*
X1584240Y529388D03*
Y515215D03*
X7982Y1527335D03*
G54D67*
X1592187Y-71006D03*
Y-81006D03*
X1582187Y-32086D03*
Y-42086D03*
X1736405Y-80978D03*
Y-70978D03*
X1801761Y-42188D03*
Y-32188D03*
X1517261Y-42058D03*
Y-32058D03*
X1481905Y-80978D03*
Y-70978D03*
X1230761Y-41928D03*
X1081187Y-71006D03*
X1337687D03*
Y-81006D03*
X1081187D03*
X1230761Y-31928D03*
X1225405Y-80978D03*
X1011187Y-31826D03*
X1297687Y-31956D03*
Y-41956D03*
X1225405Y-70978D03*
X1011187Y-41826D03*
X213969Y1460153D03*
Y1449153D03*
X227249Y1460153D03*
Y1449153D03*
G54D81*
X1817323Y1567323D03*
G54D68*
X1009333Y1344993D03*
X1015659Y681354D03*
X933725Y587636D03*
X933741Y596387D03*
X486837Y703006D03*
X394883Y340077D03*
X217907Y1428752D03*
X415203Y1497818D03*
X397267Y1516347D03*
X295011Y461917D03*
X523943Y105949D03*
X626305D03*
X728667D03*
X752097Y461917D03*
X831029Y105949D03*
X981029D03*
X1083391D03*
X1080351Y329955D03*
X1185753Y105949D03*
X1288115D03*
X1366535Y353200D03*
Y337452D03*
X1363535Y345326D03*
Y329578D03*
X1666271Y461919D03*
X174923Y543562D03*
X632009D03*
X1546183Y543564D03*
X385091Y1299153D03*
X454385Y1303545D03*
X940997Y333613D03*
X256705Y476124D03*
X264005Y483210D03*
X605779Y478199D03*
X595377Y485260D03*
X331395Y476118D03*
X320993Y483179D03*
X670067Y485254D03*
X662767Y478168D03*
X1127153Y485254D03*
X1119853Y478168D03*
X1062865Y478199D03*
X1052463Y485260D03*
X1702655Y476118D03*
X1692253Y483179D03*
X1635265Y483210D03*
X1627965Y476124D03*
X76005Y127096D03*
Y112923D03*
X86407Y120035D03*
Y134209D03*
X178367Y127096D03*
Y112923D03*
X188769Y134209D03*
Y120035D03*
X264005Y469037D03*
X291131Y134209D03*
Y120035D03*
X280729Y127096D03*
Y112923D03*
X320993Y469005D03*
X393493Y134209D03*
X383091Y127096D03*
X393493Y120035D03*
X383091Y112923D03*
X485475Y134215D03*
Y120042D03*
X492775Y127128D03*
Y112955D03*
X587837Y134215D03*
Y120042D03*
X597777Y399813D03*
X595137Y127128D03*
Y112955D03*
X595377Y471087D03*
Y442333D03*
Y428160D03*
Y413987D03*
X605779Y435221D03*
Y421047D03*
Y406874D03*
Y392701D03*
X670067Y435215D03*
X662767Y442302D03*
Y428128D03*
Y413955D03*
X670067Y421041D03*
X662767Y399782D03*
X670067Y406868D03*
Y392695D03*
Y471081D03*
X690199Y120042D03*
X697499Y127128D03*
X690199Y134215D03*
X697499Y112955D03*
X799861D03*
Y127128D03*
X792561Y120042D03*
Y134215D03*
X949861Y112955D03*
X942561Y120042D03*
Y134215D03*
X949861Y127128D03*
X1044923Y134215D03*
X1052223Y127128D03*
X1044923Y120042D03*
X1052223Y112955D03*
X1052463Y471087D03*
Y442333D03*
Y428160D03*
Y413987D03*
X1054863Y399813D03*
X1062865Y435221D03*
Y421047D03*
Y406874D03*
Y392701D03*
X1119853Y399782D03*
Y442302D03*
Y428128D03*
Y413955D03*
X1154585Y112955D03*
X1127153Y471081D03*
Y435215D03*
Y421041D03*
Y406868D03*
Y392695D03*
X1154585Y127128D03*
X1147285Y134215D03*
Y120042D03*
X1249647Y134215D03*
Y120042D03*
X1256947Y127128D03*
Y112955D03*
X1447265Y127096D03*
Y112923D03*
X1457667Y134209D03*
Y120035D03*
X1560029Y134209D03*
X1549627Y127096D03*
X1560029Y120035D03*
X1549627Y112923D03*
X1651989Y127096D03*
Y112923D03*
X1635265Y469037D03*
X1662391Y134209D03*
Y120035D03*
X1692253Y469006D03*
X1754351Y127096D03*
Y112923D03*
X1764753Y134209D03*
Y120035D03*
X264005Y513171D03*
X256705Y520258D03*
Y490297D03*
Y612817D03*
X264005Y591557D03*
Y605730D03*
X256705Y598644D03*
X264005Y577384D03*
X256705Y584471D03*
Y570297D03*
X264005Y563210D03*
X256705Y534431D03*
X264005Y527344D03*
X320993Y513139D03*
Y591525D03*
Y605699D03*
Y577352D03*
Y563179D03*
Y527313D03*
X331395Y490291D03*
Y612811D03*
Y598638D03*
Y584465D03*
Y570291D03*
Y534425D03*
Y520252D03*
X595377Y529394D03*
Y515221D03*
X605779Y536506D03*
Y522333D03*
Y492373D03*
X670067Y529388D03*
X662767Y536475D03*
Y522302D03*
X670067Y515215D03*
X662767Y492341D03*
X1052463Y529394D03*
Y515221D03*
X1062865Y536506D03*
Y522333D03*
Y492373D03*
X1119853Y536475D03*
Y522302D03*
Y492341D03*
X1127153Y529388D03*
Y515215D03*
X1627965Y584471D03*
Y570297D03*
Y534431D03*
Y520258D03*
Y490297D03*
Y612817D03*
Y598644D03*
X1635265Y527344D03*
Y513171D03*
Y605730D03*
Y591557D03*
Y577384D03*
Y563210D03*
X1692253Y605699D03*
Y591525D03*
Y577352D03*
Y563179D03*
Y527313D03*
Y513139D03*
X1702655Y534425D03*
Y520252D03*
Y490291D03*
Y612811D03*
Y598638D03*
Y584465D03*
Y570291D03*
G54D77*
X770472Y1490945D03*
X820079Y388583D03*
X1020866D03*
X1070472Y1490945D03*
G54D65*
X19685Y-83298D03*
X1821260D03*
X26789Y1373669D03*
X1796847Y1517889D03*
X1809883Y120792D03*
X184851Y334492D03*
X19685Y1801195D03*
X1821260D03*
G54D75*
X1030905Y1066535D03*
Y1263386D03*
X810038Y1066535D03*
Y1263386D03*
X573818Y1066535D03*
Y1263386D03*
X352952Y1066535D03*
Y1263386D03*
X116731Y1066535D03*
Y1263386D03*
X1724212Y1066535D03*
Y1263386D03*
X1487991Y1066535D03*
Y1263386D03*
X1267125Y1066535D03*
Y1263386D03*
%LPC*%
G75*
G36*
G01X175799Y1093897D02*
G02I-800J0D01*
G37*
G36*
G01Y1097637D02*
G02I-800J0D01*
G37*
G36*
G01X179540Y1101376D02*
G02I-800J0D01*
G37*
G36*
G01Y1105117D02*
G02I-800J0D01*
G37*
G36*
G01Y1228543D02*
G02I-800J0D01*
G37*
G36*
G01X172059Y1224803D02*
G02I-800J0D01*
G37*
G36*
G01X175799Y1232283D02*
G02I-800J0D01*
G37*
G36*
G01X172059Y1228543D02*
G02I-800J0D01*
G37*
G36*
G01X179540Y1224803D02*
G02I-800J0D01*
G37*
G36*
G01X175799Y1236023D02*
G02I-800J0D01*
G37*
G36*
G01X194500Y1105117D02*
G02I-800J0D01*
G37*
G36*
G01X198240Y1093897D02*
G02I-800J0D01*
G37*
G36*
G01X190760Y1097637D02*
G02I-800J0D01*
G37*
G36*
G01X187020Y1105117D02*
G02I-800J0D01*
G37*
G36*
G01X198240Y1097637D02*
G02I-800J0D01*
G37*
G36*
G01X183280Y1093897D02*
G02I-800J0D01*
G37*
G36*
G01Y1097637D02*
G02I-800J0D01*
G37*
G36*
G01X194500Y1101376D02*
G02I-800J0D01*
G37*
G36*
G01X187020D02*
G02I-800J0D01*
G37*
G36*
G01X190760Y1093897D02*
G02I-800J0D01*
G37*
G36*
G01X183280Y1236023D02*
G02I-800J0D01*
G37*
G36*
G01X198240D02*
G02I-800J0D01*
G37*
G36*
G01X187020Y1224803D02*
G02I-800J0D01*
G37*
G36*
G01X183280Y1232283D02*
G02I-800J0D01*
G37*
G36*
G01X194500Y1228543D02*
G02I-800J0D01*
G37*
G36*
G01X198240Y1232283D02*
G02I-800J0D01*
G37*
G36*
G01X190760Y1236023D02*
G02I-800J0D01*
G37*
G36*
G01X187020Y1228543D02*
G02I-800J0D01*
G37*
G36*
G01X194500Y1224803D02*
G02I-800J0D01*
G37*
G36*
G01X190760Y1232283D02*
G02I-800J0D01*
G37*
G36*
G01X205721Y1097637D02*
G02I-800J0D01*
G37*
G36*
G01X209461Y1101376D02*
G02I-800J0D01*
G37*
G36*
G01X213201Y1097637D02*
G02I-800J0D01*
G37*
G36*
G01X209461Y1105117D02*
G02I-800J0D01*
G37*
G36*
G01X213201Y1093897D02*
G02I-800J0D01*
G37*
G36*
G01X201981Y1101376D02*
G02I-800J0D01*
G37*
G36*
G01X205721Y1093897D02*
G02I-800J0D01*
G37*
G36*
G01X201981Y1105117D02*
G02I-800J0D01*
G37*
G36*
G01X205721Y1232283D02*
G02I-800J0D01*
G37*
G36*
G01X201981Y1224803D02*
G02I-800J0D01*
G37*
G36*
G01X213201Y1232283D02*
G02I-800J0D01*
G37*
G36*
G01X209461Y1228543D02*
G02I-800J0D01*
G37*
G36*
G01X213201Y1236023D02*
G02I-800J0D01*
G37*
G36*
G01X209461Y1224803D02*
G02I-800J0D01*
G37*
G36*
G01X201981Y1228543D02*
G02I-800J0D01*
G37*
G36*
G01X205721Y1236023D02*
G02I-800J0D01*
G37*
G36*
G01X216941Y1101376D02*
G02I-800J0D01*
G37*
G36*
G01X228162Y1093897D02*
G02I-800J0D01*
G37*
G36*
G01X220681Y1097637D02*
G02I-800J0D01*
G37*
G36*
G01X224421Y1101376D02*
G02I-800J0D01*
G37*
G36*
G01Y1105117D02*
G02I-800J0D01*
G37*
G36*
G01X216941D02*
G02I-800J0D01*
G37*
G36*
G01X220681Y1093897D02*
G02I-800J0D01*
G37*
G36*
G01X228162Y1097637D02*
G02I-800J0D01*
G37*
G36*
G01X220681Y1232283D02*
G02I-800J0D01*
G37*
G36*
G01Y1236023D02*
G02I-800J0D01*
G37*
G36*
G01X216941Y1224803D02*
G02I-800J0D01*
G37*
G36*
G01X224422D02*
G02I-800J0D01*
G37*
G36*
G01X228162Y1232283D02*
G02I-800J0D01*
G37*
G36*
G01X224422Y1228543D02*
G02I-800J0D01*
G37*
G36*
G01X216941D02*
G02I-800J0D01*
G37*
G36*
G01X228162Y1236023D02*
G02I-800J0D01*
G37*
G36*
G01X231902Y1101376D02*
G02I-800J0D01*
G37*
G36*
G01Y1105117D02*
G02I-800J0D01*
G37*
G36*
G01X295485Y1198621D02*
G02I-800J0D01*
G37*
G36*
G01Y1213582D02*
G02I-800J0D01*
G37*
G36*
G01Y1206102D02*
G02I-800J0D01*
G37*
G36*
G01Y1236023D02*
G02I-800J0D01*
G37*
G36*
G01X291744Y1224803D02*
G02I-800J0D01*
G37*
G36*
G01X295485Y1232283D02*
G02I-800J0D01*
G37*
G36*
G01X291744Y1228543D02*
G02I-800J0D01*
G37*
G36*
G01X295485Y1250984D02*
G02I-800J0D01*
G37*
G36*
G01X291744Y1247243D02*
G02I-800J0D01*
G37*
G36*
G01Y1243503D02*
G02I-800J0D01*
G37*
G36*
G01X295485Y1254724D02*
G02I-800J0D01*
G37*
G36*
G01X299225Y1198621D02*
G02I-800J0D01*
G37*
G36*
G01X306705Y1202362D02*
G02I-800J0D01*
G37*
G36*
G01X302965D02*
G02I-800J0D01*
G37*
G36*
G01X299225Y1213582D02*
G02I-800J0D01*
G37*
G36*
G01X306705Y1209842D02*
G02I-800J0D01*
G37*
G36*
G01Y1217322D02*
G02I-800J0D01*
G37*
G36*
G01X302965Y1209842D02*
G02I-800J0D01*
G37*
G36*
G01X299225Y1206102D02*
G02I-800J0D01*
G37*
G36*
G01X302965Y1217322D02*
G02I-800J0D01*
G37*
G36*
G01Y1232283D02*
G02I-800J0D01*
G37*
G36*
G01X310445D02*
G02I-800J0D01*
G37*
G36*
G01X299225Y1224803D02*
G02I-800J0D01*
G37*
G36*
G01Y1228543D02*
G02I-800J0D01*
G37*
G36*
G01X310445Y1236023D02*
G02I-800J0D01*
G37*
G36*
G01X306705Y1228543D02*
G02I-800J0D01*
G37*
G36*
G01Y1224803D02*
G02I-800J0D01*
G37*
G36*
G01X302965Y1236023D02*
G02I-800J0D01*
G37*
G36*
G01X299225Y1247243D02*
G02I-800J0D01*
G37*
G36*
G01X310445Y1250984D02*
G02I-800J0D01*
G37*
G36*
G01X299225Y1243503D02*
G02I-800J0D01*
G37*
G36*
G01X306705D02*
G02I-800J0D01*
G37*
G36*
G01Y1247243D02*
G02I-800J0D01*
G37*
G36*
G01X302965Y1250984D02*
G02I-800J0D01*
G37*
G36*
G01X310445Y1254724D02*
G02I-800J0D01*
G37*
G36*
G01X302965D02*
G02I-800J0D01*
G37*
G36*
G01X321666Y1198621D02*
G02I-800J0D01*
G37*
G36*
G01X314185Y1202362D02*
G02I-800J0D01*
G37*
G36*
G01X325406Y1198621D02*
G02I-800J0D01*
G37*
G36*
G01X317925Y1202362D02*
G02I-800J0D01*
G37*
G36*
G01Y1217322D02*
G02I-800J0D01*
G37*
G36*
G01Y1209842D02*
G02I-800J0D01*
G37*
G36*
G01X325406Y1213582D02*
G02I-800J0D01*
G37*
G36*
G01X321666Y1221062D02*
G02I-800J0D01*
G37*
G36*
G01X314185Y1209842D02*
G02I-800J0D01*
G37*
G36*
G01X321666Y1206102D02*
G02I-800J0D01*
G37*
G36*
G01Y1213582D02*
G02I-800J0D01*
G37*
G36*
G01X325406Y1221062D02*
G02I-800J0D01*
G37*
G36*
G01Y1206102D02*
G02I-800J0D01*
G37*
G36*
G01X314185Y1217322D02*
G02I-800J0D01*
G37*
G36*
G01X317925Y1236023D02*
G02I-800J0D01*
G37*
G36*
G01X314185Y1224803D02*
G02I-800J0D01*
G37*
G36*
G01X325406Y1228543D02*
G02I-800J0D01*
G37*
G36*
G01X317925Y1232283D02*
G02I-800J0D01*
G37*
G36*
G01X314185Y1228543D02*
G02I-800J0D01*
G37*
G36*
G01X321666D02*
G02I-800J0D01*
G37*
G36*
G01X325406Y1239763D02*
G02I-800J0D01*
G37*
G36*
G01X314185Y1247243D02*
G02I-800J0D01*
G37*
G36*
G01X321666D02*
G02I-800J0D01*
G37*
G36*
G01X317925Y1250984D02*
G02I-800J0D01*
G37*
G36*
G01X321666Y1239763D02*
G02I-800J0D01*
G37*
G36*
G01X314185Y1243503D02*
G02I-800J0D01*
G37*
G36*
G01X325406Y1247243D02*
G02I-800J0D01*
G37*
G36*
G01X317925Y1254724D02*
G02I-800J0D01*
G37*
G36*
G01X602965Y1228543D02*
G02I-800J0D01*
G37*
G36*
G01Y1239763D02*
G02I-800J0D01*
G37*
G36*
G01X621666Y1187401D02*
G02I-800J0D01*
G37*
G36*
G01Y1202362D02*
G02I-800J0D01*
G37*
G36*
G01Y1194881D02*
G02I-800J0D01*
G37*
G36*
G01Y1209842D02*
G02I-800J0D01*
G37*
G36*
G01Y1217322D02*
G02I-800J0D01*
G37*
G36*
G01X606705Y1228543D02*
G02I-800J0D01*
G37*
G36*
G01X621666D02*
G02I-800J0D01*
G37*
G36*
G01Y1224803D02*
G02I-800J0D01*
G37*
G36*
G01X610446Y1232283D02*
G02I-800J0D01*
G37*
G36*
G01X617926Y1236023D02*
G02I-800J0D01*
G37*
G36*
G01X614186Y1228543D02*
G02I-800J0D01*
G37*
G36*
G01X617926Y1232283D02*
G02I-800J0D01*
G37*
G36*
G01X610446Y1236023D02*
G02I-800J0D01*
G37*
G36*
G01X614186Y1224803D02*
G02I-800J0D01*
G37*
G36*
G01X606705Y1239763D02*
G02I-800J0D01*
G37*
G36*
G01X632886Y1097637D02*
G02I-800J0D01*
G37*
G36*
G01X636627Y1105117D02*
G02I-800J0D01*
G37*
G36*
G01X632886Y1093897D02*
G02I-800J0D01*
G37*
G36*
G01X636627Y1101376D02*
G02I-800J0D01*
G37*
G36*
G01X625406Y1187401D02*
G02I-800J0D01*
G37*
G36*
G01X629146Y1191141D02*
G02I-800J0D01*
G37*
G36*
G01X625406Y1194881D02*
G02I-800J0D01*
G37*
G36*
G01X632886Y1191141D02*
G02I-800J0D01*
G37*
G36*
G01X629146Y1198621D02*
G02I-800J0D01*
G37*
G36*
G01X625406Y1202362D02*
G02I-800J0D01*
G37*
G36*
G01X632886Y1198621D02*
G02I-800J0D01*
G37*
G36*
G01X629146Y1206102D02*
G02I-800J0D01*
G37*
G36*
G01X632886D02*
G02I-800J0D01*
G37*
G36*
G01X625406Y1217322D02*
G02I-800J0D01*
G37*
G36*
G01X629146Y1213582D02*
G02I-800J0D01*
G37*
G36*
G01X632886D02*
G02I-800J0D01*
G37*
G36*
G01X625406Y1209842D02*
G02I-800J0D01*
G37*
G36*
G01X629146Y1224803D02*
G02I-800J0D01*
G37*
G36*
G01Y1228543D02*
G02I-800J0D01*
G37*
G36*
G01X636627D02*
G02I-800J0D01*
G37*
G36*
G01X632886Y1232283D02*
G02I-800J0D01*
G37*
G36*
G01Y1236023D02*
G02I-800J0D01*
G37*
G36*
G01X625406Y1232283D02*
G02I-800J0D01*
G37*
G36*
G01Y1236023D02*
G02I-800J0D01*
G37*
G36*
G01X636627Y1224803D02*
G02I-800J0D01*
G37*
G36*
G01Y1243503D02*
G02I-800J0D01*
G37*
G36*
G01X632886Y1250984D02*
G02I-800J0D01*
G37*
G36*
G01X636627Y1247243D02*
G02I-800J0D01*
G37*
G36*
G01X629146Y1243503D02*
G02I-800J0D01*
G37*
G36*
G01Y1247243D02*
G02I-800J0D01*
G37*
G36*
G01X632886Y1254724D02*
G02I-800J0D01*
G37*
G36*
G01X651587Y1105117D02*
G02I-800J0D01*
G37*
G36*
G01X647847Y1093897D02*
G02I-800J0D01*
G37*
G36*
G01X640367Y1097637D02*
G02I-800J0D01*
G37*
G36*
G01X644107Y1105117D02*
G02I-800J0D01*
G37*
G36*
G01X647847Y1097637D02*
G02I-800J0D01*
G37*
G36*
G01X640367Y1093897D02*
G02I-800J0D01*
G37*
G36*
G01X644107Y1101376D02*
G02I-800J0D01*
G37*
G36*
G01X651587D02*
G02I-800J0D01*
G37*
G36*
G01X640367Y1236023D02*
G02I-800J0D01*
G37*
G36*
G01X647847D02*
G02I-800J0D01*
G37*
G36*
G01X640367Y1232283D02*
G02I-800J0D01*
G37*
G36*
G01X644107Y1224803D02*
G02I-800J0D01*
G37*
G36*
G01X647847Y1232283D02*
G02I-800J0D01*
G37*
G36*
G01X644107Y1228543D02*
G02I-800J0D01*
G37*
G36*
G01X651587D02*
G02I-800J0D01*
G37*
G36*
G01Y1224803D02*
G02I-800J0D01*
G37*
G36*
G01X640367Y1250984D02*
G02I-800J0D01*
G37*
G36*
G01X651587Y1247243D02*
G02I-800J0D01*
G37*
G36*
G01Y1243503D02*
G02I-800J0D01*
G37*
G36*
G01X647847Y1250984D02*
G02I-800J0D01*
G37*
G36*
G01X644107Y1247243D02*
G02I-800J0D01*
G37*
G36*
G01Y1243503D02*
G02I-800J0D01*
G37*
G36*
G01X640367Y1254724D02*
G02I-800J0D01*
G37*
G36*
G01X647847D02*
G02I-800J0D01*
G37*
G36*
G01X662808Y1097637D02*
G02I-800J0D01*
G37*
G36*
G01X655327Y1093897D02*
G02I-800J0D01*
G37*
G36*
G01X670288D02*
G02I-800J0D01*
G37*
G36*
G01X666548Y1105117D02*
G02I-800J0D01*
G37*
G36*
G01X655327Y1097637D02*
G02I-800J0D01*
G37*
G36*
G01X662808Y1093897D02*
G02I-800J0D01*
G37*
G36*
G01X670288Y1097637D02*
G02I-800J0D01*
G37*
G36*
G01X666548Y1101376D02*
G02I-800J0D01*
G37*
G36*
G01X659068Y1105117D02*
G02I-800J0D01*
G37*
G36*
G01Y1101376D02*
G02I-800J0D01*
G37*
G36*
G01X655327Y1236023D02*
G02I-800J0D01*
G37*
G36*
G01Y1232283D02*
G02I-800J0D01*
G37*
G36*
G01Y1250984D02*
G02I-800J0D01*
G37*
G36*
G01Y1254724D02*
G02I-800J0D01*
G37*
G36*
G01X674028Y1105117D02*
G02I-800J0D01*
G37*
G36*
G01X685249Y1093897D02*
G02I-800J0D01*
G37*
G36*
G01X677768D02*
G02I-800J0D01*
G37*
G36*
G01X685249Y1097637D02*
G02I-800J0D01*
G37*
G36*
G01X677768D02*
G02I-800J0D01*
G37*
G36*
G01X681508Y1105117D02*
G02I-800J0D01*
G37*
G36*
G01X674028Y1101376D02*
G02I-800J0D01*
G37*
G36*
G01X681508D02*
G02I-800J0D01*
G37*
G36*
G01X688989Y1105117D02*
G02I-800J0D01*
G37*
G36*
G01Y1101376D02*
G02I-800J0D01*
G37*
G36*
G01X718910Y1228543D02*
G02I-800J0D01*
G37*
G36*
G01Y1224803D02*
G02I-800J0D01*
G37*
G36*
G01Y1243503D02*
G02I-800J0D01*
G37*
G36*
G01Y1247243D02*
G02I-800J0D01*
G37*
G36*
G01X726390Y1228543D02*
G02I-800J0D01*
G37*
G36*
G01X733871D02*
G02I-800J0D01*
G37*
G36*
G01X722650Y1236023D02*
G02I-800J0D01*
G37*
G36*
G01X733871Y1224803D02*
G02I-800J0D01*
G37*
G36*
G01X722650Y1232283D02*
G02I-800J0D01*
G37*
G36*
G01X726390Y1224803D02*
G02I-800J0D01*
G37*
G36*
G01X730131Y1236023D02*
G02I-800J0D01*
G37*
G36*
G01Y1232283D02*
G02I-800J0D01*
G37*
G36*
G01Y1250984D02*
G02I-800J0D01*
G37*
G36*
G01X733871Y1247243D02*
G02I-800J0D01*
G37*
G36*
G01X722650Y1250984D02*
G02I-800J0D01*
G37*
G36*
G01X726390Y1243503D02*
G02I-800J0D01*
G37*
G36*
G01X733871D02*
G02I-800J0D01*
G37*
G36*
G01X726390Y1247243D02*
G02I-800J0D01*
G37*
G36*
G01X722650Y1254724D02*
G02I-800J0D01*
G37*
G36*
G01X730131D02*
G02I-800J0D01*
G37*
G36*
G01X745091Y1236023D02*
G02I-800J0D01*
G37*
G36*
G01X737611Y1232283D02*
G02I-800J0D01*
G37*
G36*
G01X745091D02*
G02I-800J0D01*
G37*
G36*
G01X737611Y1236023D02*
G02I-800J0D01*
G37*
G36*
G01X741351Y1224803D02*
G02I-800J0D01*
G37*
G36*
G01Y1228543D02*
G02I-800J0D01*
G37*
G36*
G01Y1243503D02*
G02I-800J0D01*
G37*
G36*
G01Y1247243D02*
G02I-800J0D01*
G37*
G36*
G01X745091Y1250984D02*
G02I-800J0D01*
G37*
G36*
G01X737611D02*
G02I-800J0D01*
G37*
G36*
G01X745091Y1254724D02*
G02I-800J0D01*
G37*
G36*
G01X737611D02*
G02I-800J0D01*
G37*
G36*
G01X940026Y1577634D02*
G03X940910Y1577268I884J885D01*
G01X956342D01*
G02X956484Y1577209I0J-200D01*
G01X959830Y1573863D01*
G02X959889Y1573721I-141J-142D01*
G01Y1543680D01*
G03X960255Y1542796I1251J0D01*
G01X964295Y1538756D01*
G03X965179Y1538390I884J885D01*
G01X1019906D01*
G02X1020048Y1538331I0J-200D01*
G01X1031515Y1526864D01*
G02X1031574Y1526722I-141J-142D01*
G01Y1492904D01*
G02X1031515Y1492762I-200J0D01*
G01X1031368Y1492615D01*
G02X1031226Y1492556I-142J141D01*
G01X947183D01*
G02X947041Y1492615I0J200D01*
G01X944876Y1494780D01*
G03X943992Y1495146I-884J-885D01*
G01X933579D01*
G03X932695Y1494780I0J-1251D01*
G01X917141Y1479226D01*
G03X916775Y1478342I885J-884D01*
G01Y1465020D01*
G02X916716Y1464878I-200J0D01*
G01X914188Y1462350D01*
G03X913822Y1461466I885J-884D01*
G01Y1460928D01*
G02X913763Y1460786I-200J0D01*
G01X913527Y1460550D01*
G03X913161Y1459666I885J-884D01*
G01Y1446448D01*
G02X913102Y1446306I-200J0D01*
G01X912955Y1446159D01*
G02X912813Y1446100I-142J141D01*
G01X900559D01*
G02X900417Y1446159I0J200D01*
G01X900270Y1446306D01*
G02X900211Y1446448I141J142D01*
G01Y1459640D01*
G03X899845Y1460524I-1251J0D01*
G01X899532Y1460837D01*
G02X899473Y1460979I141J142D01*
G01Y1462024D01*
G03X899107Y1462908I-1251J0D01*
G01X894403Y1467612D01*
G02X894344Y1467754I141J142D01*
G01Y1473096D01*
G03X893978Y1473980I-1251J0D01*
G01X888953Y1479005D01*
G03X888069Y1479371I-884J-885D01*
G01X880504D01*
G03X879620Y1479005I0J-1251D01*
G01X872265Y1471650D01*
G03X871899Y1470766I885J-884D01*
G01Y1460991D01*
G02X871840Y1460849I-200J0D01*
G01X871502Y1460511D01*
G03X871136Y1459627I885J-884D01*
G01Y1446423D01*
G02X871077Y1446281I-200J0D01*
G01X870968Y1446172D01*
G02X870826Y1446113I-142J141D01*
G01X858702D01*
G02X858560Y1446172I0J200D01*
G01X858139Y1446593D01*
G02X858080Y1446735I141J142D01*
G01Y1459524D01*
G03X857714Y1460408I-1251J0D01*
G01X853660Y1464462D01*
G03X852776Y1464828I-884J-885D01*
G01X828441D01*
G03X827557Y1464462I0J-1251D01*
G01X827039Y1463944D01*
G03X826673Y1463060I885J-884D01*
G01Y1461847D01*
G02X826614Y1461705I-200J0D01*
G01X826571Y1461662D01*
G02X826429Y1461603I-142J141D01*
G01X825036D01*
G03X824152Y1461237I0J-1251D01*
G01X821533Y1458618D01*
G02X821391Y1458559I-142J141D01*
G01X820451D01*
G03X819567Y1458193I0J-1251D01*
G01X819360Y1457986D01*
G03X818994Y1457102I885J-884D01*
G01Y1446462D01*
G02X818935Y1446320I-200J0D01*
G01X818826Y1446211D01*
G02X818684Y1446152I-142J141D01*
G01X806393D01*
G02X806251Y1446211I0J200D01*
G01X806063Y1446399D01*
G02X806004Y1446541I141J142D01*
G01Y1459828D01*
G02X806063Y1459970I200J0D01*
G01X806195Y1460102D01*
G03X806561Y1460986I-885J884D01*
G01Y1474310D01*
G02X806615Y1474447I200J0D01*
G03X806950Y1475299I-916J852D01*
G01Y1523715D01*
G02X807009Y1523857I200J0D01*
G01X816830Y1533678D01*
G03X817196Y1534562I-885J884D01*
G01Y1620853D01*
G02X817255Y1620995I200J0D01*
G01X822528Y1626268D01*
G02X822670Y1626327I142J-141D01*
G01X927565D01*
G02X927707Y1626268I0J-200D01*
G01X932114Y1621861D01*
G02X932173Y1621719I-141J-142D01*
G01Y1586005D01*
G03X932539Y1585121I1251J0D01*
G01X940026Y1577634D01*
G37*
G36*
G01X953110Y1480583D02*
G03X953130Y1480563I894J874D01*
G02X953192Y1480419I-138J-145D01*
G01Y1451442D01*
G02X953133Y1451300I-200J0D01*
G01X952668Y1450835D01*
G02X952526Y1450776I-142J141D01*
G01X930592D01*
G02X930450Y1450835I0J200D01*
G01X929621Y1451664D01*
G02X929562Y1451806I141J142D01*
G01Y1480891D01*
G02X929621Y1481033I200J0D01*
G01X930418Y1481830D01*
G02X930560Y1481889I142J-141D01*
G01X951737D01*
G02X951894Y1481812I-1J-200D01*
G03X951995Y1481698I984J770D01*
G01X953110Y1480583D01*
G37*
G36*
G01X955751Y1485453D02*
X957168Y1486870D01*
G02X957310Y1486929I142J-141D01*
G01X1045732D01*
G02X1045874Y1486870I0J-200D01*
G01X1046659Y1486085D01*
G02X1046718Y1485943I-141J-142D01*
G01Y1452303D01*
G02X1046659Y1452161I-200J0D01*
G01X1045333Y1450835D01*
G02X1045191Y1450776I-142J141D01*
G01X956304D01*
G02X956162Y1450835I0J200D01*
G01X955751Y1451246D01*
G02X955692Y1451388I141J142D01*
G01Y1485311D01*
G02X955751Y1485453I200J0D01*
G37*
G36*
G01X1089972Y1097637D02*
G02I-800J0D01*
G37*
G36*
G01Y1093897D02*
G02I-800J0D01*
G37*
G36*
G01Y1232283D02*
G02I-800J0D01*
G37*
G36*
G01Y1236023D02*
G02I-800J0D01*
G37*
G36*
G01X1086232Y1224803D02*
G02I-800J0D01*
G37*
G36*
G01Y1228543D02*
G02I-800J0D01*
G37*
G36*
G01X1093713Y1105116D02*
G02I-800J0D01*
G37*
G36*
G01X1104933Y1097637D02*
G02I-800J0D01*
G37*
G36*
G01X1097453D02*
G02I-800J0D01*
G37*
G36*
G01X1101193Y1105116D02*
G02I-800J0D01*
G37*
G36*
G01X1104933Y1093897D02*
G02I-800J0D01*
G37*
G36*
G01X1101193Y1101376D02*
G02I-800J0D01*
G37*
G36*
G01X1097453Y1093897D02*
G02I-800J0D01*
G37*
G36*
G01X1093713Y1101376D02*
G02I-800J0D01*
G37*
G36*
G01X1108673Y1105116D02*
G02I-800J0D01*
G37*
G36*
G01Y1101376D02*
G02I-800J0D01*
G37*
G36*
G01X1101193Y1228543D02*
G02I-800J0D01*
G37*
G36*
G01X1104933Y1236023D02*
G02I-800J0D01*
G37*
G36*
G01X1093713Y1224803D02*
G02I-800J0D01*
G37*
G36*
G01X1104933Y1232283D02*
G02I-800J0D01*
G37*
G36*
G01X1108673Y1224803D02*
G02I-800J0D01*
G37*
G36*
G01X1097453Y1236023D02*
G02I-800J0D01*
G37*
G36*
G01X1101193Y1224803D02*
G02I-800J0D01*
G37*
G36*
G01X1108673Y1228543D02*
G02I-800J0D01*
G37*
G36*
G01X1097453Y1232283D02*
G02I-800J0D01*
G37*
G36*
G01X1093713Y1228543D02*
G02I-800J0D01*
G37*
G36*
G01X1119894Y1097637D02*
G02I-800J0D01*
G37*
G36*
G01X1116154Y1101376D02*
G02I-800J0D01*
G37*
G36*
G01X1112413Y1093897D02*
G02I-800J0D01*
G37*
G36*
G01Y1097637D02*
G02I-800J0D01*
G37*
G36*
G01X1123634Y1105116D02*
G02I-800J0D01*
G37*
G36*
G01X1119894Y1093897D02*
G02I-800J0D01*
G37*
G36*
G01X1123634Y1101376D02*
G02I-800J0D01*
G37*
G36*
G01X1116154Y1105116D02*
G02I-800J0D01*
G37*
G36*
G01X1123634Y1224803D02*
G02I-800J0D01*
G37*
G36*
G01X1119894Y1232283D02*
G02I-800J0D01*
G37*
G36*
G01X1116154Y1228543D02*
G02I-800J0D01*
G37*
G36*
G01X1112413Y1232283D02*
G02I-800J0D01*
G37*
G36*
G01X1119894Y1236023D02*
G02I-800J0D01*
G37*
G36*
G01X1116154Y1224803D02*
G02I-800J0D01*
G37*
G36*
G01X1112413Y1236023D02*
G02I-800J0D01*
G37*
G36*
G01X1123634Y1228543D02*
G02I-800J0D01*
G37*
G36*
G01X1127374Y1093897D02*
G02I-800J0D01*
G37*
G36*
G01X1131114Y1105116D02*
G02I-800J0D01*
G37*
G36*
G01X1134854Y1093897D02*
G02I-800J0D01*
G37*
G36*
G01X1131114Y1101376D02*
G02I-800J0D01*
G37*
G36*
G01X1134854Y1097637D02*
G02I-800J0D01*
G37*
G36*
G01X1138594Y1105116D02*
G02I-800J0D01*
G37*
G36*
G01X1127374Y1097637D02*
G02I-800J0D01*
G37*
G36*
G01X1138594Y1101376D02*
G02I-800J0D01*
G37*
G36*
G01X1134854Y1236023D02*
G02I-800J0D01*
G37*
G36*
G01X1138595Y1228543D02*
G02I-800J0D01*
G37*
G36*
G01X1134854Y1232283D02*
G02I-800J0D01*
G37*
G36*
G01X1127374D02*
G02I-800J0D01*
G37*
G36*
G01Y1236023D02*
G02I-800J0D01*
G37*
G36*
G01X1138595Y1224803D02*
G02I-800J0D01*
G37*
G36*
G01X1131114Y1228543D02*
G02I-800J0D01*
G37*
G36*
G01Y1224803D02*
G02I-800J0D01*
G37*
G36*
G01X1146075Y1105116D02*
G02I-800J0D01*
G37*
G36*
G01X1142335Y1093897D02*
G02I-800J0D01*
G37*
G36*
G01X1146075Y1101376D02*
G02I-800J0D01*
G37*
G36*
G01X1142335Y1097637D02*
G02I-800J0D01*
G37*
G36*
G01Y1236023D02*
G02I-800J0D01*
G37*
G36*
G01Y1232283D02*
G02I-800J0D01*
G37*
G36*
G01X1205917Y1228543D02*
G02I-800J0D01*
G37*
G36*
G01Y1224803D02*
G02I-800J0D01*
G37*
G36*
G01Y1243503D02*
G02I-800J0D01*
G37*
G36*
G01Y1247243D02*
G02I-800J0D01*
G37*
G36*
G01X1213398Y1198621D02*
G02I-800J0D01*
G37*
G36*
G01X1209658D02*
G02I-800J0D01*
G37*
G36*
G01X1217138Y1202362D02*
G02I-800J0D01*
G37*
G36*
G01X1220878D02*
G02I-800J0D01*
G37*
G36*
G01Y1217322D02*
G02I-800J0D01*
G37*
G36*
G01Y1209842D02*
G02I-800J0D01*
G37*
G36*
G01X1213398Y1206102D02*
G02I-800J0D01*
G37*
G36*
G01X1217138Y1217322D02*
G02I-800J0D01*
G37*
G36*
G01X1213398Y1213582D02*
G02I-800J0D01*
G37*
G36*
G01X1209658Y1206102D02*
G02I-800J0D01*
G37*
G36*
G01Y1213582D02*
G02I-800J0D01*
G37*
G36*
G01X1217138Y1209842D02*
G02I-800J0D01*
G37*
G36*
G01X1220878Y1224803D02*
G02I-800J0D01*
G37*
G36*
G01X1213398Y1228543D02*
G02I-800J0D01*
G37*
G36*
G01X1209658Y1232283D02*
G02I-800J0D01*
G37*
G36*
G01X1217138Y1236023D02*
G02I-800J0D01*
G37*
G36*
G01Y1232283D02*
G02I-800J0D01*
G37*
G36*
G01X1213398Y1224803D02*
G02I-800J0D01*
G37*
G36*
G01X1220878Y1228543D02*
G02I-800J0D01*
G37*
G36*
G01X1209658Y1236023D02*
G02I-800J0D01*
G37*
G36*
G01X1213398Y1243503D02*
G02I-800J0D01*
G37*
G36*
G01X1220878Y1247243D02*
G02I-800J0D01*
G37*
G36*
G01Y1243503D02*
G02I-800J0D01*
G37*
G36*
G01X1213398Y1247243D02*
G02I-800J0D01*
G37*
G36*
G01X1209658Y1250984D02*
G02I-800J0D01*
G37*
G36*
G01X1217138D02*
G02I-800J0D01*
G37*
G36*
G01X1209658Y1254724D02*
G02I-800J0D01*
G37*
G36*
G01X1217138D02*
G02I-800J0D01*
G37*
G36*
G01X1232098Y1202362D02*
G02I-800J0D01*
G37*
G36*
G01X1235839Y1198621D02*
G02I-800J0D01*
G37*
G36*
G01X1228358Y1202362D02*
G02I-800J0D01*
G37*
G36*
G01X1235839Y1213582D02*
G02I-800J0D01*
G37*
G36*
G01X1232098Y1209842D02*
G02I-800J0D01*
G37*
G36*
G01X1228358D02*
G02I-800J0D01*
G37*
G36*
G01X1235839Y1221062D02*
G02I-800J0D01*
G37*
G36*
G01X1232098Y1217322D02*
G02I-800J0D01*
G37*
G36*
G01X1235839Y1206102D02*
G02I-800J0D01*
G37*
G36*
G01X1228358Y1217322D02*
G02I-800J0D01*
G37*
G36*
G01X1232098Y1232283D02*
G02I-800J0D01*
G37*
G36*
G01X1228358Y1228543D02*
G02I-800J0D01*
G37*
G36*
G01Y1224803D02*
G02I-800J0D01*
G37*
G36*
G01X1224618Y1236023D02*
G02I-800J0D01*
G37*
G36*
G01X1232098D02*
G02I-800J0D01*
G37*
G36*
G01X1235839Y1228543D02*
G02I-800J0D01*
G37*
G36*
G01X1224618Y1232283D02*
G02I-800J0D01*
G37*
G36*
G01X1228358Y1247243D02*
G02I-800J0D01*
G37*
G36*
G01X1224618Y1250984D02*
G02I-800J0D01*
G37*
G36*
G01X1235839Y1239763D02*
G02I-800J0D01*
G37*
G36*
G01X1228358Y1243503D02*
G02I-800J0D01*
G37*
G36*
G01X1232098Y1250984D02*
G02I-800J0D01*
G37*
G36*
G01X1235839Y1247243D02*
G02I-800J0D01*
G37*
G36*
G01X1232098Y1254724D02*
G02I-800J0D01*
G37*
G36*
G01X1224618D02*
G02I-800J0D01*
G37*
G36*
G01X1239579Y1198621D02*
G02I-800J0D01*
G37*
G36*
G01Y1221062D02*
G02I-800J0D01*
G37*
G36*
G01Y1206102D02*
G02I-800J0D01*
G37*
G36*
G01Y1213582D02*
G02I-800J0D01*
G37*
G36*
G01Y1228543D02*
G02I-800J0D01*
G37*
G36*
G01Y1247243D02*
G02I-800J0D01*
G37*
G36*
G01Y1239763D02*
G02I-800J0D01*
G37*
G36*
G01X1528359Y1228543D02*
G02I-800J0D01*
G37*
G36*
G01X1517138D02*
G02I-800J0D01*
G37*
G36*
G01X1524619Y1232283D02*
G02I-800J0D01*
G37*
G36*
G01X1520878Y1228543D02*
G02I-800J0D01*
G37*
G36*
G01X1524619Y1236023D02*
G02I-800J0D01*
G37*
G36*
G01X1528359Y1224803D02*
G02I-800J0D01*
G37*
G36*
G01X1517138Y1239763D02*
G02I-800J0D01*
G37*
G36*
G01X1520878D02*
G02I-800J0D01*
G37*
G36*
G01X1547059Y1097637D02*
G02I-800J0D01*
G37*
G36*
G01Y1093897D02*
G02I-800J0D01*
G37*
G36*
G01X1535839Y1187401D02*
G02I-800J0D01*
G37*
G36*
G01X1539579D02*
G02I-800J0D01*
G37*
G36*
G01X1543319Y1191141D02*
G02I-800J0D01*
G37*
G36*
G01X1539579Y1202362D02*
G02I-800J0D01*
G37*
G36*
G01X1535839Y1194881D02*
G02I-800J0D01*
G37*
G36*
G01X1543319Y1198621D02*
G02I-800J0D01*
G37*
G36*
G01X1547059D02*
G02I-800J0D01*
G37*
G36*
G01Y1191141D02*
G02I-800J0D01*
G37*
G36*
G01X1535839Y1202362D02*
G02I-800J0D01*
G37*
G36*
G01X1539579Y1194881D02*
G02I-800J0D01*
G37*
G36*
G01X1543319Y1213582D02*
G02I-800J0D01*
G37*
G36*
G01Y1206102D02*
G02I-800J0D01*
G37*
G36*
G01X1547059Y1213582D02*
G02I-800J0D01*
G37*
G36*
G01X1535839Y1209842D02*
G02I-800J0D01*
G37*
G36*
G01Y1217322D02*
G02I-800J0D01*
G37*
G36*
G01X1547059Y1206102D02*
G02I-800J0D01*
G37*
G36*
G01X1539579Y1209842D02*
G02I-800J0D01*
G37*
G36*
G01Y1217322D02*
G02I-800J0D01*
G37*
G36*
G01X1547059Y1232283D02*
G02I-800J0D01*
G37*
G36*
G01X1535839Y1224803D02*
G02I-800J0D01*
G37*
G36*
G01X1539579Y1236023D02*
G02I-800J0D01*
G37*
G36*
G01X1532099Y1232283D02*
G02I-800J0D01*
G37*
G36*
G01X1543319Y1228543D02*
G02I-800J0D01*
G37*
G36*
G01X1535839D02*
G02I-800J0D01*
G37*
G36*
G01X1547059Y1236023D02*
G02I-800J0D01*
G37*
G36*
G01X1543319Y1224803D02*
G02I-800J0D01*
G37*
G36*
G01X1532099Y1236023D02*
G02I-800J0D01*
G37*
G36*
G01X1539579Y1232283D02*
G02I-800J0D01*
G37*
G36*
G01X1547059Y1250984D02*
G02I-800J0D01*
G37*
G36*
G01X1543319Y1243503D02*
G02I-800J0D01*
G37*
G36*
G01Y1247243D02*
G02I-800J0D01*
G37*
G36*
G01X1547059Y1254724D02*
G02I-800J0D01*
G37*
G36*
G01X1558280Y1101376D02*
G02I-800J0D01*
G37*
G36*
G01X1562020Y1093897D02*
G02I-800J0D01*
G37*
G36*
G01X1558280Y1105116D02*
G02I-800J0D01*
G37*
G36*
G01X1562020Y1097637D02*
G02I-800J0D01*
G37*
G36*
G01X1550800Y1101376D02*
G02I-800J0D01*
G37*
G36*
G01Y1105116D02*
G02I-800J0D01*
G37*
G36*
G01X1554540Y1093897D02*
G02I-800J0D01*
G37*
G36*
G01Y1097637D02*
G02I-800J0D01*
G37*
G36*
G01Y1232283D02*
G02I-800J0D01*
G37*
G36*
G01X1550800Y1228543D02*
G02I-800J0D01*
G37*
G36*
G01X1554540Y1236023D02*
G02I-800J0D01*
G37*
G36*
G01X1550800Y1224803D02*
G02I-800J0D01*
G37*
G36*
G01X1558280Y1228543D02*
G02I-800J0D01*
G37*
G36*
G01X1562020Y1236023D02*
G02I-800J0D01*
G37*
G36*
G01Y1232283D02*
G02I-800J0D01*
G37*
G36*
G01X1558280Y1224803D02*
G02I-800J0D01*
G37*
G36*
G01X1562020Y1250984D02*
G02I-800J0D01*
G37*
G36*
G01X1550800Y1243503D02*
G02I-800J0D01*
G37*
G36*
G01X1558280Y1247243D02*
G02I-800J0D01*
G37*
G36*
G01X1550800D02*
G02I-800J0D01*
G37*
G36*
G01X1558280Y1243503D02*
G02I-800J0D01*
G37*
G36*
G01X1554540Y1250984D02*
G02I-800J0D01*
G37*
G36*
G01X1562020Y1254724D02*
G02I-800J0D01*
G37*
G36*
G01X1554540D02*
G02I-800J0D01*
G37*
G36*
G01X1565760Y1105116D02*
G02I-800J0D01*
G37*
G36*
G01X1576981Y1097637D02*
G02I-800J0D01*
G37*
G36*
G01X1569500D02*
G02I-800J0D01*
G37*
G36*
G01X1576981Y1093897D02*
G02I-800J0D01*
G37*
G36*
G01X1569500D02*
G02I-800J0D01*
G37*
G36*
G01X1573241Y1101376D02*
G02I-800J0D01*
G37*
G36*
G01Y1105116D02*
G02I-800J0D01*
G37*
G36*
G01X1565760Y1101376D02*
G02I-800J0D01*
G37*
G36*
G01X1569500Y1236023D02*
G02I-800J0D01*
G37*
G36*
G01X1565760Y1224803D02*
G02I-800J0D01*
G37*
G36*
G01Y1228543D02*
G02I-800J0D01*
G37*
G36*
G01X1569500Y1232283D02*
G02I-800J0D01*
G37*
G36*
G01X1565760Y1243503D02*
G02I-800J0D01*
G37*
G36*
G01Y1247243D02*
G02I-800J0D01*
G37*
G36*
G01X1569500Y1250984D02*
G02I-800J0D01*
G37*
G36*
G01Y1254724D02*
G02I-800J0D01*
G37*
G36*
G01X1595681Y1105116D02*
G02I-800J0D01*
G37*
G36*
G01X1591941Y1097637D02*
G02I-800J0D01*
G37*
G36*
G01X1584461Y1093897D02*
G02I-800J0D01*
G37*
G36*
G01X1595681Y1101376D02*
G02I-800J0D01*
G37*
G36*
G01X1584461Y1097637D02*
G02I-800J0D01*
G37*
G36*
G01X1588201Y1105116D02*
G02I-800J0D01*
G37*
G36*
G01X1580721Y1101376D02*
G02I-800J0D01*
G37*
G36*
G01X1591941Y1093897D02*
G02I-800J0D01*
G37*
G36*
G01X1588201Y1101376D02*
G02I-800J0D01*
G37*
G36*
G01X1580721Y1105116D02*
G02I-800J0D01*
G37*
G36*
G01X1603162Y1101376D02*
G02I-800J0D01*
G37*
G36*
G01X1599422Y1097637D02*
G02I-800J0D01*
G37*
G36*
G01Y1093897D02*
G02I-800J0D01*
G37*
G36*
G01X1603162Y1105116D02*
G02I-800J0D01*
G37*
G36*
G01X1633083Y1228543D02*
G02I-800J0D01*
G37*
G36*
G01X1640563Y1224803D02*
G02I-800J0D01*
G37*
G36*
G01X1636823Y1236023D02*
G02I-800J0D01*
G37*
G36*
G01X1644304Y1232283D02*
G02I-800J0D01*
G37*
G36*
G01X1633083Y1224803D02*
G02I-800J0D01*
G37*
G36*
G01X1644304Y1236023D02*
G02I-800J0D01*
G37*
G36*
G01X1636823Y1232283D02*
G02I-800J0D01*
G37*
G36*
G01X1640563Y1228543D02*
G02I-800J0D01*
G37*
G36*
G01X1633083Y1243503D02*
G02I-800J0D01*
G37*
G36*
G01X1640563D02*
G02I-800J0D01*
G37*
G36*
G01X1636823Y1250984D02*
G02I-800J0D01*
G37*
G36*
G01X1633083Y1247243D02*
G02I-800J0D01*
G37*
G36*
G01X1644304Y1250984D02*
G02I-800J0D01*
G37*
G36*
G01X1640563Y1247243D02*
G02I-800J0D01*
G37*
G36*
G01X1636823Y1254724D02*
G02I-800J0D01*
G37*
G36*
G01X1644304D02*
G02I-800J0D01*
G37*
G36*
G01X1655524Y1228543D02*
G02I-800J0D01*
G37*
G36*
G01X1648044D02*
G02I-800J0D01*
G37*
G36*
G01X1659264Y1232283D02*
G02I-800J0D01*
G37*
G36*
G01X1655524Y1224803D02*
G02I-800J0D01*
G37*
G36*
G01X1659264Y1236023D02*
G02I-800J0D01*
G37*
G36*
G01X1651784D02*
G02I-800J0D01*
G37*
G36*
G01X1648044Y1224803D02*
G02I-800J0D01*
G37*
G36*
G01X1651784Y1232283D02*
G02I-800J0D01*
G37*
G36*
G01X1655524Y1243503D02*
G02I-800J0D01*
G37*
G36*
G01X1651784Y1250984D02*
G02I-800J0D01*
G37*
G36*
G01X1648044Y1247243D02*
G02I-800J0D01*
G37*
G36*
G01X1655524D02*
G02I-800J0D01*
G37*
G36*
G01X1648044Y1243503D02*
G02I-800J0D01*
G37*
G36*
G01X1659264Y1250984D02*
G02I-800J0D01*
G37*
G36*
G01X1651784Y1254724D02*
G02I-800J0D01*
G37*
G36*
G01X1659264D02*
G02I-800J0D01*
G37*
%LPD*%
G75*
G54D15*
X7271Y70981D03*
X11011Y79720D03*
X8786Y88425D03*
X14264Y94236D03*
X10292D03*
X12786Y87903D03*
X18000Y90000D03*
X18298Y102141D03*
X8000Y102500D03*
X10131Y115473D03*
X15143Y115581D03*
X14996Y133034D03*
X11442Y132719D03*
X19855Y133000D03*
X9082Y135789D03*
X19855Y141362D03*
X11999Y141415D03*
X15948Y141267D03*
X10966Y162073D03*
Y159073D03*
X16909Y153263D03*
X12247Y166341D03*
X17313Y166937D03*
X21909Y153263D03*
X22335Y166721D03*
X16709Y175943D03*
X19572Y219470D03*
Y221970D03*
X10259Y218085D03*
X13059D03*
X19638Y226320D03*
X16859Y216385D03*
X19572Y216970D03*
X22599Y228646D03*
X18206Y244571D03*
X15586Y249108D03*
X13715Y259381D03*
X8970Y254871D03*
X18206Y264571D03*
X7036Y272371D03*
X8335Y280663D03*
X14807Y282181D03*
X15586Y269108D03*
X15499Y288542D03*
X17033Y1006819D03*
X14357Y1009906D03*
X20216Y1009748D03*
X14197Y1014205D03*
Y1017759D03*
X20197Y1014205D03*
Y1017759D03*
X12599Y1438143D03*
X16304Y1468196D03*
X15889Y1494254D03*
X10089D03*
X6489Y1501334D03*
X19745Y1508846D03*
X19735Y1530499D03*
X19859Y1520657D03*
X6951Y1538547D03*
X18879Y1534334D03*
X10367Y1553080D03*
X32350Y67562D03*
X28442Y55340D03*
X32350Y59562D03*
Y63562D03*
X26588Y97667D03*
X35442D03*
X35048Y103411D03*
X22439Y102495D03*
X35207Y106561D03*
X22935Y162073D03*
Y159073D03*
X26565Y177448D03*
X32507Y180517D03*
X30567Y195176D03*
X28067D03*
X25567D03*
X33067D03*
X29585Y199248D03*
X32585D03*
X29921Y206806D03*
X32585Y202048D03*
X25648Y210509D03*
X28148D03*
X29585Y201748D03*
X27421Y206806D03*
X27340Y230556D03*
X36185Y230117D03*
X31595Y227824D03*
X32201Y238714D03*
X23844Y239299D03*
X21556Y232971D03*
X31682Y246874D03*
X33902Y244297D03*
X26325Y262078D03*
X25549Y256394D03*
X31682Y266874D03*
X29116Y281129D03*
X37117Y279991D03*
X25549Y276394D03*
X34845Y291756D03*
X26629Y295619D03*
X35650Y491982D03*
Y495982D03*
X30177Y534211D03*
X34359Y541135D03*
X34732Y534909D03*
X25819Y527726D03*
Y548726D03*
X34425Y546553D03*
X34448Y552726D03*
X25819Y544726D03*
X30123Y611071D03*
X27686Y621311D03*
X36494Y616905D03*
X36306Y622285D03*
X27686Y629311D03*
Y625311D03*
X36692Y633724D03*
X36575Y627713D03*
X35293Y662952D03*
X35250Y671508D03*
X34565Y699082D03*
X36529Y1006321D03*
X30479Y1006509D03*
X24456Y1006401D03*
X32093Y1009748D03*
X26155Y1009985D03*
X29197Y1014205D03*
X32197Y1017759D03*
X26197D03*
X35197Y1014205D03*
X21196Y1065529D03*
Y1063029D03*
X36089Y1062601D03*
Y1065101D03*
X35925Y1075663D03*
X33425D03*
X28996Y1065529D03*
X23796D03*
X26396D03*
Y1063029D03*
X23796D03*
X28996D03*
X28606Y1082678D03*
X23406D03*
X26006D03*
Y1080178D03*
X23406D03*
X28606D03*
X20806Y1082678D03*
Y1080178D03*
X21321Y1098769D03*
X26521D03*
X29121D03*
X23921D03*
Y1101335D03*
X29121D03*
X26521D03*
X21321D03*
X32574Y1111633D03*
X29874D03*
X27274D03*
X24674D03*
Y1121333D03*
X27274D03*
X29874D03*
X32574D03*
X24674Y1130333D03*
X21974D03*
X21209Y1138705D03*
X23709D03*
X31631Y1198651D03*
X29860Y1438552D03*
X23603Y1449735D03*
X29880Y1441702D03*
X33189Y1501373D03*
X22381Y1554152D03*
X26231Y1554167D03*
X45988Y90512D03*
X51550Y90615D03*
X48476Y180812D03*
X48643Y442919D03*
X48596Y451419D03*
X45643Y472905D03*
X41643Y473419D03*
X49643Y472905D03*
Y464419D03*
X41643Y464919D03*
X48390Y485128D03*
X51239Y485138D03*
X40009Y481467D03*
X43948Y492108D03*
X44563Y482165D03*
X39801Y504825D03*
X42301D03*
X44801D03*
X43804Y500202D03*
X45256Y495993D03*
X45293Y522569D03*
X39742Y517401D03*
X42242D03*
X44742D03*
X46993Y529169D03*
X41408Y531882D03*
X43908D03*
X45293Y525369D03*
X46408Y531882D03*
X38358Y531948D03*
X52869Y537958D03*
X46643Y555194D03*
X52869Y540458D03*
X43843Y555194D03*
X46643Y571194D03*
X43843D03*
Y563194D03*
X46643D03*
X51000Y581222D03*
X45400D03*
X48200D03*
X51000Y591215D03*
X45400D03*
X48200D03*
X51172Y607762D03*
X48372D03*
X45572D03*
Y610562D03*
X48372D03*
X51172D03*
X40362Y610548D03*
X54192Y633473D03*
X42172Y633716D03*
X49192Y628078D03*
X47179Y633736D03*
X37847Y662910D03*
X39549Y682108D03*
X36910D03*
X37804Y671508D03*
X40165Y699082D03*
X37365D03*
X49249Y837718D03*
X52349D03*
X46049D03*
X53549Y843118D03*
X52077Y905295D03*
X48429Y916430D03*
X47264Y919649D03*
X48683Y1006510D03*
X42470Y1006738D03*
X50541Y1009589D03*
X44999Y1009510D03*
X38823Y1009273D03*
X47197Y1014205D03*
X41197D03*
X44197Y1017759D03*
X38197D03*
X48704Y1017982D03*
X43889Y1062601D03*
X38689D03*
X41289D03*
Y1065101D03*
X38689D03*
X43889D03*
X47314Y1072228D03*
X41172Y1079064D03*
X46166Y1093757D03*
X39659Y1105100D03*
X42259D03*
X44859D03*
X47559D03*
X48585Y1123867D03*
X47559Y1114800D03*
X44859D03*
X42259D03*
X39659D03*
X48547Y1133688D03*
X51047D03*
X55188Y1205179D03*
X51023Y1201416D03*
X48842Y1211109D03*
X53479Y1216256D03*
X43198Y1254055D03*
X45698D03*
X48198D03*
X45698Y1251555D03*
X43198D03*
X48198D03*
X47621Y1343672D03*
X48089Y1501387D03*
X39095Y1501361D03*
X47074Y1555923D03*
X40951Y1555932D03*
X64785Y79993D03*
Y82593D03*
Y85193D03*
Y74793D03*
Y77393D03*
X64829Y92874D03*
X55871Y99961D03*
X55921Y95236D03*
X66856Y104249D03*
Y107649D03*
X66478Y162368D03*
X63878D03*
X69261Y211695D03*
Y208695D03*
X65189Y210713D03*
Y213213D03*
Y208213D03*
X54733Y212978D03*
Y215478D03*
Y207978D03*
Y210478D03*
X65189Y215713D03*
X57987Y258880D03*
X60562Y264180D03*
X58062D03*
X66956Y267526D03*
Y270026D03*
X54167Y457339D03*
X56667D03*
X65737Y445603D03*
X57857Y446071D03*
X56667Y459839D03*
X54167D03*
Y462339D03*
X56667D03*
X62224Y473045D03*
X67670Y464818D03*
X58224Y465004D03*
X63154Y462371D03*
X55124Y478625D03*
X53739Y485138D03*
X56239D03*
X56824Y482425D03*
X55124Y475825D03*
X62700Y491214D03*
X66403Y495487D03*
X62700Y493714D03*
X66403Y492987D03*
X68202Y537877D03*
X56572Y539731D03*
X68202Y542877D03*
Y545377D03*
Y540377D03*
X61330Y544895D03*
X56572Y542231D03*
X64130Y541895D03*
Y544895D03*
X61630Y541895D03*
X68188Y548358D03*
X64408Y582747D03*
X63859Y590801D03*
X67684Y597232D03*
X63684Y597130D03*
X67684Y605637D03*
X61854Y617853D03*
Y620653D03*
X53972Y607762D03*
Y610562D03*
X59684Y605443D03*
X63684D03*
X66530Y625013D03*
X58181Y627908D03*
X64692Y642184D03*
X56049Y827218D03*
X68649D03*
X69049Y847718D03*
X65549Y850718D03*
X68598Y859415D03*
X68778Y873821D03*
X63969Y869475D03*
X63930Y874694D03*
X68100Y910122D03*
X71528Y913190D03*
X64632Y901500D03*
X59962Y910251D03*
X53197Y1014205D03*
Y1017759D03*
X55699Y1072761D03*
X61588Y1074481D03*
X62109Y1087656D03*
Y1084656D03*
Y1079656D03*
Y1091656D03*
X60269Y1198820D03*
X63094Y1207604D03*
X55596Y1210466D03*
X68245Y1212054D03*
X58443Y1272257D03*
X54843Y1501625D03*
X60227Y1514751D03*
X60277Y1528395D03*
X55862Y1541791D03*
X65478Y1541980D03*
X60303Y1534436D03*
X60747Y1555890D03*
X64747D03*
X60864Y1583484D03*
X58064D03*
X55264D03*
X69816Y1592527D03*
X60554Y1615152D03*
X73110Y98551D03*
X77804Y95879D03*
X76005Y114623D03*
Y111223D03*
X76660Y103783D03*
X76005Y125396D03*
Y128796D03*
X75194Y141247D03*
X71422Y147540D03*
X82661Y143740D03*
X80041Y148277D03*
X73578Y165393D03*
Y162793D03*
Y170493D03*
Y167993D03*
X80502Y177616D03*
X81083Y172190D03*
X72575Y181426D03*
X75786Y181366D03*
X78581Y181009D03*
X83756Y168697D03*
X84844Y191941D03*
X75400Y184012D03*
X72783Y184221D03*
X72061Y208695D03*
X71761Y211695D03*
X76819Y213859D03*
Y211359D03*
X80522Y213132D03*
Y215632D03*
X80766Y256303D03*
X75438Y265701D03*
X85541Y266114D03*
X80525Y265896D03*
X72256Y267526D03*
X69756D03*
Y270026D03*
X72256D03*
X83014Y281982D03*
X77073Y281716D03*
X71130Y462152D03*
Y459652D03*
Y464652D03*
X73630Y459652D03*
Y462152D03*
Y464652D03*
X78033Y491133D03*
X71461Y498151D03*
Y495151D03*
X73961D03*
X78033Y498633D03*
Y496133D03*
Y493633D03*
X73961Y498151D03*
X78133Y553297D03*
Y555897D03*
X75688Y548358D03*
X73188D03*
X70688D03*
X78133Y558497D03*
Y566597D03*
Y563697D03*
Y561097D03*
X72128Y570686D03*
X74923Y570478D03*
X75340Y576484D03*
X74983Y573689D03*
X72337Y573303D03*
X78733Y578405D03*
X84159Y578986D03*
X83684Y596729D03*
X72515Y596089D03*
X77734Y596782D03*
X81740Y619758D03*
Y616958D03*
Y614158D03*
X69670Y619513D03*
Y616713D03*
Y613913D03*
X79684Y605443D03*
X82648Y670679D03*
X73914Y660107D03*
X79043Y667391D03*
X84845Y659857D03*
X84314Y686107D03*
X82562Y680037D03*
X78735Y683426D03*
X72149Y827318D03*
X74349Y824718D03*
Y821918D03*
X74700Y842890D03*
X84367Y878286D03*
X76528Y878533D03*
X74028Y889065D03*
X83079Y888515D03*
X72035Y898346D03*
X80339Y897943D03*
X76203Y897910D03*
X80593Y946082D03*
X78167Y949261D03*
X76332Y953421D03*
X87632Y1007522D03*
X70059Y1075656D03*
X70302Y1067656D03*
X77734Y1095676D03*
X70947Y1201565D03*
Y1205835D03*
X71006Y1228684D03*
X71020Y1224323D03*
X74909Y1593009D03*
X71910Y1625009D03*
X78291Y1625743D03*
X83689Y1624736D03*
X82291Y1633801D03*
X78291D03*
X70291D03*
X86407Y132509D03*
Y118335D03*
Y121735D03*
Y135909D03*
X91224Y141247D03*
X92337Y144172D03*
X95711Y143518D03*
X94811Y152373D03*
X97961Y152562D03*
X103456Y157370D03*
X98826Y172665D03*
X98763Y178560D03*
X98653Y183834D03*
X99639Y186629D03*
X98943Y200864D03*
X92898Y192490D03*
X98173Y190185D03*
X89353Y206767D03*
X86853D03*
X91853D03*
X98966Y207037D03*
X99032Y212455D03*
X89483Y221708D03*
X86983D03*
X86398Y224421D03*
X88098Y231021D03*
Y228221D03*
X96333Y221642D03*
X91983Y221708D03*
X103841Y228631D03*
X93649Y236189D03*
X91149D03*
X88649D03*
X91090Y248765D03*
X88590D03*
X93590D03*
X97747Y265897D03*
X100247D03*
X94087Y270695D03*
X91287D03*
X88787D03*
Y268195D03*
X91287D03*
X94087D03*
X98255Y374510D03*
X100120Y377898D03*
X100066Y381976D03*
X86788Y581659D03*
X87684Y605443D03*
X95973Y655660D03*
X92897Y658359D03*
X95917Y658374D03*
X95539Y664443D03*
X86289Y822088D03*
X86367Y848086D03*
X90000Y871389D03*
X103770Y868206D03*
X103692Y900295D03*
X91387Y905295D03*
X100058Y977651D03*
X99836Y980330D03*
X103836Y988813D03*
X100200Y988800D03*
X95836Y988813D03*
X85706Y998507D03*
X94398Y1006648D03*
X101025Y1009655D03*
X94586Y1023900D03*
X91765Y1018307D03*
X88007Y1013678D03*
X88479Y1023731D03*
X88287Y1026537D03*
X97609Y1018469D03*
X90450Y1033542D03*
X93496Y1547768D03*
X107364Y116594D03*
X118307Y110784D03*
X113307D03*
X107364Y119594D03*
X117886Y124663D03*
X112864Y124879D03*
X107798Y124283D03*
X119230Y138838D03*
X106205Y161306D03*
X107540Y176665D03*
Y168665D03*
Y196665D03*
Y192665D03*
X107653Y186778D03*
X107572Y204864D03*
Y208864D03*
X112621Y218085D03*
X115421D03*
X103213Y219379D03*
X117948Y249108D03*
X109329Y248371D03*
X111993Y710102D03*
X120250Y758841D03*
X113505Y796856D03*
X109591Y796905D03*
X102355Y874267D03*
X102947Y877196D03*
X102320Y891043D03*
X110887Y884000D03*
X103972Y977609D03*
X103836Y980330D03*
X111836Y988813D03*
X119836D03*
X115836D03*
X107836D03*
X103825Y1009655D03*
X105971Y1025745D03*
X114770Y1016827D03*
X110409Y1024094D03*
X114770Y1029427D03*
X110970Y1030672D03*
X101970D03*
X104970D03*
X107970D03*
X102761Y1096233D03*
X108971Y1109564D03*
X103124D03*
Y1122164D03*
X108971D03*
X103124Y1134764D03*
X108971D03*
X103124Y1147364D03*
X108971D03*
X103124Y1172564D03*
X108971D03*
X103124Y1159964D03*
X108971D03*
X103861Y1182703D03*
X118533Y1207737D03*
X112048Y1214372D03*
X107803Y1218169D03*
X128950Y97667D03*
X133200Y95111D03*
X124606Y102495D03*
X119333Y116594D03*
Y119594D03*
X122867Y125107D03*
X124340Y142862D03*
X131481Y143762D03*
X125381Y148717D03*
X131947Y199248D03*
X127929Y195176D03*
X130429D03*
X132929D03*
X134947Y199248D03*
X128010Y210509D03*
X130510D03*
X132283Y206806D03*
X129783D03*
X131947Y201748D03*
X122000Y226320D03*
X119221Y216385D03*
X121934Y216970D03*
Y219470D03*
Y221970D03*
X129702Y230556D03*
X133957Y227824D03*
X124961Y228646D03*
X128687Y242078D03*
X123918Y232971D03*
X134044Y246874D03*
X120568Y244571D03*
X127911Y256394D03*
X126131Y359511D03*
X125753Y365856D03*
X119099Y755052D03*
X118467Y796785D03*
X122437Y860775D03*
X125698Y857515D03*
X122432Y857540D03*
X129666Y857514D03*
X133424Y857303D03*
X122887Y888000D03*
X123387Y892000D03*
X135836Y988813D03*
X131836D03*
X123836D03*
X127836D03*
X120617Y1029427D03*
Y1016827D03*
X133579Y1097469D03*
X124925Y1102091D03*
X130380Y1105091D03*
X124880D03*
X124925Y1114691D03*
Y1127291D03*
X124880Y1117691D03*
X130380D03*
X124925Y1139891D03*
X124880Y1130291D03*
X130380D03*
X130434Y1144964D03*
X124474Y1142997D03*
X130380Y1155491D03*
X124880D03*
X124925Y1152491D03*
X124474Y1168197D03*
X130434Y1170164D03*
X124925Y1165091D03*
Y1177691D03*
X131000Y1180266D03*
X124765Y1180691D03*
X135757Y1221407D03*
X135448Y1229402D03*
Y1234921D03*
X126433Y1230407D03*
X129250Y1227650D03*
X137410Y103411D03*
X137804Y97667D03*
X148600Y90650D03*
X148350Y95236D03*
X137569Y106561D03*
X135429Y195176D03*
X134947Y202048D03*
X138547Y230117D03*
X134563Y238714D03*
X138664Y241699D03*
X148061Y378600D03*
Y382600D03*
X148176Y458711D03*
X148940Y455921D03*
X145376Y458711D03*
X147520Y463600D03*
X142024Y552466D03*
X147925Y603600D03*
Y619600D03*
Y623600D03*
X149469Y634190D03*
X152658Y645389D03*
X136862Y857244D03*
X147836Y988813D03*
X139836D03*
X151836D03*
X143836D03*
X142026Y1012354D03*
X136571Y1009354D03*
X136526Y1012354D03*
X136571Y1021954D03*
X142026Y1024954D03*
X136526D03*
X144640Y1039439D03*
X150952Y1040115D03*
X146595Y1053457D03*
X136432Y1224472D03*
X167191Y92874D03*
X153912Y90615D03*
X158283Y95236D03*
X158233Y99961D03*
X166240Y162368D03*
X157095Y210478D03*
Y207978D03*
Y215478D03*
Y212978D03*
X160424Y264180D03*
X162924D03*
X160349Y258880D03*
X164496Y309405D03*
X150703Y453682D03*
X159836Y988813D03*
X155836Y997860D03*
X160733Y1056594D03*
X153693Y1051037D03*
X160547Y1049283D03*
X160627Y1053561D03*
X160807Y1043955D03*
X166188Y1066551D03*
X163191Y1065313D03*
X159228Y1065613D03*
X165649Y1159350D03*
Y1151870D03*
X167147Y77393D03*
Y74793D03*
Y85193D03*
Y82593D03*
Y79993D03*
X175472Y98551D03*
X178367Y111223D03*
Y114623D03*
X179022Y103783D03*
X169218Y107649D03*
Y104249D03*
X178367Y128796D03*
Y125396D03*
X173784Y147540D03*
X177556Y141247D03*
X185023Y143740D03*
X182403Y148277D03*
X175940Y162793D03*
Y165393D03*
X168840Y162368D03*
X175940Y167993D03*
Y170493D03*
X178148Y181366D03*
X180943Y181009D03*
X174937Y181426D03*
X182864Y177616D03*
X183445Y172190D03*
X175145Y184221D03*
X177762Y184012D03*
X171623Y211695D03*
X182884Y213132D03*
X179181Y211359D03*
Y213859D03*
X174123Y211695D03*
X167551Y208213D03*
Y213213D03*
Y210713D03*
X171623Y208695D03*
X174423D03*
X167551Y215713D03*
X182884Y215632D03*
X177800Y265701D03*
X182887Y265896D03*
X174618Y267526D03*
Y270026D03*
X169318Y267526D03*
X172118D03*
Y270026D03*
X169318D03*
X179435Y281716D03*
X170215Y311671D03*
X175615Y550907D03*
X173115D03*
X175615Y553407D03*
X173115D03*
X174923Y545263D03*
Y541863D03*
X177385Y566929D03*
X171339Y572070D03*
X172686Y569928D03*
X175033Y570962D03*
X174776Y568475D03*
X177099Y569426D03*
X169389Y1155610D03*
X191568Y76587D03*
Y72615D03*
X193007Y100625D03*
X186026Y97475D03*
X185957Y106186D03*
X197380Y112083D03*
X188769Y118335D03*
Y121735D03*
Y132509D03*
Y135909D03*
X193586Y141247D03*
X198073Y143518D03*
X197173Y152373D03*
X201015Y183834D03*
X201125Y178560D03*
X186118Y168697D03*
X201188Y172665D03*
X187206Y191941D03*
X195260Y192490D03*
X200535Y190185D03*
X201305Y200864D03*
X189215Y206767D03*
X191715D03*
X194215D03*
X201394Y212455D03*
X201328Y207037D03*
X194345Y221708D03*
X198695Y221642D03*
X190460Y228221D03*
Y231021D03*
X191845Y221708D03*
X188760Y224421D03*
X189345Y221708D03*
X191011Y236189D03*
X193511D03*
X196011D03*
X190952Y248765D03*
X193452D03*
X195952D03*
X183128Y256303D03*
X187903Y266114D03*
X196449Y268195D03*
X193649D03*
X196449Y270695D03*
X193649D03*
X191149D03*
Y268195D03*
X185376Y281982D03*
X185328Y545528D03*
X194063Y577716D03*
X191125Y610400D03*
X203248Y55513D03*
X199473Y68581D03*
X205848Y60513D03*
X208645Y60369D03*
X199486Y80581D03*
X214389Y86012D03*
X203616Y88801D03*
X214389Y94374D03*
X206533Y94351D03*
X210482Y94279D03*
X209530Y86046D03*
X205976Y85731D03*
X209726Y116594D03*
X201669Y103621D03*
X215669Y110784D03*
X209726Y119594D03*
X210160Y124283D03*
X215226Y124879D03*
X208567Y161306D03*
X200323Y152562D03*
X205818Y157370D03*
X209902Y176665D03*
Y168665D03*
X202001Y186629D03*
X209902Y196665D03*
Y192665D03*
X210015Y186778D03*
X209934Y204864D03*
Y208864D03*
X214983Y218085D03*
X205575Y219379D03*
X206203Y228631D03*
X211691Y248371D03*
X200109Y265897D03*
X202609D03*
X204675Y382109D03*
X204674Y551683D03*
Y558917D03*
Y561420D03*
X200495Y577937D03*
X208500Y595500D03*
X203500Y606929D03*
X208000Y604567D03*
X203460Y618400D03*
X203741Y612592D03*
X209158Y610072D03*
X209094Y616317D03*
X208540Y621591D03*
X205941Y668934D03*
X201115Y695581D03*
X203046Y693716D03*
X213969Y1447453D03*
Y1461853D03*
Y1458453D03*
Y1450853D03*
X231312Y97667D03*
X221695Y116594D03*
X226968Y102495D03*
X220669Y110784D03*
X221695Y119594D03*
X225229Y125107D03*
X220248Y124663D03*
X226702Y142862D03*
X227743Y148717D03*
X221592Y138838D03*
X230291Y195176D03*
X230372Y210509D03*
X224362Y226320D03*
X224296Y216970D03*
Y219470D03*
Y221970D03*
X221583Y216385D03*
X217783Y218085D03*
X232064Y230556D03*
X227323Y228646D03*
X231049Y242078D03*
X226280Y232971D03*
X220310Y249108D03*
X222930Y244571D03*
X233417Y253198D03*
X230842Y313888D03*
X233258Y359186D03*
X228267Y396718D03*
X221375Y455024D03*
X220349Y465622D03*
X225500Y530000D03*
X225000Y540500D03*
X224000Y547075D03*
X224200Y549800D03*
X223500Y568000D03*
X224104Y562800D03*
X224040Y558800D03*
X221693Y594982D03*
X222289Y590895D03*
X220333Y617930D03*
X220255Y629749D03*
X217906Y1430452D03*
Y1427052D03*
X219525Y1440028D03*
X216125D03*
X227249Y1447453D03*
Y1450853D03*
Y1458453D03*
Y1461853D03*
X224780Y1478149D03*
X217985Y1483055D03*
X225765Y1471985D03*
X233313Y1476699D03*
X221899Y1488800D03*
X218021Y1494724D03*
X222843Y1498442D03*
X217614Y1489671D03*
X233180Y1486442D03*
X233166Y1491454D03*
X226135Y1502442D03*
X230758Y1505046D03*
X226971Y1514578D03*
X227552Y1530675D03*
X232622Y1531104D03*
X226971Y1522578D03*
X219981Y1530797D03*
X223322Y1518578D03*
X222119Y1539941D03*
X227882Y1540816D03*
X233753Y1539752D03*
X239772Y103411D03*
X240166Y97667D03*
X235562Y95111D03*
X239931Y106561D03*
X233843Y143762D03*
X232791Y195176D03*
X235291D03*
X237309Y199248D03*
X234309D03*
X237791Y195176D03*
X237309Y202048D03*
X232872Y210509D03*
X234645Y206806D03*
X232145D03*
X234309Y201748D03*
X240909Y230117D03*
X236319Y227824D03*
X236925Y238714D03*
X236406Y246874D03*
X238626Y244297D03*
X234986Y336161D03*
X236264Y342494D03*
X245362Y546712D03*
Y542712D03*
X247536Y602689D03*
X247278Y618288D03*
X243278D03*
X240194Y643113D03*
X242102Y656321D03*
X250102D03*
X246102D03*
X245000Y678462D03*
X244267Y696911D03*
X235790Y754332D03*
X241204Y814841D03*
X237591Y815266D03*
X248556Y824003D03*
X246311Y819000D03*
X238400Y836900D03*
X234976Y1481676D03*
X243535Y1511473D03*
X245500Y1517033D03*
X237633Y1511909D03*
X244600Y1531700D03*
X240808Y1519942D03*
X235687Y1522578D03*
X237580Y1528604D03*
X245937Y1524237D03*
X239949Y1541327D03*
X244912Y1539389D03*
X250962Y90650D03*
X256274Y90615D03*
X260595Y99961D03*
X260645Y95236D03*
X250712D03*
X259457Y210478D03*
Y207978D03*
Y215478D03*
Y212978D03*
X262786Y264180D03*
X262711Y258880D03*
X257993Y307994D03*
X256475Y422088D03*
X252695Y442956D03*
X254512Y438323D03*
X261965Y458455D03*
X250336Y456386D03*
X254678Y445873D03*
X263301Y444232D03*
X262526Y451108D03*
X249125Y465874D03*
X252688Y636364D03*
X248690Y678519D03*
X248090Y691114D03*
X254634Y698241D03*
X248506Y812042D03*
X256303Y812254D03*
X250700Y819900D03*
X254058Y819851D03*
X255289Y824340D03*
X252305Y831018D03*
X252100Y836800D03*
X250876Y1532782D03*
X255909Y1542043D03*
X250790Y1539759D03*
X269509Y77393D03*
Y74793D03*
Y85193D03*
Y82593D03*
Y79993D03*
X277834Y98551D03*
X269553Y92874D03*
X271580Y107649D03*
Y104249D03*
X276146Y147540D03*
X279918Y141247D03*
X268602Y162368D03*
X271202D03*
X278302Y162793D03*
Y165393D03*
Y167993D03*
Y170493D03*
X277299Y181426D03*
X280124Y184012D03*
X277507Y184221D03*
X269913Y210713D03*
X273985Y208695D03*
X276785D03*
X273985Y211695D03*
X276485D03*
X269913Y208213D03*
Y213213D03*
Y215713D03*
X265286Y264180D03*
X280162Y265701D03*
X276980Y267526D03*
Y270026D03*
X271680Y267526D03*
X274480D03*
Y270026D03*
X271680D03*
X281797Y281716D03*
X277575Y395084D03*
X274425Y381500D03*
X278784Y435158D03*
X278529Y440489D03*
X274949Y442606D03*
X278827Y444841D03*
X282230Y458572D03*
X265011Y453881D03*
X280220Y448493D03*
X274866Y446606D03*
X265011Y446595D03*
X275873Y463479D03*
X276344Y467367D03*
X274096Y820725D03*
X274697Y830951D03*
X275123Y847874D03*
X269700Y853100D03*
X275400Y864400D03*
X278400Y890839D03*
X275400Y899400D03*
X279261Y926339D03*
X278739Y936439D03*
X289797Y36735D03*
X290113Y23188D03*
X284666Y34068D03*
X289631Y28281D03*
X293930Y76587D03*
Y72615D03*
X295369Y100625D03*
X288388Y97475D03*
X280729Y111223D03*
Y114623D03*
X281384Y103783D03*
X288319Y106186D03*
X280729Y125396D03*
X291131Y121735D03*
X280729Y128796D03*
X291131Y118335D03*
Y132509D03*
Y135909D03*
X295948Y141247D03*
X287385Y143740D03*
X284765Y148277D03*
X285807Y172190D03*
X280510Y181366D03*
X283305Y181009D03*
X288480Y168697D03*
X285226Y177616D03*
X289568Y191941D03*
X297622Y192490D03*
X291577Y206767D03*
X294077D03*
X296577D03*
X285246Y213132D03*
X281543Y211359D03*
Y213859D03*
X296707Y221708D03*
X292822Y228221D03*
Y231021D03*
X294207Y221708D03*
X291122Y224421D03*
X291707Y221708D03*
X285246Y215632D03*
X293373Y236189D03*
X295873D03*
X293314Y248765D03*
X295814D03*
X285490Y256303D03*
X290265Y266114D03*
X285249Y265896D03*
X296011Y270695D03*
X293511D03*
Y268195D03*
X296011D03*
X287738Y281982D03*
X286940Y315039D03*
X297719Y339559D03*
X291396Y350223D03*
X292520Y384410D03*
X292358Y393858D03*
X298000Y391496D03*
X295699Y382047D03*
X296000Y403500D03*
X298000Y409000D03*
X294000Y398583D03*
X295253Y440869D03*
Y438269D03*
X292453D03*
Y440869D03*
Y435669D03*
Y430469D03*
Y433069D03*
X295253D03*
Y430469D03*
Y435669D03*
X293307Y451677D03*
X295807D03*
X293307Y454177D03*
X295807D03*
X295011Y460218D03*
Y463618D03*
X281980Y953926D03*
X312256Y37543D03*
X305610Y55513D03*
X301835Y68581D03*
X310817Y60393D03*
X307916Y60529D03*
X301848Y80581D03*
X305978Y88801D03*
X312844Y94279D03*
X308895Y94351D03*
X308338Y85731D03*
X311892Y86046D03*
X312088Y116594D03*
X299742Y112083D03*
X304031Y103621D03*
X312088Y119594D03*
X312522Y124283D03*
X300435Y143518D03*
X299535Y152373D03*
X310929Y161306D03*
X302685Y152562D03*
X308180Y157370D03*
X312264Y176665D03*
Y168665D03*
X303377Y183834D03*
X303550Y172665D03*
X303487Y178560D03*
X304363Y186629D03*
X302897Y190185D03*
X312264Y196665D03*
Y192665D03*
X303667Y200864D03*
X312377Y186778D03*
X300814Y192859D03*
X312296Y204864D03*
Y208864D03*
X303756Y212455D03*
X303690Y207037D03*
X301057Y221642D03*
X307937Y219379D03*
X308565Y228631D03*
X298373Y236189D03*
X298314Y248765D03*
X302471Y265897D03*
X304971D03*
X298811Y270695D03*
Y268195D03*
X315079Y314890D03*
X312263Y324518D03*
X301943Y328867D03*
X308952Y356875D03*
X312316Y356747D03*
X299000Y377912D03*
Y386500D03*
X299088Y397912D03*
X322847Y19806D03*
X321840Y14408D03*
X322113Y26187D03*
X316751Y86012D03*
Y94374D03*
X324057Y116594D03*
X318031Y110784D03*
X323031D03*
X324057Y119594D03*
X327591Y125107D03*
X322610Y124663D03*
X317588Y124879D03*
X329064Y142862D03*
X330105Y148717D03*
X323954Y138838D03*
X317345Y218085D03*
X320145D03*
X323945Y216385D03*
X326658Y216970D03*
Y219470D03*
X326724Y226320D03*
X326658Y221970D03*
X329685Y228646D03*
X328642Y232971D03*
X322672Y249108D03*
X325292Y244571D03*
X314053Y248371D03*
X327032Y303962D03*
X314855Y311740D03*
X318508Y324322D03*
X315944Y332584D03*
X316067Y347937D03*
X321416Y348015D03*
X317333Y353470D03*
X318500Y356519D03*
X315310Y356712D03*
X318660Y539315D03*
X320785Y553287D03*
X327456Y550065D03*
X321119Y622912D03*
X330905Y15806D03*
Y19806D03*
Y27806D03*
X333674Y97667D03*
X342134Y103411D03*
X342528Y97667D03*
X337924Y95111D03*
X329330Y102495D03*
X342293Y106561D03*
X336205Y143762D03*
X335153Y195176D03*
X332653D03*
X336671Y199248D03*
X337653Y195176D03*
X340153D03*
X339671Y199248D03*
X336671Y201748D03*
X334507Y206806D03*
X337007D03*
X335234Y210509D03*
X332734D03*
X339671Y202048D03*
X343271Y230117D03*
X338681Y227824D03*
X334426Y230556D03*
X339287Y238714D03*
X333411Y242078D03*
X338768Y246874D03*
X340988Y244297D03*
X332635Y256394D03*
X347058Y399918D03*
X339072Y416888D03*
Y419488D03*
Y422088D03*
X345050Y454334D03*
X337078Y551381D03*
X335399Y544718D03*
X333985Y1017945D03*
X341077Y1018056D03*
X339251Y1138130D03*
X336755Y1143489D03*
X340500Y1147500D03*
X335190Y1173065D03*
X341266Y1171956D03*
X330800Y1174500D03*
X343121Y1188412D03*
X342009Y1176100D03*
X339776Y1187962D03*
X335502Y1188222D03*
X339540Y1196894D03*
X358636Y90615D03*
X353324Y90650D03*
X362957Y99961D03*
X353074Y95236D03*
X359376Y290592D03*
X348351Y319372D03*
X348806Y315427D03*
X351132Y322202D03*
X349120Y336100D03*
X351136Y372334D03*
X350486Y377173D03*
X358491D03*
X347591Y391533D03*
X359486Y385123D03*
X349311Y385644D03*
X354486Y385123D03*
X357655Y405889D03*
Y408489D03*
X358248Y403300D03*
X353894Y406060D03*
X354155Y421489D03*
Y418889D03*
Y416289D03*
X350163Y412106D03*
X357655Y413689D03*
Y416289D03*
Y421489D03*
Y418889D03*
Y424089D03*
Y411089D03*
X358042Y432718D03*
X357655Y426689D03*
X358042Y435518D03*
X358754Y450091D03*
X356241Y447001D03*
X359241D03*
X353320Y454214D03*
X353663Y449045D03*
X353367Y459330D03*
X358754Y462060D03*
X353670Y473571D03*
Y481071D03*
Y478571D03*
Y476071D03*
X360242Y477053D03*
X357742D03*
X358207Y836462D03*
X346366Y1134729D03*
X361621D03*
X349748D03*
X357748D03*
X353748D03*
X352545Y1142666D03*
X360877Y1157404D03*
X354420Y1157544D03*
X352931Y1167768D03*
X357950D03*
X357057Y1179542D03*
X357796Y1188058D03*
X357083Y1185205D03*
X361792Y1187310D03*
X348432Y1187215D03*
X348125Y1180175D03*
X358368Y1201043D03*
X354398D03*
X350402D03*
X346387Y1199256D03*
X360523Y1192282D03*
X349276Y1217228D03*
X351940Y1219895D03*
X362332Y1230265D03*
X355215Y1223170D03*
X360273Y1228226D03*
X358062Y1226016D03*
X371871Y85193D03*
Y82593D03*
Y79993D03*
Y77393D03*
Y74793D03*
X371915Y92874D03*
X363007Y95236D03*
X373942Y104249D03*
Y107649D03*
X370964Y162368D03*
X373564D03*
X372275Y208213D03*
X379147Y208695D03*
X376347D03*
Y211695D03*
X372275Y210713D03*
Y213213D03*
X361819Y207978D03*
Y212978D03*
Y215478D03*
Y210478D03*
X372275Y215713D03*
X367648Y264180D03*
X365148D03*
X365073Y258880D03*
X374042Y270026D03*
X376842D03*
X374042Y267526D03*
X376842D03*
X371417Y353820D03*
X365559Y354300D03*
X377237Y371060D03*
X373264Y379429D03*
X378875Y379088D03*
X366526Y377173D03*
X370486D03*
X362486Y385123D03*
X366486D03*
X370160Y391569D03*
X368587Y401066D03*
X378927Y406739D03*
X367919Y439318D03*
X375919Y442118D03*
Y439318D03*
X367919Y442118D03*
X361754Y450091D03*
X367564Y456034D03*
Y461034D03*
X373546Y470001D03*
X376046D03*
X361754Y462060D03*
X373971Y489036D03*
X371832Y485580D03*
X374332D03*
X376832D03*
X366420Y479986D03*
Y477486D03*
X363686Y478668D03*
Y476168D03*
X376207Y492836D03*
Y495636D03*
X376881Y518564D03*
X363015Y710365D03*
X365887Y710329D03*
X372400Y746300D03*
X372300Y750000D03*
X373500Y767300D03*
X376300D03*
X370415Y766108D03*
X373703Y782555D03*
X365850Y773950D03*
X371436Y791188D03*
X365691Y815127D03*
X371507Y815303D03*
X362042Y814772D03*
X368067Y925136D03*
X370214Y943812D03*
X368626Y931346D03*
X368964Y937738D03*
X372858Y935136D03*
X366761Y934550D03*
X363893Y946863D03*
X379928Y949774D03*
X379245Y956643D03*
X378875Y961862D03*
X370214Y947812D03*
X370101Y953699D03*
X370214Y963812D03*
Y971812D03*
X378928Y967812D03*
X372501Y1123695D03*
X365748Y1134325D03*
X368657Y1150087D03*
X366133Y1170767D03*
X366429Y1185238D03*
X366222Y1180235D03*
X362402Y1201039D03*
X366402Y1200969D03*
X366521Y1208993D03*
X370202Y1314764D03*
Y1311364D03*
X383612Y33768D03*
X388612Y31168D03*
X387948Y27288D03*
X380196Y98551D03*
X390750Y97475D03*
X383091Y111223D03*
Y114623D03*
X383746Y103783D03*
X390681Y106186D03*
X393493Y118335D03*
X383091Y125396D03*
Y128796D03*
X393493Y132509D03*
Y121735D03*
Y135909D03*
X380664Y165393D03*
Y162793D03*
Y167993D03*
Y170493D03*
X387588Y177616D03*
X382872Y181366D03*
X379661Y181426D03*
X385667Y181009D03*
X390842Y168697D03*
X388169Y172190D03*
X391930Y191941D03*
X382486Y184012D03*
X379869Y184221D03*
X393939Y206767D03*
X383905Y211359D03*
X387608Y213132D03*
X378847Y211695D03*
X383905Y213859D03*
X394069Y221708D03*
X393484Y224421D03*
X387608Y215632D03*
X387852Y256303D03*
X387611Y265896D03*
X382524Y265701D03*
X392627Y266114D03*
X379342Y270026D03*
Y267526D03*
X384159Y281716D03*
X390100Y281982D03*
X391737Y377581D03*
X384173Y379028D03*
X381237Y371076D03*
X394237Y379591D03*
X391940Y383817D03*
Y388817D03*
Y386317D03*
X385864Y398278D03*
X383364D03*
X378927Y409539D03*
X381927D03*
Y407039D03*
X381591Y401981D03*
X384091D03*
X378210Y424067D03*
X380710D03*
X385710D03*
X383210D03*
X378445Y413611D03*
X380945D03*
X385945D03*
X383445D03*
X385584Y438293D03*
Y441093D03*
Y443893D03*
X393646Y474382D03*
X385634Y472020D03*
X393662Y470382D03*
X385694Y477318D03*
X385293Y466409D03*
X387141Y484882D03*
X385131Y487382D03*
X391470Y732865D03*
X380963Y731000D03*
X381875Y740341D03*
X379800Y769200D03*
X380331Y782627D03*
X380607Y786932D03*
X387958Y813700D03*
X381631Y814147D03*
X384666Y814103D03*
X383391Y804000D03*
X386589Y864408D03*
X383462Y860535D03*
X392584Y875845D03*
X382675Y870151D03*
X391614Y930676D03*
X384856Y947987D03*
X378119Y953696D03*
X392910Y948536D03*
X393998Y971780D03*
X378790Y1001083D03*
X380280Y1006071D03*
X383710Y1007283D03*
X382465Y1012430D03*
X378410Y1131573D03*
X380261Y1129692D03*
X385091Y1297453D03*
Y1300853D03*
X386415Y1321645D03*
X391691Y1326715D03*
X392234Y1369579D03*
Y1364501D03*
X391757Y1383480D03*
X391852Y1389931D03*
X393951Y1447455D03*
X381900Y1544800D03*
X389700Y1536900D03*
X391740Y1545629D03*
Y1540529D03*
X382017Y1559700D03*
X395296Y1561024D03*
X391740Y1550729D03*
Y1555829D03*
X410789Y22627D03*
X408680Y37530D03*
X396680Y37543D03*
X400714Y45448D03*
X404686D03*
X397731Y100625D03*
X402104Y112083D03*
X406393Y103621D03*
X405912Y172665D03*
X405739Y183834D03*
X405849Y178560D03*
X406725Y186629D03*
X399984Y192490D03*
X405259Y190185D03*
X406029Y200864D03*
X395942Y192300D03*
X398939Y206767D03*
X396439D03*
X406118Y212455D03*
X406052Y207037D03*
X395184Y228221D03*
X399069Y221708D03*
X396569D03*
X403419Y221642D03*
X395184Y231021D03*
X410299Y219379D03*
X410927Y228631D03*
X400735Y236189D03*
X398235D03*
X395735D03*
X400676Y248765D03*
X398176D03*
X395676D03*
X407333Y265897D03*
X404833D03*
X401173Y268195D03*
Y270695D03*
X398373Y268195D03*
X395873D03*
Y270695D03*
X398373D03*
X405843Y315158D03*
X403343D03*
X394883Y341777D03*
Y338377D03*
X410086Y336795D03*
X409655Y331589D03*
X410688Y344736D03*
X400993Y331589D03*
Y335589D03*
X400728Y353152D03*
X411007Y356743D03*
X406421Y387151D03*
Y382151D03*
Y384651D03*
X398453Y387702D03*
X401253D03*
X394653Y389402D03*
X395577Y438293D03*
Y441093D03*
Y443893D03*
X397315Y471560D03*
X405801Y475560D03*
X405301Y467560D03*
X397315Y475560D03*
X406200Y741300D03*
X397223Y796792D03*
X400023D03*
X397900Y789000D03*
X407000Y784700D03*
X404468Y864407D03*
X396306Y864409D03*
X406770Y869767D03*
X405466Y881299D03*
X397431Y870654D03*
X401108Y878487D03*
X401121Y929686D03*
X409121D03*
X401121Y932186D03*
X409121D03*
X405179Y959051D03*
X404971Y956256D03*
X402354Y956465D03*
X401968Y959111D03*
X399173Y959468D03*
X397252Y962861D03*
X404176Y977684D03*
Y975084D03*
Y969984D03*
Y972484D03*
X396671Y968287D03*
X406954Y982970D03*
X409554D03*
X404354D03*
X407547Y1058097D03*
X410047D03*
X405047D03*
X407547Y1060697D03*
X410047D03*
X405047D03*
X408989Y1082501D03*
X409015Y1087705D03*
Y1085205D03*
X408847Y1090956D03*
Y1093956D03*
X406895Y1107997D03*
X402695D03*
Y1110897D03*
X407780Y1113648D03*
X409231Y1118801D03*
X406995Y1110597D03*
X404895Y1112397D03*
X404795Y1109397D03*
X402695Y1113797D03*
X408961Y1162384D03*
Y1164884D03*
Y1167384D03*
Y1169884D03*
Y1172384D03*
X403263Y1160834D03*
X408961Y1174884D03*
X406319Y1186709D03*
Y1184209D03*
Y1181709D03*
Y1179209D03*
X404004Y1192621D03*
Y1190121D03*
X397063Y1221428D03*
X401063D03*
X405063D03*
X409063D03*
X397063Y1233428D03*
Y1229428D03*
Y1225428D03*
X401063Y1237428D03*
Y1233428D03*
Y1229428D03*
Y1225428D03*
X405063Y1237428D03*
Y1233428D03*
Y1229428D03*
Y1225428D03*
X409063Y1237428D03*
Y1233428D03*
Y1229428D03*
Y1225428D03*
X401063Y1241428D03*
X405063Y1245428D03*
Y1241428D03*
X409063Y1245428D03*
Y1241428D03*
X404324Y1271889D03*
Y1275889D03*
X407767Y1292198D03*
X403678Y1295426D03*
X398584Y1313443D03*
X401011Y1307258D03*
X402967Y1319815D03*
X409220Y1315516D03*
X404583Y1316131D03*
X404921Y1321819D03*
X408787Y1321795D03*
X399959Y1352153D03*
X408159Y1349072D03*
X404759D03*
X395112Y1395690D03*
X398340Y1399779D03*
X395770Y1389817D03*
X410172Y1402446D03*
X402489Y1417275D03*
X405889D03*
X407970Y1449751D03*
X404500Y1452500D03*
X395888Y1450022D03*
X395199Y1482223D03*
X395380Y1485778D03*
X397266Y1514647D03*
X398747Y1500959D03*
X395370Y1501022D03*
X397266Y1518047D03*
X408964Y1531149D03*
X394391Y1537786D03*
Y1535286D03*
X399373Y1555855D03*
X405496Y1561024D03*
X400396D03*
X410596D03*
X397461Y1569560D03*
X401461D03*
X416900Y33400D03*
X422473Y22627D03*
X422450Y30483D03*
X422378Y26534D03*
X414145Y27486D03*
X413904Y32569D03*
X426147Y147540D03*
X414626Y176665D03*
Y168665D03*
Y196665D03*
Y192665D03*
X414739Y186778D03*
X414658Y204864D03*
Y208864D03*
X423651Y307470D03*
X419177Y304470D03*
X415777D03*
X422988Y323627D03*
X415129Y325181D03*
X412671Y333418D03*
X412812Y330617D03*
X426830Y359026D03*
X426138Y355079D03*
X416574Y357528D03*
X421413Y359053D03*
X412318Y367903D03*
X420422Y367859D03*
X418997Y382210D03*
Y384710D03*
Y387210D03*
X422215Y424939D03*
Y427439D03*
X414924Y435321D03*
Y438121D03*
X412124Y435321D03*
Y438121D03*
X414924Y440921D03*
X412124D03*
X414924Y443721D03*
X412124D03*
X426647Y452987D03*
X421267Y452799D03*
X414910Y448931D03*
X415433Y459170D03*
X425673Y461607D03*
X424876Y471334D03*
X418801Y474513D03*
X414275Y492469D03*
X424731Y492704D03*
X414275Y497469D03*
Y499969D03*
X427693Y498943D03*
X424731Y497704D03*
Y495204D03*
Y500204D03*
X414275Y494969D03*
X419340Y549990D03*
X419140Y547390D03*
Y544790D03*
X419340Y552590D03*
Y555190D03*
X423963Y625778D03*
X426607Y712360D03*
Y709760D03*
X424993Y728291D03*
X423700Y795500D03*
X426300Y797400D03*
X421200Y786400D03*
X411267Y829193D03*
Y831693D03*
X416267D03*
X413767D03*
Y829193D03*
X416267D03*
X425062Y883981D03*
X417121Y929686D03*
X425121D03*
X417121Y932186D03*
X425121D03*
X411960Y962261D03*
X414560D03*
X417160D03*
X411276Y978109D03*
X416476D03*
X413876D03*
X415047Y1058097D03*
X412547D03*
X415047Y1060697D03*
X412547D03*
X411989Y1082501D03*
X412015Y1085205D03*
X414989Y1082501D03*
X415015Y1085205D03*
Y1088205D03*
X412015D03*
X412297Y1091227D03*
X425060Y1101917D03*
X420782Y1105552D03*
X423340Y1104335D03*
X424995Y1106897D03*
X416988Y1104792D03*
X418495Y1106867D03*
X414580Y1113648D03*
X412080D03*
X411461Y1162384D03*
Y1164884D03*
Y1167384D03*
Y1169884D03*
Y1172384D03*
X420619Y1179421D03*
Y1181921D03*
Y1184421D03*
Y1186921D03*
X411461Y1174884D03*
X422934Y1192621D03*
Y1190121D03*
X417469Y1192621D03*
Y1190121D03*
X413063Y1221428D03*
X417063D03*
X421063D03*
X425063D03*
X413063Y1237428D03*
Y1233428D03*
Y1229428D03*
Y1225428D03*
X417063Y1237428D03*
Y1233428D03*
Y1229428D03*
Y1225428D03*
X421063Y1237428D03*
Y1233428D03*
Y1229428D03*
Y1225428D03*
X425063Y1237428D03*
Y1233428D03*
Y1229428D03*
Y1225428D03*
X413063Y1245428D03*
Y1241428D03*
X417063Y1245428D03*
Y1241428D03*
X421063Y1245428D03*
Y1241428D03*
X425063Y1245428D03*
Y1241428D03*
X425702Y1257160D03*
X422702Y1260160D03*
Y1257160D03*
X425702Y1260160D03*
X419702Y1257160D03*
Y1260160D03*
X413526Y1288938D03*
X419977Y1288843D03*
X413640Y1292856D03*
X419545Y1317722D03*
X413127Y1318011D03*
X425283Y1364023D03*
X417305Y1359169D03*
X425855Y1360495D03*
X425912Y1357141D03*
X416029Y1371572D03*
X420636Y1383912D03*
X418610Y1371590D03*
X423400Y1394500D03*
X423200Y1397500D03*
X418430Y1394237D03*
X422729Y1400490D03*
X420925Y1390330D03*
X419045Y1398874D03*
X421300Y1415400D03*
X419100Y1402200D03*
X421200Y1417900D03*
X411000Y1463500D03*
Y1460500D03*
Y1457500D03*
Y1454500D03*
Y1451000D03*
X413934Y1477101D03*
X417334D03*
X415202Y1496118D03*
Y1499518D03*
X417153Y1516886D03*
X413753D03*
X419619Y1539978D03*
X421454Y1544625D03*
X422539Y1534361D03*
X426701Y1541947D03*
X418151Y1552470D03*
X417461Y1569584D03*
X429919Y141247D03*
X437386Y143740D03*
X434766Y148277D03*
X431525Y304470D03*
X434925D03*
X427051Y307470D03*
X441296Y325061D03*
X436666Y322583D03*
X427713Y321965D03*
X430361Y323187D03*
X443424Y332988D03*
X440538Y355372D03*
X428420Y353578D03*
X435886Y353867D03*
X431524Y370309D03*
X434924D03*
X428637Y408104D03*
X431437D03*
X434237D03*
X428354Y420375D03*
X431154D03*
X433954D03*
X438098Y442114D03*
X437835Y435101D03*
X432270Y431112D03*
X432440Y440101D03*
X432075Y452718D03*
X438086Y452601D03*
X438078Y447121D03*
X433673Y461607D03*
X429673D03*
X435789Y501525D03*
X427568Y502003D03*
X435831Y498923D03*
X438644Y500461D03*
X428740Y549990D03*
X442804Y546990D03*
Y544390D03*
X428740Y546990D03*
Y544390D03*
Y555190D03*
Y552590D03*
X431384D03*
Y555190D03*
Y544390D03*
Y546990D03*
Y549990D03*
X443144Y628667D03*
X441162Y638313D03*
X439290Y712399D03*
X436790D03*
X439290Y709799D03*
X436790D03*
X434290Y712399D03*
Y709799D03*
X429290D03*
X431790Y712399D03*
X429290D03*
X431790Y709799D03*
X429253Y759847D03*
X432303Y785067D03*
X434100Y797400D03*
X430600D03*
X443091Y1026266D03*
X432678Y1016186D03*
X429878D03*
X427078D03*
X427052Y1019384D03*
X429852D03*
X432652D03*
X433378Y1091816D03*
Y1089316D03*
X430878Y1084316D03*
Y1086816D03*
X433378D03*
Y1084316D03*
X436244Y1090288D03*
X433378Y1081816D03*
X430878D03*
X429677Y1106955D03*
X439023Y1107997D03*
X436244Y1093088D03*
X434823Y1107997D03*
X431476Y1115896D03*
X427810Y1110092D03*
X439908Y1113648D03*
X441359Y1116101D03*
Y1118801D03*
X439123Y1110597D03*
X434823Y1113797D03*
Y1110897D03*
X437023Y1112397D03*
X436923Y1109397D03*
X431476Y1118396D03*
X429348Y1129092D03*
X432838Y1128821D03*
X436789Y1167384D03*
Y1164884D03*
Y1162384D03*
Y1172384D03*
Y1169884D03*
X439289Y1167384D03*
Y1164884D03*
Y1162384D03*
X427231D03*
X429731D03*
Y1164884D03*
Y1167384D03*
Y1169884D03*
Y1172384D03*
X427231D03*
Y1169884D03*
Y1167384D03*
Y1164884D03*
X439289Y1172384D03*
Y1169884D03*
X437132Y1158266D03*
X433249Y1186709D03*
Y1184209D03*
Y1181709D03*
Y1179209D03*
X429731Y1174884D03*
X427231D03*
X436789D03*
X439289D03*
X430934Y1190121D03*
Y1192621D03*
X429063Y1221428D03*
X433063D03*
X429063Y1237428D03*
Y1233428D03*
Y1229428D03*
Y1225428D03*
X433063Y1237428D03*
Y1233428D03*
Y1229428D03*
Y1225428D03*
X429063Y1245428D03*
Y1241428D03*
X433063Y1245428D03*
Y1241428D03*
X440702Y1260160D03*
Y1257160D03*
X437702Y1260160D03*
Y1257160D03*
X428702D03*
X431702Y1260160D03*
Y1257160D03*
X434702Y1260160D03*
Y1257160D03*
X428702Y1260160D03*
X434424Y1286274D03*
X430527Y1289198D03*
X440906D03*
X431867Y1315696D03*
X431885Y1313115D03*
X439434Y1322369D03*
X429530Y1325051D03*
X445949Y141247D03*
X450436Y143518D03*
X449536Y152373D03*
X452686Y152562D03*
X458181Y157370D03*
X443508Y337713D03*
X446566Y337917D03*
X443480Y344014D03*
X450852Y372054D03*
X455885Y367702D03*
X448391Y382641D03*
X448323Y379643D03*
X451144Y468809D03*
X459414Y468689D03*
X459757Y463520D03*
X459461Y473805D03*
X459929Y491669D03*
X450942Y506449D03*
X448442D03*
X445942D03*
X460537Y501905D03*
X459952Y496842D03*
X459645Y509486D03*
X446025Y511512D03*
X448525D03*
X446025Y519699D03*
X448525D03*
X452404Y549790D03*
X443004Y549890D03*
X452404Y546990D03*
Y544390D03*
X443004Y555090D03*
X452404Y552390D03*
Y554990D03*
X443004Y552490D03*
X455009Y554912D03*
Y552312D03*
Y544312D03*
Y546912D03*
Y549712D03*
X447279Y637031D03*
X447921Y630789D03*
X453552Y631779D03*
X446987Y643360D03*
X456469Y638302D03*
X460498Y870334D03*
X458120Y974701D03*
X451460Y974695D03*
X450591Y1004766D03*
X453270Y1003763D03*
X459360Y1012325D03*
X443591Y1019766D03*
X459885Y1018860D03*
X451140Y1021793D03*
X447091Y1019766D03*
X450875Y1028416D03*
X443091Y1034266D03*
X452091Y1039880D03*
X459700Y1032266D03*
X455468Y1104335D03*
X457188Y1101917D03*
X452910Y1105552D03*
X457123Y1106897D03*
X449116Y1104792D03*
X450623Y1106867D03*
X444208Y1113648D03*
X446708D03*
X457559Y1169884D03*
Y1167384D03*
Y1164884D03*
Y1162384D03*
X455059D03*
Y1164884D03*
Y1167384D03*
Y1169884D03*
Y1172384D03*
X457559D03*
X455059Y1174884D03*
X457559D03*
X447549Y1179421D03*
Y1181921D03*
Y1184421D03*
Y1186921D03*
X449864Y1190121D03*
Y1192621D03*
X449702Y1260160D03*
Y1257160D03*
X443702Y1260160D03*
X446702D03*
Y1257160D03*
X443702D03*
X451304Y1297045D03*
X454385Y1301845D03*
Y1305245D03*
X444288Y1314391D03*
X462089Y116594D03*
X474058D03*
X473032Y110784D03*
X468032D03*
X462089Y119594D03*
X474058D03*
X477592Y125107D03*
X462523Y124283D03*
X467589Y124879D03*
X472611Y124663D03*
X473955Y138838D03*
X460930Y161306D03*
X467346Y218085D03*
X470146D03*
X473946Y216385D03*
X475293Y244571D03*
X472673Y249108D03*
X464054Y248371D03*
X460950Y328185D03*
Y324785D03*
X463950Y332659D03*
Y336059D03*
X460950Y343933D03*
Y340533D03*
X472810Y347995D03*
X472913Y360089D03*
X472608Y352495D03*
X467335Y359944D03*
X463950Y351807D03*
Y348407D03*
X472913Y369089D03*
Y373589D03*
X469530Y366754D03*
X472913Y387089D03*
Y391589D03*
Y382589D03*
Y378089D03*
X470796Y394592D03*
X464848Y464566D03*
X467848D03*
X465126Y460435D03*
X462126D03*
X473658Y470509D03*
Y475509D03*
X467848Y476535D03*
X464848D03*
X468558Y495669D03*
Y499669D03*
Y516609D03*
X464199Y510184D03*
X468850Y545586D03*
X469300Y799500D03*
X459245Y807152D03*
X473654Y821234D03*
X472399Y839566D03*
X463404Y846870D03*
X465492Y861970D03*
X471726Y883705D03*
X474540Y927341D03*
X471110Y921577D03*
X471876Y937236D03*
X471068Y930235D03*
X473992Y952546D03*
X475018Y992568D03*
X467345Y996480D03*
X459360Y1004680D03*
X464795Y1000647D03*
X462185Y1016825D03*
X459860Y1015825D03*
X464385Y1038534D03*
X471558Y1029482D03*
X471755Y1038665D03*
X470610Y1033783D03*
X475588Y1043055D03*
X473639Y1030952D03*
X459700Y1035716D03*
X470978Y1046591D03*
X474348Y1090171D03*
X462913Y1106365D03*
X474277Y1093048D03*
X472482Y1107997D03*
X468282D03*
X459938Y1110092D03*
X463604Y1115896D03*
X473367Y1113648D03*
X474818Y1116101D03*
Y1118801D03*
X472582Y1110597D03*
X470482Y1112397D03*
X468282Y1110897D03*
Y1113797D03*
X470382Y1109397D03*
X463604Y1118396D03*
X462687Y1160834D03*
X474548Y1172384D03*
Y1169884D03*
Y1167384D03*
Y1164884D03*
Y1162384D03*
X468850Y1160834D03*
X474548Y1174884D03*
X465785Y1197471D03*
X461285Y1193471D03*
Y1197471D03*
X465785Y1193471D03*
X474647Y1260160D03*
Y1257160D03*
X471647D03*
Y1260160D03*
X459290Y1297035D03*
X463290D03*
X492135Y103411D03*
X492529Y97667D03*
X483675D03*
X487925Y95111D03*
X479331Y102495D03*
X479065Y142862D03*
X486206Y143762D03*
X480106Y148717D03*
X487654Y195176D03*
X489672Y199248D03*
X485154Y195176D03*
X482654D03*
X486672Y199248D03*
X490154Y195176D03*
X485235Y210509D03*
X482735D03*
X489672Y202048D03*
X486672Y201748D03*
X484508Y206806D03*
X487008D03*
X476659Y216970D03*
Y219470D03*
X476725Y226320D03*
X476659Y221970D03*
X493272Y230117D03*
X484427Y230556D03*
X488682Y227824D03*
X479686Y228646D03*
X483412Y242078D03*
X478643Y232971D03*
X488769Y246874D03*
X489288Y238714D03*
X490989Y244297D03*
X482636Y256394D03*
X492817Y357111D03*
X491843Y351089D03*
X481724Y373589D03*
Y369089D03*
X490885Y373589D03*
X491053Y365423D03*
X491289Y391589D03*
X481724Y382589D03*
Y378089D03*
X490885Y382570D03*
X490985Y412342D03*
X488438Y418417D03*
X485485Y439903D03*
X489485D03*
X481485Y439900D03*
Y431917D03*
X489485Y431417D03*
X492736Y491982D03*
X482836Y534249D03*
X491818Y534909D03*
X491445Y541135D03*
X482905Y527726D03*
Y548726D03*
Y544726D03*
X491534Y552726D03*
X491511Y546553D03*
X487209Y611071D03*
X484772Y621311D03*
X493392Y622285D03*
X493580Y616905D03*
X484772Y629311D03*
Y625311D03*
X493661Y627713D03*
X493778Y633724D03*
X481165Y646036D03*
X483059Y662649D03*
X488765Y667224D03*
X481742Y657477D03*
X486837Y701306D03*
Y704706D03*
X489406Y797558D03*
X489572Y822805D03*
X479448Y828594D03*
X479700Y847600D03*
X477574Y860815D03*
X490706Y859339D03*
X491616Y938771D03*
X476475Y952249D03*
X479613Y952189D03*
X489163Y977163D03*
X487091Y989550D03*
X480711Y999941D03*
X477857Y1004375D03*
X488041Y1020440D03*
X485678Y1039880D03*
X485633Y1036155D03*
X477765Y1093432D03*
X477607Y1089942D03*
X491503Y1086796D03*
Y1084296D03*
X478517Y1086724D03*
Y1084224D03*
Y1081724D03*
X476017D03*
Y1084224D03*
Y1086724D03*
X486369Y1105552D03*
X490647Y1101917D03*
X488927Y1104335D03*
X490582Y1106897D03*
X482575Y1104792D03*
X484082Y1106867D03*
X480167Y1113648D03*
X477667D03*
X477048Y1172384D03*
Y1169884D03*
Y1167384D03*
Y1164884D03*
Y1162384D03*
X479521Y1179209D03*
Y1181709D03*
Y1184209D03*
Y1186709D03*
X477048Y1174884D03*
X490671Y1192621D03*
Y1190121D03*
X477206Y1192621D03*
Y1190121D03*
X489647Y1260160D03*
Y1257160D03*
X486647D03*
Y1260160D03*
X480647Y1257160D03*
X477647D03*
Y1260160D03*
X480647D03*
X483647Y1257160D03*
Y1260160D03*
X490100Y1302100D03*
X487600D03*
X503325Y90650D03*
X508637Y90615D03*
X503075Y95236D03*
X492294Y106561D03*
X496023Y362913D03*
X497048Y369450D03*
X495750Y377531D03*
X506500Y379687D03*
X495203Y386890D03*
X503729Y439919D03*
X503682Y448419D03*
X500729Y469905D03*
X496729Y470419D03*
X504729Y469905D03*
X496729Y461919D03*
X504729Y461419D03*
X505476Y485128D03*
X497095Y481467D03*
X501224Y492050D03*
X501649Y482165D03*
X501887Y504825D03*
X499387D03*
X496887D03*
X500890Y500202D03*
X502493Y495917D03*
X492736Y495982D03*
X501828Y517401D03*
X499328D03*
X496828D03*
X502379Y522569D03*
X495444Y531948D03*
X503494Y531882D03*
X502379Y525369D03*
X500994Y531882D03*
X498494D03*
X504079Y529169D03*
X503729Y555194D03*
X500929D03*
Y571194D03*
X503729D03*
Y563194D03*
X500929D03*
X505286Y581222D03*
X502486D03*
X505286Y591215D03*
X502486D03*
X505458Y610562D03*
X502658D03*
Y607762D03*
X505458D03*
X497448Y610548D03*
X504265Y633736D03*
X499258Y633716D03*
X506278Y628078D03*
X494465Y657772D03*
X502755Y657694D03*
X496070Y665976D03*
X499528Y657843D03*
X504966Y678098D03*
X498284Y681453D03*
Y678953D03*
X500714Y708755D03*
X502832Y720491D03*
X504895Y770457D03*
X501495D03*
X504508Y783817D03*
X506166Y793224D03*
X504641Y789139D03*
X507095Y814784D03*
X494677Y830468D03*
X509665Y824512D03*
X495073Y835586D03*
X495470Y844271D03*
X495700Y849389D03*
X503383Y863025D03*
X498507Y865392D03*
X508248Y873319D03*
X509791Y881932D03*
X509017Y905295D03*
X494315Y941212D03*
X503144Y957934D03*
X504088Y985171D03*
X506888D03*
X506702Y978947D03*
X493091Y989550D03*
X503933Y981392D03*
X498435Y1008766D03*
X506566D03*
Y996766D03*
X498524Y997590D03*
X498585Y1016266D03*
X506566Y1012266D03*
X503177Y1058097D03*
X495677D03*
X493177D03*
X498177D03*
X500677D03*
X503177Y1060697D03*
X495677D03*
X493177D03*
X498177D03*
X500677D03*
X494003Y1086796D03*
X496503D03*
X499003D03*
X501503D03*
Y1084296D03*
X499003D03*
X496503D03*
X494003D03*
X501831Y1090288D03*
X496372Y1106298D03*
X504610Y1107997D03*
X501831Y1093088D03*
X500410Y1107997D03*
X497063Y1115896D03*
X505495Y1113648D03*
X506946Y1116101D03*
Y1118801D03*
X504710Y1110597D03*
X500410Y1113797D03*
X502610Y1112397D03*
X500410Y1110897D03*
X502510Y1109397D03*
X493397Y1110092D03*
X497063Y1118396D03*
X498727Y1128759D03*
X495236Y1129094D03*
X502376Y1172384D03*
Y1169884D03*
Y1167384D03*
Y1164884D03*
Y1162384D03*
X504876Y1172384D03*
Y1169884D03*
Y1167384D03*
Y1164884D03*
Y1162384D03*
X492818D03*
Y1164884D03*
Y1167384D03*
Y1169884D03*
Y1172384D03*
X495318D03*
Y1169884D03*
Y1167384D03*
Y1164884D03*
Y1162384D03*
X502562Y1158200D03*
X506451Y1179209D03*
Y1181709D03*
Y1184209D03*
Y1186709D03*
X504876Y1174884D03*
X493821Y1186921D03*
Y1184421D03*
Y1181921D03*
Y1179421D03*
X492818Y1174884D03*
X495318D03*
X502376D03*
X504136Y1190121D03*
Y1192621D03*
X496136Y1190121D03*
Y1192621D03*
X506562Y1222194D03*
X502562D03*
X498562D03*
X494562D03*
X506562Y1226194D03*
Y1230194D03*
Y1234194D03*
Y1238194D03*
X502562Y1226194D03*
Y1230194D03*
Y1234194D03*
Y1238194D03*
X498562Y1226194D03*
Y1230194D03*
Y1234194D03*
Y1238194D03*
X494562Y1226194D03*
Y1230194D03*
Y1234194D03*
Y1238194D03*
Y1246194D03*
Y1242194D03*
X506562D03*
Y1246194D03*
X502562Y1242194D03*
Y1246194D03*
X498562Y1242194D03*
Y1246194D03*
X504647Y1257160D03*
X507347D03*
X501647D03*
Y1260160D03*
X495647D03*
X492647D03*
Y1257160D03*
X495647D03*
X498647D03*
Y1260160D03*
X507347D03*
X504647D03*
X521872Y82593D03*
Y85193D03*
Y74793D03*
Y77393D03*
Y79993D03*
X521916Y92874D03*
X512958Y99961D03*
X513008Y95236D03*
X523943Y107649D03*
Y104249D03*
X520965Y162368D03*
X523565D03*
X511820Y207978D03*
Y210478D03*
Y215478D03*
Y212978D03*
X522276Y208213D03*
Y213213D03*
Y210713D03*
Y215713D03*
X515149Y264180D03*
X517649D03*
X515074Y258880D03*
X524043Y270026D03*
Y267526D03*
X514769Y312953D03*
X519638Y314346D03*
X511790Y313804D03*
X512943Y443071D03*
X520823Y442603D03*
X511753Y454339D03*
Y456839D03*
X509253D03*
Y454339D03*
X518240Y459371D03*
X509253Y459339D03*
X511753D03*
X512210Y475825D03*
X517310Y470045D03*
X513310Y462004D03*
X522756Y461818D03*
X508325Y485138D03*
X512210Y478625D03*
X513910Y482425D03*
X513325Y485138D03*
X510825D03*
X519786Y491214D03*
X523489Y492987D03*
X519786Y493714D03*
X523489Y495487D03*
X509955Y537958D03*
X513658Y539731D03*
X518716Y541895D03*
X521216Y544895D03*
Y541895D03*
X513658Y542231D03*
X518416Y544895D03*
X509955Y540458D03*
X521494Y582747D03*
X508086Y581222D03*
X520945Y590801D03*
X508086Y591215D03*
X520770Y597130D03*
X524770Y605637D03*
X518940Y620653D03*
Y617853D03*
X511058Y610562D03*
Y607762D03*
X508258Y610562D03*
Y607762D03*
X520770Y605443D03*
X516770D03*
X523616Y625013D03*
X515267Y627908D03*
X511278Y633473D03*
X521778Y642184D03*
X521868Y666577D03*
X518812Y662874D03*
X510425Y683246D03*
X522200Y677613D03*
X521540Y686319D03*
X515484Y695757D03*
X515504Y701351D03*
X521159Y706388D03*
X515649D03*
X512530Y718301D03*
X514531Y716398D03*
X523929Y706388D03*
X518389D03*
X521131Y741071D03*
X517731D03*
X511724Y741035D03*
X508324D03*
X520549Y761982D03*
X509096Y753072D03*
X515422Y753455D03*
X513504Y755804D03*
X513278Y783286D03*
X520833Y773389D03*
X513551Y773203D03*
X522697Y797102D03*
X519891Y795848D03*
X518157Y803973D03*
X518565Y811973D03*
X520741Y805149D03*
X522481Y824661D03*
X517702Y826600D03*
X514682Y834590D03*
X511741Y846649D03*
X524741Y845149D03*
X520870Y874694D03*
X525159Y913818D03*
X521572Y901500D03*
X516902Y910251D03*
X520146Y939241D03*
X523289Y939195D03*
X521353Y952266D03*
X522544Y992854D03*
X512232Y985172D03*
X514566Y1000766D03*
X514690Y996766D03*
Y1004766D03*
X514566Y1016266D03*
X514649Y1020266D03*
X514843Y1030766D03*
X519500Y1028377D03*
X518497Y1105552D03*
X522775Y1101917D03*
X521055Y1104335D03*
X514703Y1104792D03*
X522710Y1106897D03*
X516210Y1106867D03*
X509795Y1113648D03*
X512295D03*
X520646Y1169884D03*
Y1167384D03*
Y1164884D03*
Y1162384D03*
X523146D03*
Y1164884D03*
Y1167384D03*
Y1169884D03*
Y1172384D03*
X520646D03*
X520751Y1186921D03*
Y1184421D03*
Y1181921D03*
Y1179421D03*
X523146Y1174884D03*
X520646D03*
X523066Y1190121D03*
Y1192621D03*
X522562Y1222194D03*
X518562D03*
X514562D03*
X510562D03*
X522562Y1226194D03*
X518562D03*
Y1230194D03*
Y1234194D03*
X514562Y1226194D03*
Y1230194D03*
Y1234194D03*
Y1238194D03*
X510562Y1226194D03*
Y1230194D03*
Y1234194D03*
Y1238194D03*
X514562Y1242194D03*
Y1246194D03*
X510562Y1242194D03*
Y1246194D03*
X530197Y98551D03*
X540751Y97475D03*
X533092Y114623D03*
Y111223D03*
X533747Y103783D03*
X533092Y128796D03*
Y125396D03*
X532281Y141247D03*
X528509Y147540D03*
X539748Y143740D03*
X537128Y148277D03*
X530665Y162793D03*
Y165393D03*
Y170493D03*
Y167993D03*
X538170Y172190D03*
X535668Y181009D03*
X529662Y181426D03*
X532873Y181366D03*
X537589Y177616D03*
X529870Y184221D03*
X532487Y184012D03*
X533906Y211359D03*
Y213859D03*
X528848Y211695D03*
X537609Y213132D03*
X526348Y208695D03*
X529148D03*
X526348Y211695D03*
X537609Y215632D03*
X537853Y256303D03*
X532525Y265701D03*
X537612Y265896D03*
X526843Y270026D03*
X529343D03*
X526843Y267526D03*
X529343D03*
X534160Y281716D03*
X540101Y281982D03*
X532659Y359557D03*
X526388Y351301D03*
X531612Y354272D03*
X531636Y349057D03*
X528812Y369164D03*
X533211Y364746D03*
X533115Y371856D03*
X530144Y376062D03*
X531953Y380749D03*
X542034Y392209D03*
X541706Y386223D03*
X533189Y390723D03*
X531953Y385749D03*
X531992Y397552D03*
X526216Y456652D03*
X528716D03*
X526216Y459152D03*
Y461652D03*
X528716Y459152D03*
Y461652D03*
X535119Y491133D03*
X531047Y498151D03*
X535119Y493633D03*
Y496133D03*
Y498633D03*
X531047Y495151D03*
X528547D03*
X528247Y498151D03*
X525288Y537877D03*
X535219Y555897D03*
Y553297D03*
X533488Y548344D03*
X525288Y540377D03*
Y545377D03*
Y542877D03*
X528488Y548344D03*
X525988D03*
X530988D03*
X535219Y561097D03*
Y563697D03*
Y566797D03*
Y558497D03*
X532009Y570478D03*
X529214Y570686D03*
X529423Y573303D03*
X532069Y573689D03*
X532426Y576484D03*
X535819Y578405D03*
X541245Y578986D03*
X524770Y597232D03*
X534820Y596782D03*
X540770Y596729D03*
X529601Y596089D03*
X526756Y613913D03*
Y616713D03*
Y619513D03*
X538826Y614158D03*
Y616958D03*
Y619758D03*
X536770Y605443D03*
X537664Y661556D03*
X534264D03*
X529664Y664056D03*
X526264D03*
X538316Y687357D03*
X535738Y687489D03*
X536087Y702364D03*
X529469Y706230D03*
X526699Y706388D03*
X535585Y736593D03*
X538985D03*
X530985Y741593D03*
X527585D03*
X524598Y753387D03*
X539449Y782389D03*
X537578Y772428D03*
X532304Y806649D03*
X531313Y812850D03*
Y826630D03*
X532316Y833649D03*
X534000Y843000D03*
X537300Y842900D03*
X530741Y845149D03*
X534632Y849830D03*
X525718Y873821D03*
X533468Y878533D03*
X538468Y888033D03*
X530968Y888283D03*
X528975Y898346D03*
X537279Y897943D03*
X533143Y897910D03*
X531076Y913190D03*
X527879Y952189D03*
X530473Y961728D03*
X528500Y1106365D03*
X529191Y1115896D03*
X525525Y1110092D03*
X529191Y1118396D03*
X528274Y1160834D03*
X554198Y68581D03*
X554211Y80581D03*
X546293Y76587D03*
Y72615D03*
X547732Y100625D03*
X540682Y106186D03*
X552105Y112083D03*
X556394Y103621D03*
X543494Y121735D03*
Y132509D03*
Y118335D03*
Y135909D03*
X548311Y141247D03*
X552798Y143518D03*
X551898Y152373D03*
X555048Y152562D03*
X540843Y168697D03*
X555850Y178560D03*
X555913Y172665D03*
X555740Y183834D03*
X541931Y191941D03*
X555260Y190185D03*
X549985Y192490D03*
X556030Y200864D03*
X548940Y206767D03*
X546440D03*
X543940D03*
X556119Y212455D03*
X556053Y207037D03*
X549070Y221708D03*
X546570D03*
X553420Y221642D03*
X545185Y231021D03*
Y228221D03*
X544070Y221708D03*
X543485Y224421D03*
X550736Y236189D03*
X548236D03*
X545736D03*
X550677Y248765D03*
X548177D03*
X545677D03*
X542628Y266114D03*
X545874Y268195D03*
X548374D03*
X551174Y270695D03*
X554834Y265897D03*
X551174Y268195D03*
X548374Y270695D03*
X545874D03*
X551536Y359223D03*
Y354723D03*
Y350223D03*
Y345723D03*
Y377223D03*
Y372723D03*
Y368223D03*
Y363723D03*
Y381723D03*
X551620Y390723D03*
X553563Y384987D03*
X544738Y581659D03*
X544770Y605443D03*
X551475Y661504D03*
X547227Y678299D03*
X547276Y675521D03*
X543101Y698772D03*
X540379Y719785D03*
X557751Y750851D03*
X550420Y793743D03*
X556326D03*
X540578Y793889D03*
X544515Y793875D03*
X544741Y809649D03*
X544878Y816309D03*
X546855Y829949D03*
X550087Y829836D03*
X556326Y829989D03*
X556741Y820149D03*
X544741Y823149D03*
X546241Y843149D03*
X557836Y851669D03*
X548665Y850399D03*
X540968Y878360D03*
X546940Y871389D03*
X548327Y905295D03*
X552238Y959102D03*
X552923Y988813D03*
X542793Y998507D03*
X544719Y1007522D03*
X551485Y1006648D03*
X551673Y1023900D03*
X548852Y1018307D03*
X545094Y1013678D03*
X545566Y1023731D03*
X554696Y1018469D03*
X556493Y1118351D03*
X557584Y1543411D03*
X560573Y60513D03*
X563433Y60438D03*
X557973Y55513D03*
X569114Y86012D03*
X558341Y88801D03*
X569114Y94374D03*
X561258Y94351D03*
X565207Y94279D03*
X560701Y85731D03*
X564255Y86046D03*
X564451Y116594D03*
X570394Y110784D03*
X564451Y119594D03*
X574973Y124663D03*
X564885Y124283D03*
X569951Y124879D03*
X563292Y161306D03*
X560543Y157370D03*
X564627Y176665D03*
Y168665D03*
X556726Y186629D03*
X564627Y196665D03*
Y192665D03*
X564740Y186778D03*
X564659Y204864D03*
Y208864D03*
X569708Y218085D03*
X572508D03*
X560300Y219379D03*
X560928Y228631D03*
X575035Y249108D03*
X566416Y248371D03*
X557334Y265897D03*
X573479Y374705D03*
X569938Y378317D03*
X559070Y684809D03*
Y700809D03*
Y688209D03*
X561570Y696209D03*
Y692809D03*
X559070Y716809D03*
X561570Y708809D03*
Y712209D03*
X559070Y704209D03*
Y720209D03*
X558616Y732530D03*
X562001Y732834D03*
X562374Y721593D03*
X567428Y750145D03*
X557847Y744599D03*
X563200Y739600D03*
X571493Y763090D03*
X570038Y752339D03*
X564362Y757979D03*
X560263Y782207D03*
X567126Y779066D03*
X571984Y784507D03*
X561001Y806889D03*
X567559Y803008D03*
Y824661D03*
X562400Y818900D03*
X560813Y840574D03*
X568990Y844721D03*
X572476Y845535D03*
X559295Y874267D03*
X559887Y877196D03*
X561134Y869291D03*
X559260Y891043D03*
X559214Y897425D03*
X564165Y894411D03*
X567827Y884000D03*
X562328Y957307D03*
X566303Y951807D03*
X569403D03*
X563103D03*
X570603Y957207D03*
X560923Y980443D03*
X556923Y980523D03*
X564923Y988813D03*
X560923D03*
X556923D03*
X568923D03*
X558112Y1009655D03*
X560912D03*
X567484Y1024003D03*
X571857Y1016827D03*
X559057Y1030563D03*
X562057D03*
X568057Y1030672D03*
X565057D03*
X571857Y1029427D03*
X566058Y1109564D03*
X560211D03*
X566058Y1122164D03*
X560211D03*
X566058Y1134764D03*
X560211D03*
X566058Y1147364D03*
X560211D03*
X566058Y1159964D03*
X560211D03*
X566058Y1172564D03*
X560211D03*
X566058Y1185164D03*
X560211D03*
X568532Y1200001D03*
X575620Y1207737D03*
X569135Y1214372D03*
X564890Y1218169D03*
X570796Y1530309D03*
X567324Y1528151D03*
X572432Y1521462D03*
X565400Y1535100D03*
X563968Y1541445D03*
X568279Y1538438D03*
X572507Y1541375D03*
X586037Y97667D03*
X581693Y102495D03*
X576420Y116594D03*
X575394Y110784D03*
X576420Y119594D03*
X579954Y125107D03*
X581427Y142862D03*
X588568Y143762D03*
X582468Y148717D03*
X576317Y138838D03*
X587516Y195176D03*
X585016D03*
X589034Y199248D03*
X587597Y210509D03*
X585097D03*
X589034Y201748D03*
X586870Y206806D03*
X576308Y216385D03*
X579021Y216970D03*
Y219470D03*
X579087Y226320D03*
X579021Y221970D03*
X586789Y230556D03*
X591044Y227824D03*
X582048Y228646D03*
X585774Y242078D03*
X581005Y232971D03*
X577655Y244571D03*
X584998Y256394D03*
X578193Y336391D03*
X584679Y336285D03*
X576556Y728219D03*
X575979Y732517D03*
X573778Y747437D03*
X577638Y769772D03*
X578271Y763556D03*
X583102Y767137D03*
X587183Y785008D03*
X578204Y775137D03*
X585912Y778470D03*
X588345Y798030D03*
X588659Y790336D03*
X582100Y787600D03*
X586060Y793145D03*
X581001Y810973D03*
X588377Y807536D03*
X588272Y804601D03*
X588231Y801520D03*
X577501Y829069D03*
X588001Y829624D03*
X582737Y819831D03*
X581158Y823473D03*
X573300Y829600D03*
X579827Y888000D03*
X580327Y892000D03*
X586136Y908935D03*
X583065Y903294D03*
X573103Y941307D03*
X585703D03*
X586103Y961807D03*
X573895Y965319D03*
X584923Y988813D03*
X576923D03*
X580923D03*
X588923D03*
X572923D03*
X577704Y1029427D03*
Y1016827D03*
X587880Y1034834D03*
X581967Y1105091D03*
X587467D03*
X582012Y1102091D03*
X587467Y1117691D03*
X581967D03*
X582012Y1127291D03*
Y1114691D03*
X587467Y1130291D03*
X581967D03*
X587467Y1142891D03*
X582012Y1139891D03*
X581967Y1155491D03*
X587467D03*
X581967Y1142891D03*
X582012Y1152491D03*
X581967Y1168091D03*
X587467D03*
X582012Y1165091D03*
X581967Y1180691D03*
X587467D03*
X582012Y1177691D03*
X586502Y1227300D03*
X583520Y1230407D03*
X581803Y1493687D03*
X578859Y1497758D03*
X588859Y1490895D03*
X590826Y1495688D03*
X588507Y1514141D03*
X582027Y1502800D03*
X581803Y1509687D03*
X577931Y1505687D03*
X575809Y1532912D03*
X572849Y1518702D03*
X587809Y1528389D03*
X583809Y1533025D03*
X579809Y1528163D03*
X587809Y1545854D03*
X583809Y1541607D03*
X577571Y1544013D03*
X594497Y103411D03*
X594891Y97667D03*
X605687Y90650D03*
X590287Y95111D03*
X594656Y106561D03*
X590016Y195176D03*
X592516D03*
X592034Y199248D03*
Y202048D03*
X589370Y206806D03*
X595634Y230117D03*
X591131Y246874D03*
X591650Y238714D03*
X593351Y244297D03*
X592900Y309871D03*
X605147Y378600D03*
Y382600D03*
X605262Y458711D03*
X602462D03*
X604606Y463600D03*
X598462Y504684D03*
X599110Y552466D03*
X605011Y603600D03*
Y619600D03*
Y623600D03*
X592272Y877262D03*
X592110Y895611D03*
X601084Y913544D03*
X604715Y914640D03*
X589203Y941407D03*
X591403Y938807D03*
Y936007D03*
X591754Y956979D03*
X597556Y965829D03*
X602484Y965764D03*
X600923Y988813D03*
X592923D03*
X604923D03*
X596923D03*
X599113Y1012354D03*
X593658Y1009354D03*
X593613Y1012354D03*
X599113Y1024954D03*
X593613D03*
X593658Y1021954D03*
X606434Y1041904D03*
X603682Y1053457D03*
X594183Y1220068D03*
X593519Y1224472D03*
X592885Y1229402D03*
X592634Y1234921D03*
X591487Y1501687D03*
X591481Y1509313D03*
X595809Y1532133D03*
X591872Y1518071D03*
X595809Y1546214D03*
X591809Y1542407D03*
X610999Y90615D03*
X615370Y95236D03*
X615320Y99961D03*
X605437Y95236D03*
X620727Y162368D03*
X614182Y210478D03*
Y215478D03*
Y212978D03*
Y207978D03*
X617511Y264180D03*
X620011D03*
X617436Y258880D03*
X607789Y453682D03*
X606026Y455921D03*
X609133Y941137D03*
X605733D03*
X608965Y966414D03*
X616923Y988813D03*
X608923D03*
X612923Y997860D03*
X618878Y1011914D03*
X621479Y1030482D03*
X607993Y1036920D03*
X610780Y1051037D03*
X617634Y1049283D03*
X617894Y1043955D03*
X612955Y1062941D03*
X622736Y1151870D03*
Y1159350D03*
X613738Y1546507D03*
X624234Y74793D03*
Y82593D03*
Y85193D03*
Y77393D03*
Y79993D03*
X624278Y92874D03*
X632559Y98551D03*
X635454Y114623D03*
Y111223D03*
X636109Y103783D03*
X626305Y104249D03*
Y107649D03*
X635454Y128796D03*
Y125396D03*
X630871Y147540D03*
X634643Y141247D03*
X639490Y148277D03*
X625927Y162368D03*
X623327D03*
X633027Y165393D03*
Y162793D03*
Y170493D03*
Y167993D03*
X639951Y177616D03*
X632024Y181426D03*
X635235Y181366D03*
X632232Y184221D03*
X634849Y184012D03*
X628710Y211695D03*
Y208695D03*
X631510D03*
X624638Y208213D03*
X636268Y211359D03*
Y213859D03*
X631210Y211695D03*
X624638Y213213D03*
Y210713D03*
Y215713D03*
X639974Y265896D03*
X634887Y265701D03*
X629205Y267526D03*
X626405D03*
X631705D03*
X629205Y270026D03*
X626405D03*
X631705D03*
X636522Y281716D03*
X632009Y541863D03*
Y545263D03*
X630201Y553407D03*
X632701D03*
X630201Y550907D03*
X632701D03*
X634185Y569426D03*
X634471Y566929D03*
X628425Y572070D03*
X629772Y569928D03*
X632119Y570962D03*
X631862Y568475D03*
X621592Y1033862D03*
X626476Y1155610D03*
X621727Y1556800D03*
X648655Y76587D03*
Y72615D03*
X650094Y100625D03*
X643113Y97475D03*
X643044Y106186D03*
X645856Y118335D03*
Y132509D03*
Y121735D03*
Y135909D03*
X650673Y141247D03*
X655160Y143518D03*
X642110Y143740D03*
X654260Y152373D03*
X640532Y172190D03*
X638030Y181009D03*
X643205Y168697D03*
X644293Y191941D03*
X652347Y192490D03*
X646302Y206767D03*
X651302D03*
X648802D03*
X639971Y213132D03*
X648932Y221708D03*
X647547Y228221D03*
X645847Y224421D03*
X647547Y231021D03*
X646432Y221708D03*
X651432D03*
X639971Y215632D03*
X650598Y236189D03*
X648098D03*
X653098D03*
X653039Y248765D03*
X650539D03*
X648039D03*
X640215Y256303D03*
X644990Y266114D03*
X650736Y268195D03*
X653536Y270695D03*
Y268195D03*
X650736Y270695D03*
X648236D03*
Y268195D03*
X642463Y281982D03*
X642414Y545528D03*
X651149Y577716D03*
X648211Y610400D03*
X650958Y668153D03*
X662935Y60513D03*
X665795Y60438D03*
X657507Y58013D03*
X656560Y68581D03*
X671476Y86012D03*
X656573Y80581D03*
X660703Y88801D03*
X663620Y94351D03*
X667569Y94279D03*
X663063Y85731D03*
X666617Y86046D03*
X658756Y103621D03*
X666813Y116594D03*
X654467Y112083D03*
X666813Y119594D03*
X667247Y124283D03*
X672313Y124879D03*
X665654Y161306D03*
X657410Y152562D03*
X662905Y157370D03*
X666989Y176665D03*
Y168665D03*
X658275Y172665D03*
X658212Y178560D03*
X658102Y183834D03*
X659088Y186629D03*
X657622Y190185D03*
X658392Y200864D03*
X666989Y196665D03*
Y192665D03*
X667102Y186778D03*
X667021Y204864D03*
Y208864D03*
X658481Y212455D03*
X658415Y207037D03*
X655782Y221642D03*
X662662Y219379D03*
X663290Y228631D03*
X668886Y248371D03*
X657196Y265897D03*
X659696D03*
X661761Y382109D03*
X661760Y551683D03*
Y561420D03*
Y558917D03*
X657581Y577937D03*
X660586Y606929D03*
X665086Y604567D03*
X665586Y595500D03*
X660827Y612592D03*
X666244Y610072D03*
X660546Y618400D03*
X666180Y616317D03*
X665643Y646055D03*
X658233Y646449D03*
X658064Y650119D03*
X657967Y662981D03*
X662092Y666275D03*
X659209Y691851D03*
X661018Y707592D03*
X688399Y97667D03*
X671476Y94374D03*
X678782Y116594D03*
X684055Y102495D03*
X677756Y110784D03*
X672756D03*
X678782Y119594D03*
X682316Y125107D03*
X677335Y124663D03*
X683789Y142862D03*
X684830Y148717D03*
X678679Y138838D03*
X674870Y218085D03*
X681383Y219470D03*
Y216970D03*
X678670Y216385D03*
X681383Y221970D03*
X681449Y226320D03*
X672070Y218085D03*
X684410Y228646D03*
X683367Y232971D03*
X677397Y249108D03*
X680017Y244571D03*
X682857Y339477D03*
X687055Y376456D03*
X685353Y396718D03*
X678461Y455981D03*
X675237Y465611D03*
X682586Y530000D03*
X682086Y540500D03*
X681086Y547075D03*
X681286Y549800D03*
X680586Y568000D03*
X681126Y558800D03*
X681190Y562800D03*
X696859Y103411D03*
X697253Y97667D03*
X692649Y95111D03*
X697018Y106561D03*
X690930Y143762D03*
X691396Y199248D03*
X687378Y195176D03*
X689878D03*
X694396Y199248D03*
X694878Y195176D03*
X692378D03*
X691396Y201748D03*
X689232Y206806D03*
X687459Y210509D03*
X689959D03*
X694396Y202048D03*
X691732Y206806D03*
X697996Y230117D03*
X689151Y230556D03*
X693406Y227824D03*
X694012Y238714D03*
X688136Y242078D03*
X693493Y246874D03*
X695713Y244297D03*
X690504Y253198D03*
X689486Y339583D03*
X702448Y546712D03*
Y542712D03*
X699188Y656321D03*
X702086Y678462D03*
X692478Y730641D03*
X702691Y762971D03*
Y756971D03*
X692356Y764614D03*
X691991Y759581D03*
X702677Y780659D03*
Y775159D03*
X692155Y778974D03*
X692221Y773449D03*
X690449Y814406D03*
X708049Y90650D03*
X713361Y90615D03*
X717732Y95236D03*
X717682Y99961D03*
X707799Y95236D03*
X716544Y215478D03*
Y210478D03*
Y207978D03*
Y212978D03*
X718338Y305272D03*
X712692Y356779D03*
X717105Y410964D03*
X717420Y404334D03*
X709781Y442956D03*
X720996Y442856D03*
X711598Y438323D03*
X719051Y458455D03*
X719612Y451108D03*
X710643Y456335D03*
X711764Y445873D03*
X706211Y465874D03*
X711463Y546712D03*
X704364Y618288D03*
X711328Y653821D03*
X705390Y655789D03*
X705776Y678519D03*
X713200Y699676D03*
X716623Y702463D03*
X703600Y702212D03*
X703680Y697094D03*
X715802Y706446D03*
X710196Y707562D03*
X717434Y782500D03*
X710275Y786131D03*
X713222Y793312D03*
Y790812D03*
X712901Y821600D03*
X726596Y74793D03*
Y77393D03*
Y79993D03*
Y85193D03*
Y82593D03*
X726640Y92874D03*
X734921Y98551D03*
X728667Y104249D03*
Y107649D03*
X733233Y147540D03*
X728289Y162368D03*
X725689D03*
X734386Y181426D03*
X734594Y184221D03*
X727000Y213213D03*
Y208213D03*
X733872Y208695D03*
X731072D03*
X733572Y211695D03*
X731072D03*
X727000Y210713D03*
Y215713D03*
X722373Y264180D03*
X719873D03*
X719798Y258880D03*
X737249Y265701D03*
X731567Y267526D03*
X728767D03*
X734067D03*
Y270026D03*
X731567D03*
X728767D03*
X723404Y379657D03*
X721900Y384500D03*
X723440Y391496D03*
X734661Y393633D03*
X731511Y381113D03*
X723440Y398583D03*
X732035Y442606D03*
X722097Y453881D03*
X731952Y446606D03*
X722097Y446595D03*
X732959Y463479D03*
X733430Y467367D03*
X724362Y504731D03*
X722473Y693718D03*
X723656Y705858D03*
X720985Y711658D03*
X725667Y732161D03*
X723177Y728219D03*
X721163Y738981D03*
X733000Y816000D03*
X730880Y828924D03*
X733680Y828977D03*
X732713Y853890D03*
X722600Y869600D03*
X728503Y891692D03*
X736452Y890548D03*
X728692Y886653D03*
X724707Y893143D03*
X719661Y904900D03*
X722789Y927095D03*
X722400Y942500D03*
X725194Y942073D03*
X720271Y931730D03*
X732306Y942682D03*
X728846Y948331D03*
X733798Y950186D03*
X727116Y959326D03*
X732825Y1604100D03*
X736067Y1611892D03*
X729600Y1625165D03*
X732268Y1618260D03*
X751017Y76587D03*
Y72615D03*
X752456Y100625D03*
X745475Y97475D03*
X737816Y114623D03*
Y111223D03*
X745406Y106186D03*
X738471Y103783D03*
X748218Y118335D03*
X737816Y128796D03*
X748218Y132509D03*
Y121735D03*
X737816Y125396D03*
X748218Y135909D03*
X737005Y141247D03*
X744472Y143740D03*
X741852Y148277D03*
X735389Y165393D03*
Y162793D03*
Y170493D03*
Y167993D03*
X740392Y181009D03*
X737597Y181366D03*
X745567Y168697D03*
X742894Y172190D03*
X742313Y177616D03*
X746655Y191941D03*
X737211Y184012D03*
X750667Y192300D03*
X751164Y206767D03*
X748664D03*
X738630Y213859D03*
Y211359D03*
X742333Y213132D03*
X749909Y228221D03*
Y231021D03*
X751294Y221708D03*
X748209Y224421D03*
X748794Y221708D03*
X742333Y215632D03*
X750460Y236189D03*
X750401Y248765D03*
X742577Y256303D03*
X747352Y266114D03*
X742336Y265896D03*
X750598Y268195D03*
Y270695D03*
X744825Y281982D03*
X738884Y281716D03*
X741051Y316389D03*
X749444Y393858D03*
X749606Y384410D03*
X752785Y382047D03*
X753086Y403500D03*
X751086Y398583D03*
X749539Y438269D03*
Y440869D03*
Y435669D03*
Y430469D03*
Y433069D03*
X735599Y449961D03*
X739316Y458572D03*
X750393Y451677D03*
Y454177D03*
X741992Y763480D03*
X742000Y768137D03*
X743428Y772418D03*
X741993Y775909D03*
X736000Y864266D03*
X742407Y988452D03*
X743062Y1004460D03*
X749439Y1458777D03*
X740530Y1524113D03*
X747140Y1581335D03*
X749786Y1590517D03*
X738775Y1597866D03*
X737892Y1602340D03*
X749704Y1608631D03*
X744924Y1617709D03*
X743331Y1627871D03*
X741705Y1622015D03*
X738325Y1634485D03*
X762697Y55513D03*
X758922Y68581D03*
X765297Y60513D03*
X758935Y80581D03*
X763065Y88801D03*
X765982Y94351D03*
X769931Y94279D03*
X765425Y85731D03*
X756829Y112083D03*
X761118Y103621D03*
X769609Y124283D03*
X753035Y141247D03*
X757522Y143518D03*
X756622Y152373D03*
X759772Y152562D03*
X765267Y157370D03*
X760637Y172665D03*
X760464Y183834D03*
X760574Y178560D03*
X761450Y186629D03*
X754709Y192490D03*
X759984Y190185D03*
X760754Y200864D03*
X753182Y198671D03*
X753664Y206767D03*
X769383Y208864D03*
X760843Y212455D03*
X760777Y207037D03*
X753794Y221708D03*
X758144Y221642D03*
X765024Y219379D03*
X763653Y224536D03*
X752960Y236189D03*
X755460D03*
X755401Y248765D03*
X752901D03*
X753098Y268195D03*
X755898D03*
X753098Y270695D03*
X755898D03*
X759558Y265897D03*
X762058D03*
X769349Y324518D03*
X759029Y328867D03*
X754805Y339559D03*
X759624Y353961D03*
X756086Y377912D03*
X766344D03*
X755086Y391496D03*
X756086Y386500D03*
X766344Y381912D03*
X756174Y397912D03*
X755086Y409000D03*
X766344Y397912D03*
X752339Y438269D03*
Y433069D03*
Y430469D03*
Y435669D03*
Y440869D03*
X752893Y451677D03*
Y454177D03*
X752097Y460218D03*
Y463618D03*
X755035Y1443524D03*
X765713Y1437365D03*
X760398Y1440276D03*
X755187Y1580821D03*
X759802Y1590864D03*
X763542Y1590186D03*
X768361Y1610083D03*
X762671Y1619367D03*
X756358Y1613767D03*
X768157Y60438D03*
X773838Y86012D03*
Y94374D03*
X768979Y86046D03*
X781144Y116594D03*
X769175D03*
X775118Y110784D03*
X780118D03*
X781144Y119594D03*
X769175D03*
X784678Y125107D03*
X779697Y124663D03*
X774675Y124879D03*
X781041Y138838D03*
X768016Y161306D03*
X769351Y176665D03*
Y168665D03*
Y192665D03*
X769464Y186778D03*
X769383Y204864D03*
X774432Y218085D03*
X777232D03*
X783745Y216970D03*
X781032Y216385D03*
X783745Y221970D03*
X783811Y226320D03*
X783745Y219470D03*
X782379Y244571D03*
X779759Y249108D03*
X771140Y248371D03*
X772165Y314890D03*
X784118Y303962D03*
X771941Y311740D03*
X772162Y332584D03*
X778502Y348015D03*
X772859Y347937D03*
X774419Y353470D03*
X784902Y428653D03*
X775746Y539315D03*
X777708Y553287D03*
X781429Y545017D03*
X778860Y626912D03*
X778205Y622912D03*
X783694Y1410977D03*
X778685Y1416198D03*
X780162Y1412848D03*
X777749Y1431432D03*
X783469Y1424655D03*
X771557Y1446818D03*
X768910Y1437741D03*
X777749Y1435432D03*
Y1439432D03*
X777260Y1446237D03*
X778428Y1455156D03*
X777725Y1450193D03*
X783620Y1460108D03*
X768812Y1453306D03*
X781124Y1583553D03*
X781110Y1595254D03*
X777059Y1608982D03*
X784046Y1600438D03*
X778045Y1619395D03*
X778358Y1627418D03*
X771383Y1616917D03*
X799221Y103411D03*
X799615Y97667D03*
X790761D03*
X795011Y95111D03*
X786417Y102495D03*
X799380Y106561D03*
X786151Y142862D03*
X793292Y143762D03*
X787192Y148717D03*
X796758Y199248D03*
X797240Y195176D03*
X794740D03*
X789740D03*
X792240D03*
X793758Y199248D03*
X794094Y206806D03*
X791594D03*
X789821Y210509D03*
X792321D03*
X793758Y201748D03*
X796758Y202048D03*
X800358Y230117D03*
X795768Y227824D03*
X791513Y230556D03*
X786772Y228646D03*
X796374Y238714D03*
X790498Y242078D03*
X785729Y232971D03*
X795855Y246874D03*
X798075Y244297D03*
X789722Y256394D03*
X786461Y293028D03*
X790280Y287421D03*
X800155Y337368D03*
X800029Y333368D03*
X797141Y350368D03*
X795445Y356950D03*
X789581Y405011D03*
X793893Y409502D03*
X784804Y425371D03*
X794173Y450510D03*
X802136Y448334D03*
X796000Y553101D03*
X788600Y1006923D03*
X799631Y1025440D03*
X795631D03*
X789050Y1026150D03*
X796338Y1138130D03*
X793842Y1143384D03*
X797160Y1146609D03*
X792277Y1173065D03*
X799020Y1175975D03*
X798353Y1172011D03*
X787887Y1174500D03*
X798542Y1188345D03*
X792382Y1191664D03*
X794533Y1195766D03*
X794983Y1334030D03*
Y1331230D03*
X793548Y1397690D03*
X795296Y1416995D03*
X792848Y1414718D03*
X793459Y1429165D03*
X789647Y1427518D03*
X788648Y1422044D03*
X785820Y1425993D03*
X798601Y1431673D03*
X793288Y1450918D03*
X793744Y1437159D03*
X786787Y1433800D03*
X787694Y1442749D03*
X800607Y1440760D03*
X790361Y1447895D03*
X790754Y1441399D03*
X793994Y1441499D03*
X799057Y1449158D03*
X797083Y1467883D03*
X799057Y1456016D03*
X794005Y1464178D03*
X790296Y1463459D03*
X787038Y1460533D03*
X786591Y1452803D03*
X790989Y1455695D03*
X799314Y1475693D03*
X797318Y1471242D03*
X810411Y90650D03*
X815723Y90615D03*
X810161Y95236D03*
X805952Y301675D03*
X817456Y305368D03*
Y313368D03*
X809490Y305368D03*
X809466Y310604D03*
X801097Y325858D03*
X817100Y319600D03*
X809457Y330459D03*
X809490Y325368D03*
Y317368D03*
X809489Y313830D03*
X809490Y321368D03*
Y333368D03*
X816177Y441442D03*
X813456Y441474D03*
X810749Y443045D03*
X815840Y444091D03*
Y456060D03*
X810453Y453330D03*
X810406Y448214D03*
X810756Y471071D03*
Y468571D03*
X814580Y468806D03*
X814828Y472053D03*
X810756Y473571D03*
Y476071D03*
X813902Y730738D03*
X813678Y740979D03*
X813653Y746856D03*
X817584Y764219D03*
X813635Y762000D03*
X818000Y797000D03*
X817845Y817879D03*
X818500Y810135D03*
X813000Y805000D03*
X813548Y814000D03*
X813009Y819734D03*
X815500Y824000D03*
X815863Y830097D03*
X814299Y840877D03*
X813887Y835146D03*
X816037Y845578D03*
X812440Y862306D03*
X814080Y864464D03*
X812575Y880834D03*
X812219Y883586D03*
X817884Y915425D03*
X803673Y1025440D03*
X803453Y1134729D03*
X814835D03*
X806835D03*
X809632Y1142666D03*
X817964Y1157404D03*
X811507Y1157544D03*
X810018Y1167768D03*
X815037D03*
X814160Y1178240D03*
X814170Y1185205D03*
X805212Y1180175D03*
X805519Y1187215D03*
X815455Y1201043D03*
X811485D03*
X807489D03*
X804452Y1199814D03*
X804458Y1193112D03*
X809027Y1219895D03*
X807020Y1217900D03*
X812302Y1223170D03*
X815149Y1226016D03*
X810148Y1374884D03*
X806148Y1383715D03*
Y1375208D03*
X810204Y1401661D03*
X804654Y1404769D03*
X812901Y1432804D03*
X815901D03*
X810059Y1432778D03*
X812104Y1426483D03*
X809986Y1438785D03*
X812986D03*
X815986D03*
X809986Y1441485D03*
X812986D03*
X815986D03*
X812901Y1435504D03*
X815901D03*
X810001D03*
X803057Y1449158D03*
X801057Y1447158D03*
X805569Y1441519D03*
X803057Y1456016D03*
X801057Y1458016D03*
X802684Y1465549D03*
X801354Y1478681D03*
X807576Y1469584D03*
X804919Y1489247D03*
X828958Y79993D03*
Y77393D03*
Y74793D03*
Y85193D03*
Y82593D03*
X829002Y92874D03*
X820094Y95236D03*
X820044Y99961D03*
X831029Y104249D03*
Y107649D03*
X830651Y162368D03*
X828051D03*
X829362Y213213D03*
X818906Y207978D03*
Y212978D03*
Y215478D03*
Y210478D03*
X829362Y208213D03*
Y210713D03*
Y215713D03*
X822235Y264180D03*
X824735D03*
X822160Y258880D03*
X831129Y267526D03*
Y270026D03*
X822477Y309368D03*
X825971Y345101D03*
X829485D03*
X822626Y348066D03*
X818840Y444091D03*
X825103Y430358D03*
Y435558D03*
Y432958D03*
X831378Y433086D03*
Y435686D03*
Y430486D03*
X818840Y456060D03*
X824650Y455034D03*
Y450034D03*
X817328Y472053D03*
X820810Y471243D03*
X817380Y468806D03*
X823544Y475061D03*
Y472561D03*
X820810Y473743D03*
X828918Y480580D03*
X831418D03*
X831057Y484036D03*
X834282Y536085D03*
X828272Y535462D03*
X827291Y533100D03*
X829496Y676793D03*
X829784Y716589D03*
Y705489D03*
X823890Y703415D03*
X823670Y710542D03*
X824387Y726246D03*
X818307Y724144D03*
X821582Y727140D03*
X826484Y747127D03*
X827500Y750000D03*
X819788Y739634D03*
X830484Y738750D03*
X824500Y760500D03*
X830075Y769000D03*
X822151Y752283D03*
X824500Y756000D03*
X817365Y756827D03*
X824500Y778500D03*
Y774000D03*
Y782500D03*
X830075Y787000D03*
X824500Y796500D03*
X824342Y792315D03*
X824500Y800500D03*
X830075Y805000D03*
X824500Y814500D03*
X830075Y823000D03*
X829946Y829788D03*
X825721Y839816D03*
X830014Y833046D03*
X829757Y842672D03*
X822608Y848526D03*
X822916Y852576D03*
X823540Y857956D03*
X831654Y864494D03*
X831583Y853454D03*
X822938Y863298D03*
X826209Y866052D03*
X823234Y870830D03*
X833194Y873561D03*
X827992Y874107D03*
X826070Y893014D03*
X817152Y896380D03*
X817139Y890330D03*
X830063Y898500D03*
X819918Y889365D03*
X823900Y882083D03*
X824804Y898395D03*
X834465Y884538D03*
X829848Y914211D03*
X818031Y907747D03*
X825336Y916774D03*
X831057Y916745D03*
X834751Y922368D03*
X823552Y930700D03*
X829617Y939583D03*
X824414Y939655D03*
X816519Y931147D03*
X824168Y949538D03*
X825670Y964671D03*
X832423Y964669D03*
X828964Y977780D03*
X830356Y1116251D03*
X827856D03*
X825335Y1137129D03*
X819449Y1134534D03*
X819026Y1128137D03*
X825744Y1150087D03*
X823220Y1170767D03*
X818879Y1187310D03*
X823309Y1180235D03*
X823516Y1185238D03*
X819489Y1201039D03*
X823489Y1200969D03*
X823608Y1208993D03*
X819419Y1230265D03*
X817360Y1228226D03*
X816648Y1380758D03*
X824901Y1427404D03*
X827901D03*
X821901D03*
X818901Y1430104D03*
X821901D03*
X830901D03*
X827901D03*
X824901D03*
Y1432804D03*
X827901D03*
X830901D03*
X821901D03*
X818901D03*
X824901Y1435504D03*
X827901D03*
X821901D03*
X818901D03*
X821986Y1441485D03*
X818986D03*
Y1438785D03*
X821986D03*
X826204Y1444689D03*
Y1440689D03*
X826341Y1451236D03*
X826365Y1458974D03*
X826219Y1455244D03*
X837283Y98551D03*
X847837Y97475D03*
X840178Y114623D03*
Y111223D03*
X840833Y103783D03*
X847768Y106186D03*
X840178Y128796D03*
Y125396D03*
X837751Y165393D03*
Y162793D03*
Y170493D03*
Y167993D03*
X842754Y181009D03*
X839959Y181366D03*
X836748Y181426D03*
X847929Y168697D03*
X844675Y177616D03*
X845256Y172190D03*
X839573Y184012D03*
X836956Y184221D03*
X836234Y208695D03*
X833434D03*
X835934Y211695D03*
X840992Y213859D03*
Y211359D03*
X833434Y211695D03*
X844695Y213132D03*
Y215632D03*
X844939Y256303D03*
X844698Y265896D03*
X839611Y265701D03*
X849714Y266114D03*
X836429Y267526D03*
X833929D03*
Y270026D03*
X836429D03*
X841246Y281716D03*
X847187Y281982D03*
X842240Y324854D03*
X848879Y360849D03*
X845435Y356172D03*
X846098Y408715D03*
X849591Y411388D03*
X842515Y461382D03*
X850732Y469382D03*
X842779Y473076D03*
X842916Y467009D03*
X833293Y490636D03*
Y487836D03*
X833918Y480580D03*
X834215Y484138D03*
X844227Y479882D03*
X842476Y482382D03*
X833269Y506683D03*
X833953Y530621D03*
X848444Y657756D03*
X837272Y663910D03*
X839636Y666533D03*
X842352Y659243D03*
X842640Y662814D03*
X838152Y700215D03*
X845784Y705489D03*
Y716589D03*
X845850Y710969D03*
X845784Y708089D03*
X836078Y709619D03*
X835987Y713745D03*
X838484Y746701D03*
X846484Y738750D03*
X836713Y738751D03*
X842661Y769521D03*
X846000Y772079D03*
X840136Y830903D03*
X836839Y831301D03*
X836894Y824401D03*
X848224Y823502D03*
X835626Y843629D03*
X838189Y843459D03*
Y847490D03*
X835215Y847719D03*
X848384Y843459D03*
X846239Y847490D03*
X835553Y835119D03*
X848384Y839459D03*
Y835459D03*
X838194Y836962D03*
X848739Y847459D03*
X837183Y855459D03*
X840234Y851459D03*
X847138Y859459D03*
X839530Y859408D03*
X848384Y863459D03*
X846336Y855459D03*
X845820Y863413D03*
X848384Y851459D03*
X843574Y859423D03*
X837434Y851459D03*
X833327Y855560D03*
X837383Y879530D03*
X837396Y871459D03*
X840234Y875459D03*
X836999Y867413D03*
X845876Y879459D03*
X848384Y867459D03*
X845820Y867413D03*
X848384Y879459D03*
Y871459D03*
Y875459D03*
X837290Y887490D03*
X842827Y895443D03*
X835346Y891346D03*
X848322Y888421D03*
X848792Y896472D03*
X836066Y894955D03*
X847098Y891213D03*
X845633Y883492D03*
X845964Y887490D03*
X837276Y883459D03*
X848200Y883400D03*
X841329Y926602D03*
X841274Y914060D03*
X843315Y916612D03*
X836909Y916618D03*
Y914018D03*
X833683Y939579D03*
X836243D03*
X833683Y949105D03*
X836243D03*
X842856Y949146D03*
X836423Y964669D03*
X835431Y977775D03*
X840935Y1011499D03*
X844058Y1011738D03*
X848045Y1019310D03*
X848070Y1022190D03*
X839744Y1444959D03*
Y1440859D03*
Y1448959D03*
X836704Y1448849D03*
Y1440849D03*
X836744Y1444849D03*
X845306Y1438269D03*
X846844Y1454334D03*
X837685Y1453196D03*
X839744Y1457959D03*
X835474Y1457397D03*
X846044Y1451459D03*
X839744Y1461959D03*
X834475Y1460059D03*
X865059Y55513D03*
X861284Y68581D03*
X861297Y80581D03*
X853379Y76587D03*
Y72615D03*
X854818Y100625D03*
X859191Y112083D03*
X863480Y103621D03*
X850580Y118335D03*
Y132509D03*
Y121735D03*
Y135909D03*
X862826Y183834D03*
X862999Y172665D03*
X862936Y178560D03*
X849017Y191941D03*
X863812Y186629D03*
X857071Y192490D03*
X862346Y190185D03*
X863116Y200864D03*
X853029Y192300D03*
X853526Y206767D03*
X856026D03*
X851026D03*
X863205Y212455D03*
X863139Y207037D03*
X860506Y221642D03*
X852271Y228221D03*
Y231021D03*
X853656Y221708D03*
X856156D03*
X850571Y224421D03*
X851156Y221708D03*
X866015Y224536D03*
X852822Y236189D03*
X855322D03*
X857822D03*
X852763Y248765D03*
X855263D03*
X857763D03*
X852960Y268195D03*
Y270695D03*
X855460D03*
X864420Y265897D03*
X858260Y268195D03*
Y270695D03*
X861920Y265897D03*
X855460Y268195D03*
X863430Y309368D03*
Y316970D03*
X863114Y324505D03*
X863040Y330140D03*
X861770Y343006D03*
X852569Y356712D03*
X856069Y356426D03*
X854086Y374500D03*
X858586D03*
X863086D03*
X860586Y383000D03*
X861235Y394000D03*
X854086Y392999D03*
X864086Y384000D03*
X855017Y411969D03*
X861413Y417071D03*
X858827Y419896D03*
X858410Y413890D03*
X858767Y416685D03*
X861622Y419688D03*
X862882Y458991D03*
X854882D03*
X862882Y461791D03*
X854882D03*
X850748Y465382D03*
X861468Y483303D03*
Y487303D03*
X858169Y495032D03*
X853989Y630453D03*
Y632953D03*
X861663Y646653D03*
X855300Y646819D03*
X853982Y657506D03*
X859441Y678015D03*
X849680Y694789D03*
X858186Y701170D03*
X855646Y692710D03*
X864029Y688970D03*
X867455Y710611D03*
X858002Y707244D03*
X857986Y722670D03*
X854484Y746701D03*
X859199Y744517D03*
X854484Y738633D03*
X859000Y756000D03*
X849500Y758500D03*
Y763500D03*
X863443Y753254D03*
X859000Y764000D03*
Y760000D03*
Y774000D03*
X849500Y776500D03*
Y781500D03*
X861425Y770500D03*
X859000Y781000D03*
Y778000D03*
X853282Y789887D03*
X857632Y789385D03*
X859000Y792000D03*
X849500Y794500D03*
Y799500D03*
X861425Y788500D03*
X859000Y800000D03*
Y796000D03*
X861425Y806500D03*
X859000Y810000D03*
X849500Y812500D03*
X859000Y814000D03*
X850496Y831469D03*
X861425Y824500D03*
X849500Y817500D03*
X859000Y818000D03*
X851184Y839459D03*
Y835459D03*
X859165Y848728D03*
X851239Y847459D03*
X851184Y843459D03*
Y863459D03*
X862114Y859479D03*
X851184Y851459D03*
X859603Y863570D03*
X859461Y859459D03*
X851184Y867459D03*
Y871459D03*
Y875459D03*
X859234Y879600D03*
X859463Y866125D03*
X851184Y879459D03*
X849267Y892567D03*
X859614Y883800D03*
Y887846D03*
X850900Y888359D03*
X850800Y883500D03*
X858988Y898307D03*
X855524Y898505D03*
X864253Y918042D03*
X856628D03*
X849600Y918028D03*
X849205Y924129D03*
X867096Y935963D03*
X858601Y934505D03*
X853030Y934690D03*
X851925Y951350D03*
X850686Y1006923D03*
X853449Y1007048D03*
X863334Y1009393D03*
X861047Y1018909D03*
X860887Y1023208D03*
Y1026762D03*
X863956Y1020763D03*
X863689Y1024974D03*
X863944Y1432359D03*
Y1429359D03*
X860944Y1432359D03*
X857944Y1429359D03*
X860944D03*
Y1426359D03*
X857944D03*
X863944D03*
X857944Y1432359D03*
X863944Y1435359D03*
Y1441359D03*
Y1438359D03*
X860944Y1441359D03*
X857944Y1435359D03*
X860944D03*
X857944Y1441359D03*
Y1438359D03*
X860944D03*
X850544Y1447559D03*
X853514Y1457510D03*
X850644Y1457359D03*
X870519Y60438D03*
X867659Y60513D03*
X876200Y86012D03*
X867787Y85731D03*
X865427Y88801D03*
X876200Y94374D03*
X872293Y94279D03*
X868344Y94351D03*
X871341Y86046D03*
X871713Y168665D03*
Y176665D03*
Y196665D03*
Y192665D03*
X871826Y186778D03*
X871745Y204864D03*
Y208864D03*
X867386Y219379D03*
X883118Y262687D03*
X876622Y293721D03*
X872050Y302644D03*
X873262Y300030D03*
X869924Y305368D03*
X879112Y302369D03*
X877977Y305368D03*
Y309368D03*
X869924Y313368D03*
X877977D03*
Y325368D03*
Y317368D03*
Y321368D03*
X869924D03*
Y328722D03*
X874005Y344917D03*
X870413Y342791D03*
X869924Y333722D03*
X877977Y333368D03*
Y329368D03*
X872158Y359962D03*
X868086Y373750D03*
X876736Y383125D03*
X877909Y391731D03*
X880736Y383125D03*
X882925Y391099D03*
X872736Y391754D03*
X867586Y393000D03*
Y385000D03*
X869342Y407627D03*
X868586Y398500D03*
X877253Y420380D03*
X876917Y415322D03*
X879417D03*
X881190Y411619D03*
X878690D03*
X874253Y422880D03*
Y420080D03*
X877253Y422880D03*
X881271Y426952D03*
X878771D03*
X873536Y437408D03*
X876036D03*
X881036D03*
X878536D03*
X873771Y426952D03*
X876271D03*
X870882Y458991D03*
X880910Y454634D03*
Y457434D03*
Y460234D03*
X870882Y461791D03*
X869454Y479303D03*
X869954Y487303D03*
X882954Y486256D03*
X882195Y539204D03*
X867093Y554703D03*
X866938Y549771D03*
X878382Y554942D03*
X874649Y545296D03*
X876949Y571419D03*
X867093Y586828D03*
Y574703D03*
X881476Y588202D03*
X881131Y577349D03*
X875290Y578703D03*
X876351Y605023D03*
Y608523D03*
X879135Y632552D03*
X872862Y666859D03*
X878881Y667156D03*
X876286Y690970D03*
X868919Y700894D03*
X876286Y694970D03*
Y698970D03*
X881157Y749148D03*
X874142Y748914D03*
X879875Y753612D03*
X873728Y752692D03*
X875473Y742056D03*
X878670Y742841D03*
X869325Y761259D03*
X870017Y757313D03*
X867000Y774000D03*
X870000Y780000D03*
X879887Y784719D03*
X880040Y792851D03*
X867000Y792000D03*
X876402Y797415D03*
X874925Y800746D03*
X870035Y801032D03*
X867000Y810000D03*
X879916Y808965D03*
X877407Y828017D03*
X877818Y824214D03*
X876475Y830372D03*
X871600Y898584D03*
X872628Y918042D03*
X876628Y915242D03*
X880628Y918042D03*
X876628D03*
X872126Y934766D03*
X865830Y961600D03*
X870209Y949384D03*
X865973Y978187D03*
X874066Y977928D03*
X875391Y993796D03*
X872183Y993980D03*
X878976Y994020D03*
X871069Y1023114D03*
X878927Y1022387D03*
X878783Y1018751D03*
X872845Y1018988D03*
X866906Y1018751D03*
X866887Y1023208D03*
X875887D03*
X878887Y1026762D03*
X872887D03*
X866887D03*
X869741Y1025895D03*
X873824Y1071604D03*
X871224D03*
X876424D03*
Y1074104D03*
X871224D03*
X873824D03*
X868624Y1071604D03*
Y1074104D03*
X870057Y1091604D03*
X875257D03*
Y1089104D03*
X870057D03*
X872657D03*
X880115Y1084666D03*
X867457Y1091604D03*
Y1089104D03*
X872657Y1091604D03*
X875375Y1107647D03*
X872675D03*
X870075D03*
X867475D03*
X871364Y1120636D03*
X873964D03*
X876564D03*
X879264D03*
X875376Y1110175D03*
X872676D03*
X870076D03*
X867476D03*
X871364Y1139336D03*
X868664D03*
X879264Y1130336D03*
X876564D03*
X873964D03*
X871364D03*
X870522Y1148080D03*
X868022D03*
X875321Y1207654D03*
X872600Y1300833D03*
Y1298333D03*
X872944Y1432359D03*
Y1429359D03*
Y1426359D03*
X869944Y1432359D03*
Y1429359D03*
Y1426359D03*
X866944Y1432359D03*
Y1429359D03*
Y1426359D03*
X872944Y1435359D03*
Y1441359D03*
Y1438359D03*
X869944Y1435359D03*
X866944D03*
X869944Y1441359D03*
Y1438359D03*
X866944Y1441359D03*
Y1438359D03*
X881244Y1448859D03*
Y1440859D03*
X878244Y1451605D03*
X881244Y1464859D03*
Y1453059D03*
Y1456859D03*
X875744Y1453573D03*
X881244Y1476859D03*
X883233Y147540D03*
X887005Y141247D03*
X894472Y143740D03*
X891852Y148277D03*
X893284Y233339D03*
Y236739D03*
X895064Y250186D03*
X891383Y243203D03*
X896034Y243307D03*
X885884Y255118D03*
X897004Y257480D03*
X892484Y260860D03*
X887148Y249670D03*
X896953Y272012D03*
X886496Y268968D03*
X895140Y265236D03*
X886059Y284644D03*
X885918Y289500D03*
X885989Y309368D03*
Y305368D03*
Y317368D03*
X885953Y325368D03*
X885989Y313368D03*
X885953Y321368D03*
Y329368D03*
Y333368D03*
X896592Y358369D03*
Y354369D03*
X888812Y357372D03*
X883552Y357276D03*
X896592Y374369D03*
X891251Y387484D03*
X890553Y392038D03*
X887266Y400158D03*
Y405158D03*
Y402658D03*
X896579Y404043D03*
X893779D03*
X889979Y405743D03*
X890903Y454634D03*
Y457434D03*
Y460234D03*
X891454Y486303D03*
X892931Y534093D03*
X885931D03*
X891449Y547363D03*
X893949D03*
X886549Y553963D03*
X885556Y543664D03*
X887417Y566713D03*
X891673Y600049D03*
X891933Y618143D03*
X895933Y609696D03*
X883309Y666608D03*
X892461Y666671D03*
X886304Y666650D03*
X884903Y696678D03*
X884911Y690279D03*
X886836Y715970D03*
X893241Y704656D03*
X883686Y729778D03*
X889525Y722060D03*
X882098Y741565D03*
X884976Y740891D03*
X884463Y744757D03*
X881637Y744154D03*
X883126Y766124D03*
X883413Y759855D03*
X892040Y784511D03*
X889763Y788159D03*
X898737Y792289D03*
X889516Y792851D03*
X891916Y799605D03*
X884002Y797616D03*
X887916Y800815D03*
X895916Y808965D03*
X883916D03*
X887916D03*
X895829Y800660D03*
X883916Y800815D03*
X890326Y828548D03*
X895050D03*
X889178Y905619D03*
X884628Y915242D03*
Y918042D03*
X896553D03*
X892628Y915242D03*
X888628D03*
Y918042D03*
X882763Y933472D03*
X891367Y941126D03*
X888400Y994579D03*
X894660Y994330D03*
X891343Y994378D03*
X885099Y1021685D03*
X881887Y1023208D03*
X888743Y1019931D03*
X895394Y1026985D03*
X893147Y1020025D03*
X893887Y1023208D03*
X887887D03*
X890887Y1026762D03*
X884887D03*
X882779Y1074104D03*
Y1071604D03*
X887979Y1074104D03*
X885379D03*
X890579D03*
Y1071604D03*
X885379D03*
X887979D03*
X882615Y1084666D03*
X887862Y1088067D03*
X894004Y1081231D03*
X892856Y1102760D03*
X894249Y1114103D03*
X891549D03*
X888949D03*
X886349D03*
Y1123803D03*
X888949D03*
X891549D03*
X894249D03*
X895275Y1132870D03*
X892575D03*
X895547Y1145169D03*
X894713Y1210419D03*
X898878Y1214182D03*
X899286Y1219469D03*
X892532Y1220112D03*
X897169Y1225259D03*
X886888Y1263058D03*
X889388D03*
X891888D03*
X889388Y1260558D03*
X886888D03*
X891888D03*
X886926Y1298712D03*
X889729Y1295516D03*
X891107Y1314305D03*
X887342Y1314990D03*
X889244Y1444859D03*
X892244Y1449636D03*
Y1440859D03*
X889944Y1457959D03*
X889244Y1460859D03*
X895244Y1457510D03*
X889336Y1452554D03*
X893919Y1462132D03*
X889244Y1472859D03*
Y1468859D03*
X903035Y141247D03*
X907522Y143518D03*
X906622Y152373D03*
X909772Y152562D03*
X899573Y158195D03*
X910977Y243307D03*
Y248032D03*
Y262205D03*
X898048Y269387D03*
X913057Y311046D03*
X915653Y307438D03*
X899352Y308560D03*
Y311960D03*
X909298Y302347D03*
X905898D03*
X898533Y334498D03*
X908521Y356708D03*
X908625Y359317D03*
X905483Y355262D03*
X905000Y362158D03*
X898869Y351114D03*
X906161Y367191D03*
X913288Y372752D03*
X910646Y376084D03*
X906344Y372524D03*
X911072Y386992D03*
X897736Y383125D03*
X901747Y398492D03*
Y403492D03*
Y400992D03*
X910250Y457262D03*
Y454462D03*
X907450D03*
Y457262D03*
X910250Y451662D03*
X907450D03*
X910250Y460062D03*
X907450D03*
X910236Y465272D03*
X910759Y475511D03*
X899931Y534093D03*
X899530Y530753D03*
X914296Y558143D03*
X913728Y550495D03*
X899407Y560019D03*
X908846Y560124D03*
X910789Y598726D03*
X898207Y599891D03*
X900676Y621536D03*
X904076D03*
X909508Y621616D03*
X912908D03*
X900753Y656925D03*
X912462Y683770D03*
X909265Y677795D03*
X912462Y687770D03*
X906886Y702285D03*
X902236Y689332D03*
Y694332D03*
X908699Y709387D03*
X913247Y714204D03*
X902841Y703665D03*
X910836Y721570D03*
X913858Y721289D03*
X907866Y795572D03*
X911028Y796598D03*
X909785Y810778D03*
X903916Y810809D03*
X913716Y811954D03*
X899916Y808965D03*
X902641Y800748D03*
X907884Y829866D03*
X908920Y905630D03*
X900628Y918042D03*
X912628Y915242D03*
X908628Y918042D03*
X900628Y915242D03*
X912628Y918042D03*
X904838D03*
X908628Y915242D03*
X900983Y940895D03*
X903759Y951358D03*
X909811Y962400D03*
X913005Y969605D03*
X912690Y994350D03*
X897825Y994413D03*
X909166Y994188D03*
X897717Y1019915D03*
X899887Y1023208D03*
Y1026762D03*
X908422Y1023103D03*
X908856Y1017677D03*
X902389Y1081764D03*
X908799Y1093659D03*
Y1088659D03*
X908278Y1083484D03*
X908799Y1096659D03*
Y1100659D03*
X902353Y1104333D03*
X898278Y1136426D03*
X898047Y1145169D03*
X903959Y1207823D03*
X906784Y1216607D03*
X913784Y1221057D03*
X910633Y1222799D03*
X906309Y1226647D03*
X909077Y1232724D03*
X899699Y1283872D03*
X910788Y1299456D03*
X906506Y1299188D03*
X902908Y1299828D03*
X911117Y1314130D03*
X902875Y1309301D03*
X905740Y1309264D03*
X908700Y1316300D03*
X911135Y1345560D03*
X904177Y1359955D03*
X899944Y1432359D03*
X908944Y1426359D03*
Y1429359D03*
Y1432359D03*
X911944Y1426359D03*
Y1429359D03*
Y1432359D03*
X905944Y1426359D03*
X899944D03*
X902944D03*
Y1429359D03*
X899944D03*
X902944Y1432359D03*
X905944Y1429359D03*
Y1432359D03*
X902944Y1438359D03*
X899944D03*
Y1441359D03*
X902944Y1435359D03*
X899944D03*
X908944Y1438359D03*
Y1441359D03*
X911944Y1438359D03*
Y1441359D03*
X902944D03*
X905944Y1438359D03*
Y1441359D03*
X908944Y1435359D03*
X911944D03*
X905944D03*
X919175Y116594D03*
X930118Y110784D03*
X925118D03*
X919175Y119594D03*
X924675Y124879D03*
X929697Y124663D03*
X919609Y124283D03*
X931041Y138838D03*
X918016Y161306D03*
X915267Y157370D03*
X916453Y167975D03*
X927898Y203256D03*
X925098D03*
X919577Y240945D03*
Y250394D03*
Y271654D03*
X919616Y268462D03*
X919577Y264567D03*
X923732Y304585D03*
X917882Y328216D03*
Y324816D03*
X915954Y344150D03*
X916229Y336333D03*
X919354Y344150D03*
X919629Y336333D03*
X927964Y344041D03*
X924564D03*
X923311Y349959D03*
X929943Y372600D03*
X921343Y376888D03*
X916330Y377748D03*
X929947Y376821D03*
X915072Y386992D03*
X914323Y398551D03*
Y403551D03*
Y401051D03*
X927563Y424445D03*
X924763D03*
X921963D03*
X927280Y436716D03*
X921680D03*
X924480D03*
X917541Y441280D03*
Y443780D03*
X927766Y456442D03*
X927596Y447453D03*
X921973Y469328D03*
X927401Y469059D03*
X916593Y469140D03*
X928999Y477948D03*
X920999D03*
X924999D03*
X917811Y544325D03*
X923453Y569578D03*
X923642Y561578D03*
X919080Y587640D03*
X921507Y578791D03*
X919038Y579378D03*
X923599Y581578D03*
X921217Y589216D03*
X913998Y597103D03*
X925949Y612363D03*
Y608863D03*
X922626Y633772D03*
X915800Y629700D03*
X918300D03*
X929690Y666593D03*
X920090Y666714D03*
X928353Y686342D03*
X928704Y680261D03*
X921061Y715386D03*
X926961Y723797D03*
X914202Y797460D03*
X923872Y798271D03*
X922352Y800809D03*
X917803Y811365D03*
X927916Y800909D03*
X929790Y828603D03*
X927916Y817015D03*
X925228Y816934D03*
X929181Y895029D03*
X921451Y903800D03*
X920628Y918042D03*
X916628D03*
X924628D03*
X928628D03*
X924628Y915242D03*
X920628D03*
X928628D03*
X916628D03*
X914193Y945318D03*
X928227Y951125D03*
X921364Y951251D03*
X918265Y969745D03*
X923289Y965780D03*
X926796Y966297D03*
X929741Y967006D03*
X916932Y994405D03*
X924956Y994321D03*
X924864Y1026762D03*
Y1023208D03*
X925024Y1018909D03*
X927861Y1024768D03*
X916749Y1084659D03*
X916992Y1076659D03*
X916749Y1092664D03*
X916875Y1098643D03*
X916749Y1104659D03*
X914637Y1210568D03*
Y1214838D03*
X930754Y1310564D03*
X924650Y1327819D03*
Y1324419D03*
X914033Y1345613D03*
X927193Y1361547D03*
X931159Y1379427D03*
X920360Y1387039D03*
X920255Y1383264D03*
X931199Y1371951D03*
X931159Y1390827D03*
Y1406027D03*
X914944Y1426359D03*
Y1429359D03*
Y1432359D03*
Y1438359D03*
Y1441359D03*
Y1435359D03*
X921498Y1446692D03*
X925697Y1460109D03*
X917744Y1453573D03*
X920244Y1451605D03*
X919285Y1456226D03*
X924803Y1474743D03*
X925435Y1478114D03*
X940761Y97667D03*
X945011Y95111D03*
X931144Y116594D03*
X936417Y102495D03*
X931144Y119594D03*
X934678Y125107D03*
X936151Y142862D03*
X943292Y143762D03*
X937192Y148717D03*
X945406Y180347D03*
X940406D03*
X942906D03*
X947424Y184419D03*
X944424Y186919D03*
X944760Y191977D03*
X942260D03*
X940487Y195680D03*
X942987D03*
X944424Y184419D03*
X934411Y202141D03*
X931698Y201556D03*
X934411Y207141D03*
X934477Y211491D03*
X934411Y204641D03*
X946234Y213390D03*
X942179Y215727D03*
X937438Y213817D03*
X936395Y218142D03*
X933403Y245507D03*
X936962Y249807D03*
X944248Y239844D03*
X945018Y276051D03*
X943183Y281652D03*
X930727Y302571D03*
X937000Y312284D03*
Y315684D03*
X940997Y331912D03*
Y335312D03*
X934128Y355168D03*
X934464Y358618D03*
X944238Y360828D03*
X934047Y369160D03*
X936175Y364823D03*
X931072Y386992D03*
X941872Y440942D03*
X933424Y458455D03*
X933161Y451442D03*
X933404Y463462D03*
X933412Y468942D03*
X936653Y526836D03*
X944351Y534211D03*
X948532Y541135D03*
X939992Y527726D03*
Y548726D03*
Y544726D03*
X948598Y546553D03*
X948621Y552726D03*
X931627Y557641D03*
Y569578D03*
Y581578D03*
Y577578D03*
Y573578D03*
X933725Y585936D03*
X933741Y598087D03*
Y594687D03*
X933725Y589336D03*
X944296Y611071D03*
X941859Y621311D03*
Y629311D03*
X943181Y632536D03*
X945434Y634325D03*
X941859Y625311D03*
X946128Y666522D03*
X935281Y680945D03*
X936026Y727450D03*
X933974Y719371D03*
X942676Y789286D03*
X933201Y798297D03*
X946970Y786366D03*
X944916Y808965D03*
X938357Y808856D03*
X931916Y817015D03*
X942858Y819430D03*
X945736Y819397D03*
X935124Y831382D03*
X940100Y830700D03*
X935262Y825135D03*
X932418D03*
X940716Y840074D03*
X944297Y839975D03*
X933021Y840893D03*
X933054Y843804D03*
X937200Y841000D03*
X936450Y858327D03*
X937551Y860801D03*
X932770Y878233D03*
X935765Y878317D03*
X934928Y871727D03*
X932319Y871626D03*
X938729Y874396D03*
X932300Y890200D03*
X942194Y891216D03*
X930800Y904840D03*
X941592Y900908D03*
X936628Y915242D03*
X940628D03*
X932628D03*
X936628Y918042D03*
X932628D03*
X936371Y951484D03*
X940716Y951733D03*
X946363Y951179D03*
X935255Y962725D03*
X945671Y982191D03*
X940015Y1020176D03*
X934911Y1023579D03*
X945864Y1023208D03*
X930864Y1026762D03*
X936864D03*
X942864D03*
X939864Y1023208D03*
X930864D03*
X930883Y1018751D03*
X936822Y1018988D03*
X942760Y1018751D03*
X943093Y1021769D03*
X932289Y1074182D03*
Y1071682D03*
X937489Y1074182D03*
X934889D03*
X940089D03*
Y1071682D03*
X934889D03*
X937489D03*
X944092Y1084666D03*
X931628Y1091409D03*
Y1088909D03*
X936828Y1091409D03*
X934228D03*
X939428D03*
Y1088909D03*
X934228D03*
X936828D03*
X943241Y1120636D03*
X940541D03*
X937941D03*
X935341D03*
X937941Y1130336D03*
X940541D03*
X943241D03*
X932641Y1139336D03*
X935341Y1130336D03*
Y1139336D03*
X934500Y1147708D03*
X932000D03*
X939298Y1207654D03*
X943891Y1306608D03*
X944207Y1320739D03*
X947308Y1325035D03*
X931137Y1375878D03*
X931159Y1383227D03*
X939559Y1398427D03*
X931159Y1394627D03*
Y1387027D03*
Y1398427D03*
Y1402227D03*
X939559D03*
X944235Y1406262D03*
X943725Y1430744D03*
Y1427744D03*
X934725Y1430744D03*
X940725Y1427744D03*
Y1430744D03*
X934725Y1427744D03*
X937725D03*
Y1430744D03*
X943725Y1433744D03*
Y1439744D03*
Y1436744D03*
X940725Y1433744D03*
Y1439744D03*
Y1436744D03*
X934725Y1433744D03*
X937725D03*
X934725Y1439744D03*
X937725D03*
X934725Y1436744D03*
X937725D03*
X937671Y1492139D03*
Y1488139D03*
X949221Y103411D03*
X949615Y97667D03*
X960411Y90650D03*
X960161Y95236D03*
X949380Y106561D03*
X947906Y180347D03*
X947424Y187219D03*
X950177Y215730D03*
X947040Y223885D03*
X948741Y229468D03*
X948785Y242464D03*
X951278Y250583D03*
X946482Y255940D03*
X949974Y291554D03*
X947733Y319680D03*
X950953Y317947D03*
X960376Y392807D03*
X962769Y451419D03*
X959816Y472905D03*
X955816Y473419D03*
Y464919D03*
X963816Y464419D03*
X962563Y485128D03*
X954182Y481467D03*
X958124Y492354D03*
X958736Y482165D03*
X958974Y504825D03*
X956474D03*
X953974D03*
X949823Y491982D03*
X959600Y496486D03*
X949823Y495982D03*
X957977Y500202D03*
X958915Y517401D03*
X956415D03*
X953915D03*
X959466Y522569D03*
Y525369D03*
X958081Y531882D03*
X955581D03*
X961166Y529169D03*
X952531Y531948D03*
X960581Y531882D03*
X948905Y534909D03*
X958016Y555194D03*
X960816D03*
X958016Y563194D03*
X960816D03*
Y571194D03*
X958016D03*
X959573Y581222D03*
X962373D03*
X959573Y591215D03*
X962373D03*
X962545Y607762D03*
X959745D03*
Y610562D03*
X962545D03*
X950479Y622285D03*
X954535Y610548D03*
X950667Y616905D03*
X963365Y628078D03*
X961352Y633736D03*
X950865Y633724D03*
X950748Y627713D03*
X956345Y633716D03*
X949137Y666660D03*
X954526Y666671D03*
X947556Y699550D03*
X956023Y706907D03*
X951151Y730111D03*
X963869Y725057D03*
X955950Y734178D03*
X957763Y725336D03*
X959950Y734178D03*
X957579Y744168D03*
X953837Y763025D03*
X950699Y779711D03*
X956017Y770300D03*
X957500Y780800D03*
X955076Y784861D03*
X950475Y789361D03*
X955225Y788984D03*
X949609Y796051D03*
X957487Y798553D03*
X951461Y812223D03*
X951791Y808121D03*
X957379Y826586D03*
X954760Y826734D03*
X951708Y818894D03*
X955712Y833988D03*
X956239Y829577D03*
X960100Y846665D03*
X954700Y837700D03*
X961175Y838525D03*
X955343Y866850D03*
X955850Y862902D03*
X957900Y856300D03*
X950300Y877800D03*
X953240Y876834D03*
X954567Y927654D03*
X964280Y927777D03*
X958567Y927654D03*
X947029Y915242D03*
X959545Y918306D03*
X951863Y936168D03*
X957235Y936398D03*
X962329Y936229D03*
X957671Y977921D03*
X949671D03*
X961671Y991564D03*
X953671D03*
X949671D03*
X953671Y982191D03*
X954937Y1021998D03*
X948864Y1026762D03*
X954864D03*
X951864Y1023208D03*
X957864D03*
X957678Y1018555D03*
X961208Y1018592D03*
X960636Y1021917D03*
X959371Y1026985D03*
X948975Y1021325D03*
X951956Y1071604D03*
X949356D03*
X954556D03*
Y1074104D03*
X949356D03*
X951956D03*
X946756Y1071604D03*
Y1074104D03*
X946592Y1084666D03*
X957981Y1081231D03*
X951839Y1088067D03*
X956833Y1102760D03*
X950326Y1114103D03*
Y1123803D03*
X952926D03*
X955526D03*
Y1114103D03*
X958226D03*
X952926D03*
X958226Y1123803D03*
X956552Y1132870D03*
X959252D03*
X962255Y1136426D03*
X962024Y1145169D03*
X959524D03*
X958690Y1210419D03*
X963263Y1219469D03*
X962855Y1214182D03*
X956509Y1220112D03*
X961146Y1225259D03*
X950865Y1263058D03*
X953365D03*
X955865D03*
X953365Y1260558D03*
X950865D03*
X955865D03*
X948259Y1295965D03*
X948832Y1371654D03*
X951832D03*
X952561Y1383465D03*
X952417Y1379528D03*
X949469D03*
X949385Y1375591D03*
X952385D03*
X952514Y1391339D03*
X952395Y1395276D03*
X952716Y1387402D03*
X952180Y1407087D03*
X950239Y1409555D03*
X948235Y1406262D03*
X946725Y1427744D03*
Y1430744D03*
X949725D03*
Y1427744D03*
X960883Y1427997D03*
Y1430997D03*
X946725Y1433744D03*
X949725D03*
X946725Y1439744D03*
X949725D03*
X946725Y1436744D03*
X949725D03*
X960883Y1433997D03*
Y1436997D03*
Y1439997D03*
X952695Y1444139D03*
X979002Y92874D03*
X965723Y90615D03*
X970094Y95236D03*
X970044Y99961D03*
X978051Y162368D03*
X968906Y207978D03*
Y212978D03*
Y215478D03*
Y210478D03*
X970865Y264068D03*
X973365D03*
X972160Y258880D03*
X977150Y331972D03*
Y338972D03*
X975631Y343112D03*
Y346612D03*
X971721Y407762D03*
X968348Y402369D03*
X971826Y430187D03*
X966694Y427599D03*
X968462Y429368D03*
X970840Y457339D03*
X968340D03*
X962816Y442919D03*
X972030Y446071D03*
X979910Y445603D03*
X970840Y459839D03*
Y462339D03*
X968340D03*
Y459839D03*
X963816Y472905D03*
X976397Y473045D03*
X972397Y465004D03*
X977327Y462371D03*
X965412Y485138D03*
X969297Y478625D03*
Y475825D03*
X970997Y482425D03*
X970412Y485138D03*
X967912D03*
X976873Y491214D03*
Y493714D03*
X970745Y539731D03*
X967042Y537658D03*
X970745Y542231D03*
X978303Y541895D03*
X975803D03*
X967042Y540458D03*
X975503Y544895D03*
X978303D03*
X978581Y582747D03*
X965173Y581222D03*
X978032Y590801D03*
X965173Y591215D03*
X977857Y597130D03*
X976027Y620653D03*
Y617853D03*
X968145Y610562D03*
X965345Y607762D03*
Y610562D03*
X968145Y607762D03*
X977857Y605443D03*
X973857D03*
X972354Y627908D03*
X968365Y633473D03*
X978865Y642184D03*
X966797Y667653D03*
X970197D03*
X965774Y706907D03*
X973712Y722064D03*
X968589Y722434D03*
X970839Y729923D03*
X965042Y722234D03*
X971081Y722637D03*
X978352Y730766D03*
X963950Y734178D03*
X973450Y747280D03*
X965983Y763567D03*
X966127Y776382D03*
X968094Y799792D03*
X976186Y789819D03*
X967562Y802982D03*
X978978Y817618D03*
X978214Y821224D03*
X967337Y828901D03*
X970040Y842903D03*
X969309Y839334D03*
X974437Y849140D03*
X973510Y834991D03*
X967842Y864801D03*
X970299Y853773D03*
X978880Y869552D03*
X967510Y868971D03*
X966813Y904556D03*
X973988Y910038D03*
X968507Y937615D03*
X971443Y938828D03*
X965671Y991564D03*
Y982191D03*
X963864Y1026762D03*
Y1023208D03*
X966366Y1081764D03*
X972776Y1093659D03*
X972255Y1083484D03*
X972776Y1088659D03*
Y1096659D03*
X966330Y1104333D03*
X972776Y1100659D03*
X967936Y1207823D03*
X978614Y1210568D03*
X970761Y1216607D03*
X978614Y1214838D03*
X978169Y1221268D03*
X974985Y1290950D03*
X979996Y1386100D03*
X963883Y1430997D03*
Y1427997D03*
X966883Y1430997D03*
Y1427997D03*
X969883D03*
Y1430997D03*
X975883Y1427997D03*
Y1430997D03*
X972883D03*
Y1427997D03*
X963883Y1433997D03*
X966883D03*
X969883D03*
X963883Y1436997D03*
Y1439997D03*
X966883Y1436997D03*
Y1439997D03*
X969883Y1436997D03*
Y1439997D03*
X975883Y1433997D03*
X972883D03*
X975883Y1436997D03*
X972883D03*
X975883Y1439997D03*
X972883D03*
X977547Y1546081D03*
X974547D03*
X971547D03*
X978958Y85193D03*
Y82593D03*
Y77393D03*
Y74793D03*
Y79993D03*
X987283Y98551D03*
X990178Y114623D03*
Y111223D03*
X990833Y103783D03*
X981029Y104249D03*
Y107649D03*
X990178Y128796D03*
Y125396D03*
X985595Y147540D03*
X989367Y141247D03*
X996834Y143740D03*
X994214Y148277D03*
X980651Y162368D03*
X987751Y162793D03*
Y165393D03*
Y167993D03*
Y170493D03*
X995256Y172190D03*
X994675Y177616D03*
X989959Y181366D03*
X986748Y181426D03*
X992754Y181009D03*
X986956Y184221D03*
X989573Y184012D03*
X994695Y213132D03*
X979362Y208213D03*
Y210713D03*
Y213213D03*
X986234Y208695D03*
X983434D03*
X985934Y211695D03*
X990992Y213859D03*
Y211359D03*
X983434Y211695D03*
X979362Y215713D03*
X994695Y215632D03*
X994939Y256303D03*
X989611Y265701D03*
X994698Y265896D03*
X986429Y270026D03*
X983929D03*
X981129D03*
X983929Y267526D03*
X986429D03*
X981129D03*
X991246Y281716D03*
X997187Y281982D03*
X987517Y314092D03*
X993552Y318175D03*
X990420Y340454D03*
Y337954D03*
X989630Y343862D03*
X983717Y341665D03*
X983956Y346652D03*
X993026Y353813D03*
X981719Y352217D03*
X988631Y349496D03*
X980045Y366559D03*
X986373Y370467D03*
X991392Y409230D03*
X985303Y464652D03*
Y462152D03*
Y459652D03*
X987803Y464652D03*
Y462152D03*
Y459652D03*
X981843Y464818D03*
X992206Y491133D03*
Y498633D03*
X988134Y495151D03*
X985634D03*
X980576Y492987D03*
X985334Y498151D03*
X980576Y495487D03*
X988134Y498151D03*
X992206Y493633D03*
Y496133D03*
X982375Y537877D03*
X992306Y555897D03*
Y553297D03*
X989888Y548366D03*
X987388D03*
X982388D03*
X984888D03*
X982375Y542877D03*
Y545377D03*
Y540377D03*
X992306Y561097D03*
Y563697D03*
Y566797D03*
Y558497D03*
X986301Y570686D03*
X989096Y570478D03*
X989513Y576484D03*
X989156Y573689D03*
X986510Y573303D03*
X992906Y578405D03*
X981857Y597232D03*
X991907Y596782D03*
X986688Y596089D03*
X983843Y619513D03*
Y616713D03*
Y613913D03*
X993857Y605443D03*
X981857Y605637D03*
X980703Y625013D03*
X986600Y717641D03*
X987461Y745796D03*
X981876Y745179D03*
X988371Y764143D03*
X983786Y765647D03*
X984357Y777555D03*
X997051Y778833D03*
X990699Y778630D03*
X987990Y774005D03*
X987394Y787490D03*
X987501Y812573D03*
X985921Y805135D03*
X994051Y810871D03*
X996385Y816141D03*
X979203Y829159D03*
X994094Y829000D03*
X982300Y821200D03*
X987702Y829159D03*
X989700Y846500D03*
X987202Y846395D03*
X987319Y843589D03*
X979203Y833159D03*
X989800Y843900D03*
X987200Y848940D03*
X987703Y837159D03*
X990457Y852043D03*
X983269Y853883D03*
X981700Y856300D03*
X979891Y876589D03*
X992441Y870398D03*
X988054Y888283D03*
X990300Y897500D03*
X979592Y902849D03*
X982783Y909995D03*
X979498Y907500D03*
X989311Y920364D03*
X983227Y968565D03*
X988240Y1020015D03*
Y1016923D03*
Y1023968D03*
X984909Y1081071D03*
X983751Y1078675D03*
X980969Y1076659D03*
X980726Y1084659D03*
X980852Y1098643D03*
X980726Y1104659D03*
Y1092664D03*
X986645Y1108465D03*
X989513Y1097683D03*
X995009Y1131223D03*
X991763Y1140378D03*
Y1128378D03*
Y1134378D03*
X984558Y1140774D03*
X988112Y1137774D03*
X984558Y1128774D03*
Y1134774D03*
X987804Y1131619D03*
X984817Y1303297D03*
X979001Y1288925D03*
X990613Y1324248D03*
Y1327048D03*
X993413Y1324248D03*
Y1327048D03*
X990501Y1320756D03*
X988784Y1361974D03*
X980139Y1381496D03*
X980166Y1373622D03*
X980203Y1377559D03*
X980047Y1397245D03*
X985448Y1398271D03*
X980092Y1389370D03*
X980139Y1393308D03*
X984136Y1401636D03*
X987136D03*
X986949Y1430997D03*
Y1427997D03*
X983949D03*
X989949Y1430997D03*
Y1427997D03*
X983949Y1430997D03*
X992949Y1427997D03*
Y1430997D03*
X986949Y1433997D03*
X983949D03*
X989949D03*
X992949D03*
X986949Y1436997D03*
X983949D03*
X986949Y1439997D03*
X983949D03*
X989949Y1436997D03*
Y1439997D03*
X992949Y1436997D03*
Y1439997D03*
X978934Y1444392D03*
X978987Y1489832D03*
X982241Y1489637D03*
X986773Y1546081D03*
X983773D03*
X980773D03*
X1011284Y68581D03*
X1011297Y80581D03*
X1003379Y72615D03*
Y76587D03*
X1004818Y100625D03*
X997837Y97475D03*
X1013480Y103621D03*
X997768Y106186D03*
X1009191Y112083D03*
X1000580Y121735D03*
Y118335D03*
Y132509D03*
Y135909D03*
X1005397Y141247D03*
X1009884Y143518D03*
X1008984Y152373D03*
X1012936Y178560D03*
X997929Y168697D03*
X1012826Y183834D03*
X1012999Y172665D03*
X999017Y191941D03*
X1003029Y192300D03*
X1012346Y190185D03*
X1007071Y192490D03*
X1013116Y200864D03*
X1003526Y206767D03*
X1006026D03*
X1001026D03*
X1010291Y199582D03*
X1013139Y207037D03*
X1013205Y212455D03*
X1002271Y228221D03*
Y231021D03*
X1010506Y221642D03*
X1003656Y221708D03*
X1006156D03*
X1000571Y224421D03*
X1001156Y221708D03*
X1002822Y236189D03*
X1005322D03*
X1007822D03*
X1002763Y248765D03*
X1005263D03*
X1007763D03*
X999714Y266114D03*
X1008260Y268195D03*
X1005460D03*
X1002960D03*
X1008260Y270695D03*
X1002960D03*
X1005460D03*
X1000698Y300276D03*
X1002580Y309619D03*
X1010499Y309062D03*
X1003181Y323057D03*
X1001105Y318006D03*
X1009770Y344486D03*
X997020Y345354D03*
X1003076Y332496D03*
X1000420Y353954D03*
X996024Y352132D03*
X1001825Y581659D03*
X998332Y578986D03*
X997857Y596729D03*
X995913Y619758D03*
Y616958D03*
Y614158D03*
X1001857Y605443D03*
X1003900Y628700D03*
X1001605Y627605D03*
X1005800Y637600D03*
X1002883Y622521D03*
X1001676Y678015D03*
X1011185Y724519D03*
X1009562Y722438D03*
X1003990Y765899D03*
X1007990D03*
X1002751Y757169D03*
X999990Y764566D03*
X1013151Y756726D03*
X1012695Y776728D03*
X999990Y774671D03*
X1013319Y785929D03*
X1007027Y792973D03*
X998376Y810970D03*
X1006054Y810969D03*
X1010699Y803454D03*
X1002699Y819475D03*
X1011144Y844340D03*
X1010977Y841737D03*
X1012703Y837659D03*
X1001187Y850084D03*
X1004577Y853679D03*
X1004713Y871389D03*
X998313Y888295D03*
X1005413Y905295D03*
X1004953Y923995D03*
X1008935Y924007D03*
X1004994Y955372D03*
X1007919Y948822D03*
X1011019D03*
X1004719D03*
X1012219Y954222D03*
X1006222Y980337D03*
X1009564Y988874D03*
X999879Y998507D03*
X1001805Y1007522D03*
X1008571Y1006648D03*
X1008759Y1023900D03*
X1002180Y1013678D03*
X1002652Y1023731D03*
X1005938Y1018307D03*
X995317Y1137378D03*
X996213Y1324248D03*
Y1327048D03*
X1009333Y1346693D03*
Y1343293D03*
X998600Y1369200D03*
X1008387Y1380797D03*
X998600Y1373400D03*
X997401Y1381200D03*
X999283Y1377400D03*
X1007850Y1368835D03*
X998643Y1398271D03*
X1008138Y1407186D03*
Y1409986D03*
X1005338Y1407186D03*
Y1409986D03*
X1008138Y1415586D03*
Y1412786D03*
X1005338Y1415586D03*
Y1412786D03*
X1008138Y1418386D03*
X1005338D03*
X998949Y1427997D03*
Y1430997D03*
X995949D03*
Y1427997D03*
X1009981Y1431097D03*
Y1428097D03*
X1006981D03*
Y1431097D03*
X998949Y1433997D03*
X995949D03*
X998949Y1436997D03*
X995949D03*
X998949Y1439997D03*
X995949D03*
X1009981Y1434097D03*
X1006981D03*
X1009981Y1437097D03*
X1006981D03*
X1009981Y1440097D03*
X1006981D03*
X1002194Y1444392D03*
X1015059Y55513D03*
X1020519Y60438D03*
X1017659Y60513D03*
X1026200Y86012D03*
X1017787Y85731D03*
X1026200Y94374D03*
X1015427Y88801D03*
X1022293Y94279D03*
X1018344Y94351D03*
X1021341Y86046D03*
X1021537Y116594D03*
X1027480Y110784D03*
X1021537Y119594D03*
X1021971Y124283D03*
X1027037Y124879D03*
X1020378Y161306D03*
X1012134Y152562D03*
X1017629Y157370D03*
X1021713Y176665D03*
Y168665D03*
X1013812Y186629D03*
X1021713Y196665D03*
X1021826Y186778D03*
X1021713Y192665D03*
X1021745Y204864D03*
Y208864D03*
X1026794Y218085D03*
X1017386Y219379D03*
X1018014Y228631D03*
X1023502Y248371D03*
X1014420Y265897D03*
X1011920D03*
X1027216Y289440D03*
X1022604Y290262D03*
X1016635Y300276D03*
X1012635D03*
X1025749D03*
X1020635D03*
X1022435Y312865D03*
X1021848Y310396D03*
X1020406Y350772D03*
X1012188Y443421D03*
X1015659Y679654D03*
Y683054D03*
X1021885Y698974D03*
X1022937Y691421D03*
X1014641Y724436D03*
X1012851Y722417D03*
X1026916Y719769D03*
X1018015Y751565D03*
X1013486Y750773D03*
X1024684Y756485D03*
X1017664Y779101D03*
X1014064Y793660D03*
X1018071Y798490D03*
X1013821Y813520D03*
X1014781Y810319D03*
X1017955Y812097D03*
X1021895Y818974D03*
X1020703Y837659D03*
X1013918Y851306D03*
X1017800Y867065D03*
X1016973Y877196D03*
X1016574Y874537D03*
X1016798Y890299D03*
X1021408Y895008D03*
X1024913Y884000D03*
X1012842Y910685D03*
X1022346Y917669D03*
X1029570Y917718D03*
X1018419Y917575D03*
X1014719Y938322D03*
X1027319D03*
X1027719Y958822D03*
X1014009Y980356D03*
X1018009D03*
X1014009Y988813D03*
X1018009D03*
X1021924Y980456D03*
X1026009Y988813D03*
X1022009D03*
X1017998Y1009655D03*
X1015198D03*
X1024570Y1024003D03*
X1011782Y1016591D03*
X1022143Y1030672D03*
X1019143D03*
X1016143D03*
X1025143D03*
X1023144Y1109564D03*
X1017297D03*
X1023144Y1122164D03*
X1017297D03*
X1023144Y1134764D03*
X1017297D03*
X1023144Y1147364D03*
X1017297D03*
X1023144Y1159964D03*
X1017297D03*
Y1172564D03*
X1023162Y1174445D03*
X1023139Y1184856D03*
X1017297Y1185164D03*
X1026221Y1214372D03*
X1021976Y1218169D03*
X1023358Y1363921D03*
X1013991Y1360842D03*
X1019391Y1377061D03*
X1012981Y1431097D03*
Y1428097D03*
X1015981D03*
Y1431097D03*
X1021981Y1428097D03*
Y1431097D03*
X1018981D03*
Y1428097D03*
X1012981Y1434097D03*
X1015981D03*
X1012981Y1437097D03*
Y1440097D03*
X1015981Y1437097D03*
Y1440097D03*
X1021981Y1434097D03*
X1018981D03*
X1021981Y1437097D03*
X1018981D03*
X1021981Y1440097D03*
X1018981D03*
X1025615Y1444492D03*
X1020023Y1489637D03*
X1016769Y1489832D03*
X1043123Y97667D03*
X1033506Y116594D03*
X1038779Y102495D03*
X1032480Y110784D03*
X1033506Y119594D03*
X1037040Y125107D03*
X1032059Y124663D03*
X1038513Y142862D03*
X1045654Y143762D03*
X1039554Y148717D03*
X1033403Y138838D03*
X1042102Y195176D03*
X1042183Y210509D03*
X1029594Y218085D03*
X1036107Y221970D03*
X1036173Y226320D03*
X1036107Y219470D03*
Y216970D03*
X1033394Y216385D03*
X1043875Y230556D03*
X1039134Y228646D03*
X1042860Y242078D03*
X1038091Y232971D03*
X1034741Y244571D03*
X1032121Y249108D03*
X1042084Y256394D03*
X1037290Y296293D03*
X1033890D03*
X1045650Y300093D03*
X1029639Y300141D03*
X1041783Y321114D03*
X1030220Y313554D03*
X1042948Y333696D03*
X1043106Y340230D03*
X1031259Y350427D03*
X1029885Y711762D03*
X1033200Y731700D03*
X1035619Y755809D03*
X1038344Y756476D03*
X1043016Y782161D03*
X1038678Y776750D03*
X1039251Y812340D03*
X1042414Y801443D03*
X1043425Y830800D03*
X1043626Y836563D03*
X1041100Y838500D03*
X1037527Y836486D03*
X1031813Y850273D03*
X1046045Y841217D03*
X1040822Y841339D03*
X1044390Y861210D03*
X1035185Y862793D03*
X1037685Y862789D03*
X1038363Y875288D03*
X1037709Y886209D03*
X1038010Y902565D03*
X1033019Y933022D03*
Y935822D03*
X1030819Y938422D03*
X1033370Y953994D03*
X1038009Y988813D03*
X1030009D03*
X1042009D03*
X1034009D03*
X1028943Y1016827D03*
X1034790D03*
X1028943Y1029427D03*
X1034790D03*
X1039499Y1098758D03*
X1039053Y1105091D03*
X1044553D03*
X1039098Y1102091D03*
X1039053Y1117691D03*
X1044553D03*
X1039098Y1114691D03*
Y1127291D03*
X1039053Y1130291D03*
X1044553D03*
Y1142891D03*
X1039098Y1139891D03*
X1039053Y1142891D03*
Y1155491D03*
X1044553D03*
X1039098Y1152491D03*
X1044553Y1168091D03*
X1039053D03*
X1039098Y1165091D03*
X1044553Y1180691D03*
X1039053D03*
X1039098Y1177691D03*
X1032831Y1207950D03*
X1029797Y1220921D03*
X1040606Y1230407D03*
X1043588Y1227300D03*
X1032867Y1431213D03*
Y1428213D03*
X1029867D03*
X1035867Y1431213D03*
Y1428213D03*
X1029867Y1431213D03*
X1038867Y1428213D03*
Y1431213D03*
X1041867D03*
Y1428213D03*
X1032867Y1434213D03*
X1029867D03*
X1035867D03*
X1038867D03*
X1032867Y1437213D03*
X1029867D03*
X1032867Y1440213D03*
X1029867D03*
X1035867Y1437213D03*
Y1440213D03*
X1038867Y1437213D03*
Y1440213D03*
X1041867Y1434213D03*
Y1437213D03*
Y1440213D03*
X1051583Y103411D03*
X1051977Y97667D03*
X1047373Y95111D03*
X1051742Y106561D03*
X1047102Y195176D03*
X1046120Y199248D03*
X1044602Y195176D03*
X1049120Y199248D03*
X1049602Y195176D03*
X1046120Y201748D03*
X1049120Y202048D03*
X1044683Y210509D03*
X1046456Y206806D03*
X1043956D03*
X1052720Y230117D03*
X1048130Y227824D03*
X1048736Y238714D03*
X1048217Y246874D03*
X1050437Y244297D03*
X1045364Y279895D03*
X1051796Y279965D03*
X1050164Y302748D03*
X1050076Y305512D03*
X1061387Y343509D03*
X1060679Y356151D03*
X1059549Y458711D03*
X1055885Y554555D03*
X1046068Y792742D03*
X1046930Y796557D03*
X1048314Y833102D03*
X1053392Y832788D03*
X1051550Y823146D03*
X1055700Y840900D03*
X1053913Y837718D03*
X1050358Y837793D03*
X1052500Y841200D03*
X1049087Y856033D03*
X1053909Y855472D03*
X1045300Y872352D03*
X1054900Y879321D03*
X1058155Y887635D03*
X1050295Y891100D03*
X1054009Y988813D03*
X1046009D03*
X1050009D03*
X1058009D03*
X1056199Y1012354D03*
X1050744Y1009354D03*
X1056199Y1024954D03*
X1050699D03*
Y1012354D03*
X1050744Y1021954D03*
X1046485Y1034538D03*
X1057212Y1040356D03*
X1049930Y1221407D03*
X1050605Y1224472D03*
X1049770Y1229402D03*
X1049720Y1234921D03*
X1052660Y1293257D03*
X1050002Y1293283D03*
X1049204Y1337377D03*
X1049670Y1347462D03*
X1046075Y1350650D03*
X1049493Y1350694D03*
X1044867Y1428213D03*
Y1431213D03*
Y1434213D03*
Y1437213D03*
Y1440213D03*
X1048403Y1444608D03*
X1062773Y90650D03*
X1068085Y90615D03*
X1072456Y95236D03*
X1072406Y99961D03*
X1062523Y95236D03*
X1071268Y207978D03*
Y212978D03*
Y215478D03*
Y210478D03*
X1074597Y264180D03*
X1074522Y258880D03*
X1076571Y310574D03*
X1060679Y368276D03*
X1062234Y378600D03*
Y382600D03*
X1062349Y458711D03*
X1064876Y453682D03*
X1063113Y455921D03*
X1061693Y463600D03*
X1062098Y603600D03*
X1061342Y610269D03*
X1061496Y612786D03*
X1062098Y619600D03*
X1063642Y634190D03*
X1062098Y623600D03*
X1066931Y645389D03*
X1060698Y931619D03*
X1069685Y933391D03*
X1066878Y931909D03*
X1070009Y988813D03*
X1069607Y980131D03*
X1066009Y980330D03*
X1062009Y988813D03*
X1065823Y988773D03*
X1074009Y988813D03*
X1070009Y997860D03*
X1073525Y1012428D03*
X1076110Y1029535D03*
X1065079Y1036920D03*
X1076577Y1041332D03*
X1074232Y1055836D03*
X1067866Y1051037D03*
X1060768Y1053457D03*
X1074650Y1070006D03*
X1069642Y1445541D03*
X1068861Y1451311D03*
X1081320Y85193D03*
Y82593D03*
Y79993D03*
Y77393D03*
Y74793D03*
X1089645Y98551D03*
X1081364Y92874D03*
X1092540Y111223D03*
Y114623D03*
X1083391Y104249D03*
Y107649D03*
X1092540Y128796D03*
Y125396D03*
X1087957Y147540D03*
X1091729Y141247D03*
X1083013Y162368D03*
X1090113Y165393D03*
Y162793D03*
X1080413Y162368D03*
X1090113Y170493D03*
Y167993D03*
X1092321Y181366D03*
X1089110Y181426D03*
X1091935Y184012D03*
X1089318Y184221D03*
X1081724Y208213D03*
X1085796Y208695D03*
Y211695D03*
X1081724Y210713D03*
Y213213D03*
X1088596Y208695D03*
X1088296Y211695D03*
X1081724Y215713D03*
X1077097Y264180D03*
X1091973Y265701D03*
X1083491Y267526D03*
X1088791D03*
X1086291D03*
X1083491Y270026D03*
X1086291D03*
X1088791D03*
X1093608Y281716D03*
X1080351Y328256D03*
X1079748Y322743D03*
Y319343D03*
X1080351Y331656D03*
X1082297Y340770D03*
X1092554Y340318D03*
X1085615Y339815D03*
X1092561Y353374D03*
X1082787Y348501D03*
X1091031Y374810D03*
X1089788Y550907D03*
X1087288D03*
X1089788Y553407D03*
X1087288D03*
X1089096Y541863D03*
Y545263D03*
X1091558Y566929D03*
X1091272Y569426D03*
X1088949Y568475D03*
X1089206Y570962D03*
X1086859Y569928D03*
X1085512Y572070D03*
X1078920Y856700D03*
X1090375Y899047D03*
X1076800Y1012900D03*
X1078755Y1031518D03*
X1079178Y1037884D03*
X1076868Y1047293D03*
X1079910Y1045264D03*
X1079822Y1151870D03*
X1083562Y1155610D03*
X1079822Y1159350D03*
X1083283Y1526583D03*
X1084000Y1529600D03*
X1091529Y1528718D03*
X1091525Y1546300D03*
X1090876Y1554183D03*
X1091569Y1561300D03*
X1092527Y1579422D03*
X1086469Y1588435D03*
X1090469D03*
X1083900Y1593206D03*
X1082176Y1600598D03*
X1090904Y1599047D03*
X1088021Y1606949D03*
X1093778Y1599574D03*
X1086904Y1599004D03*
X1090093Y1628297D03*
X1085474Y1629028D03*
X1089474Y1638213D03*
X1105741Y76587D03*
Y72615D03*
X1100199Y97475D03*
X1107180Y100625D03*
X1100130Y106186D03*
X1093195Y103783D03*
X1102942Y118335D03*
Y132509D03*
Y121735D03*
Y135909D03*
X1107759Y141247D03*
X1099196Y143740D03*
X1096576Y148277D03*
X1095116Y181009D03*
X1100291Y168697D03*
X1097618Y172190D03*
X1109903Y171523D03*
X1097037Y177616D03*
X1101379Y191941D03*
X1109433Y192490D03*
X1105888Y206767D03*
X1108388D03*
X1103388D03*
X1093354Y213859D03*
Y211359D03*
X1097057Y213132D03*
X1104633Y228221D03*
X1106018Y221708D03*
X1108518D03*
X1102933Y224421D03*
X1103518Y221708D03*
X1104633Y231021D03*
X1097057Y215632D03*
X1105184Y236189D03*
X1107684D03*
X1105125Y248765D03*
X1107625D03*
X1097301Y256303D03*
X1102076Y266114D03*
X1097060Y265896D03*
X1107822Y268195D03*
X1105322D03*
Y270695D03*
X1107822D03*
X1099549Y281982D03*
X1093478Y310305D03*
X1108779Y327705D03*
X1103432Y340544D03*
X1097976Y340477D03*
X1105012Y353504D03*
X1098845Y353404D03*
X1093841Y371335D03*
X1099501Y545528D03*
X1108236Y577716D03*
X1105298Y610400D03*
X1108045Y668153D03*
X1092769Y936975D03*
X1095080Y1513398D03*
X1096780Y1526700D03*
X1101402Y1531702D03*
X1095250Y1531600D03*
X1098617Y1546183D03*
X1096780Y1535400D03*
X1100876Y1554183D03*
X1099371Y1561153D03*
X1100476Y1579318D03*
X1102904Y1566668D03*
X1093682Y1582433D03*
X1098498Y1590435D03*
X1104233Y1587983D03*
X1100233Y1588000D03*
X1107620Y1603602D03*
X1098904Y1602138D03*
X1101946Y1614709D03*
X1096941Y1627905D03*
X1105474Y1629450D03*
X1101474Y1637820D03*
X1093474Y1638213D03*
X1105474Y1638426D03*
X1097474Y1637753D03*
X1114781Y58013D03*
X1113646Y68581D03*
X1120021Y60513D03*
X1122881Y60438D03*
X1113659Y80581D03*
X1120149Y85731D03*
X1117789Y88801D03*
X1123703Y86046D03*
X1120706Y94351D03*
X1124655Y94279D03*
X1115842Y103621D03*
X1123899Y116594D03*
X1111553Y112083D03*
X1123899Y119594D03*
X1124333Y124283D03*
X1112246Y143518D03*
X1111346Y152373D03*
X1122740Y161306D03*
X1114496Y152562D03*
X1119991Y157370D03*
X1124075Y168665D03*
Y176665D03*
X1115188Y183834D03*
X1115298Y178560D03*
X1115361Y172665D03*
X1116174Y186629D03*
X1124075Y192665D03*
Y196665D03*
X1115478Y200864D03*
X1114708Y190185D03*
X1124188Y186778D03*
X1124107Y204864D03*
X1115501Y207037D03*
X1115567Y212455D03*
X1124107Y208864D03*
X1112868Y221642D03*
X1119748Y219379D03*
X1120376Y228631D03*
X1110184Y236189D03*
X1110125Y248765D03*
X1116782Y265897D03*
X1114282D03*
X1110622Y268195D03*
Y270695D03*
X1115000Y329000D03*
Y334000D03*
Y339000D03*
X1118848Y382109D03*
X1118847Y551683D03*
Y561420D03*
Y558917D03*
X1122705Y588515D03*
X1114668Y577937D03*
X1117673Y606929D03*
X1122673Y595500D03*
X1122173Y604567D03*
X1122705Y591015D03*
X1123331Y610072D03*
X1123267Y616317D03*
X1117633Y618400D03*
X1117914Y612592D03*
X1115151Y650119D03*
X1115320Y646449D03*
X1115054Y662981D03*
X1116296Y691851D03*
X1111785Y686971D03*
X1118105Y707592D03*
X1128562Y86012D03*
Y94374D03*
X1135868Y116594D03*
X1141141Y102495D03*
X1129842Y110784D03*
X1134842D03*
X1135868Y119594D03*
X1139402Y125107D03*
X1129399Y124879D03*
X1134421Y124663D03*
X1140875Y142862D03*
X1141916Y148717D03*
X1135765Y138838D03*
X1129156Y218085D03*
X1131956D03*
X1138469Y221970D03*
X1138535Y226320D03*
X1138469Y219470D03*
Y216970D03*
X1135756Y216385D03*
X1141496Y228646D03*
X1140453Y232971D03*
X1137103Y244571D03*
X1134483Y249108D03*
X1125864Y248371D03*
X1137830Y336230D03*
X1135548Y455804D03*
X1134629Y465551D03*
X1126622Y506256D03*
X1139673Y530000D03*
X1139173Y540500D03*
X1138373Y549800D03*
X1138173Y547075D03*
X1137673Y568000D03*
X1138213Y558800D03*
X1138277Y562800D03*
X1129471Y732571D03*
X1153945Y103411D03*
X1145485Y97667D03*
X1154339D03*
X1149735Y95111D03*
X1154104Y106561D03*
X1148016Y143762D03*
X1149464Y195176D03*
X1148482Y199248D03*
X1151482D03*
X1144464Y195176D03*
X1146964D03*
X1151964D03*
X1151482Y202048D03*
X1146318Y206806D03*
X1144545Y210509D03*
X1147045D03*
X1148818Y206806D03*
X1148482Y201748D03*
X1146237Y230556D03*
X1155082Y230117D03*
X1150492Y227824D03*
X1151098Y238714D03*
X1145222Y242078D03*
X1150579Y246874D03*
X1152799Y244297D03*
X1147590Y253198D03*
X1145587Y339148D03*
X1142440Y396718D03*
X1157451Y618288D03*
X1156275Y656321D03*
X1155146Y699491D03*
X1152512Y728543D03*
X1148962Y747253D03*
X1152485Y764552D03*
X1147468Y766093D03*
X1154652Y791056D03*
X1145910Y803642D03*
X1153485Y813142D03*
X1154985Y802897D03*
X1153229Y848581D03*
X1170447Y90615D03*
X1165135Y90650D03*
X1174768Y99961D03*
X1164885Y95236D03*
X1173630Y207978D03*
Y210478D03*
Y212978D03*
Y215478D03*
X1173559Y304948D03*
X1171445Y422088D03*
X1166868Y442956D03*
X1168685Y438323D03*
X1168398Y456309D03*
X1168851Y445873D03*
X1163298Y465874D03*
X1159535Y546712D03*
Y542712D03*
X1165400Y553300D03*
X1167900D03*
X1161451Y618288D03*
X1160275Y656321D03*
X1164275D03*
X1162863Y678519D03*
X1159173Y678462D03*
X1170465Y677836D03*
X1157646Y699491D03*
X1162646D03*
X1160146D03*
X1169256Y694983D03*
X1163774Y713347D03*
X1166115Y718469D03*
X1171934Y733857D03*
X1173034Y765060D03*
X1169697Y791935D03*
X1164925Y791607D03*
X1164732Y802269D03*
X1173122Y802759D03*
X1163579Y850774D03*
X1161535Y844167D03*
X1159887Y869106D03*
X1174461Y914515D03*
X1183682Y85193D03*
Y82593D03*
Y74793D03*
Y79993D03*
Y77393D03*
X1183726Y92874D03*
X1174818Y95236D03*
X1185753Y107649D03*
Y104249D03*
X1182775Y162368D03*
X1185375D03*
X1188158Y211695D03*
X1184086Y210713D03*
Y213213D03*
Y208213D03*
X1190958Y208695D03*
X1188158D03*
X1184086Y215713D03*
X1176959Y264180D03*
X1179459D03*
X1177035Y257919D03*
X1185853Y267526D03*
X1188653D03*
X1185853Y270026D03*
X1188653D03*
X1179901Y306366D03*
X1181706Y310131D03*
X1178045Y312193D03*
X1181379Y316049D03*
X1174929Y319167D03*
X1179761Y336380D03*
X1187996Y331992D03*
X1191748Y392676D03*
X1188598Y381500D03*
X1178083Y442856D03*
X1189122Y442606D03*
X1176699Y451108D03*
X1176138Y458455D03*
X1179184Y453881D03*
Y446595D03*
X1188739Y446606D03*
X1190046Y463479D03*
X1174595Y771744D03*
X1176500Y784933D03*
X1185516Y844248D03*
X1190968Y848703D03*
X1184340Y851072D03*
X1183012Y856553D03*
X1190213Y856816D03*
X1187431Y868340D03*
X1180239Y868430D03*
X1179858Y883455D03*
X1179727Y886197D03*
X1181654Y894671D03*
X1185058Y883475D03*
X1187151Y921000D03*
X1182000Y936500D03*
X1189219Y940703D03*
X1192007Y98551D03*
X1202561Y97475D03*
X1194902Y114623D03*
Y111223D03*
X1195557Y103783D03*
X1202492Y106186D03*
X1205304Y118335D03*
Y121735D03*
X1194902Y128796D03*
X1205304Y132509D03*
X1194902Y125396D03*
X1205304Y135909D03*
X1190319Y147540D03*
X1194091Y141247D03*
X1201558Y143740D03*
X1198938Y148277D03*
X1192475Y165393D03*
Y162793D03*
Y167993D03*
Y170493D03*
X1199980Y172190D03*
X1194683Y181366D03*
X1191472Y181426D03*
X1197478Y181009D03*
X1202653Y168697D03*
X1199399Y177616D03*
X1203741Y191941D03*
X1194297Y184012D03*
X1191680Y184221D03*
X1205750Y206767D03*
X1195716Y211359D03*
Y213859D03*
X1199419Y213132D03*
X1190658Y211695D03*
X1205295Y224421D03*
X1205880Y221708D03*
X1199419Y215632D03*
X1199663Y256303D03*
X1199422Y265896D03*
X1204438Y266114D03*
X1194335Y265701D03*
X1191153Y267526D03*
Y270026D03*
X1201911Y281982D03*
X1195970Y281716D03*
X1201113Y315039D03*
X1190127Y324142D03*
X1195800Y324000D03*
X1206531Y393858D03*
X1208173Y398583D03*
X1192702Y440489D03*
X1192957Y435158D03*
X1193000Y444841D03*
X1192686Y449961D03*
X1196403Y458572D03*
X1192431Y868620D03*
X1192152Y884399D03*
X1192367Y903785D03*
X1190210Y900909D03*
X1191151Y936296D03*
X1193219Y940703D03*
X1197173Y940645D03*
X1196352Y951033D03*
X1191219Y967757D03*
X1191928Y987314D03*
X1198644Y985289D03*
X1195757Y988131D03*
X1203419Y1011161D03*
X1200008D03*
X1196300Y998600D03*
X1202028Y998349D03*
X1199700Y1013661D03*
X1201800Y1019431D03*
X1219783Y55513D03*
X1216008Y68581D03*
X1222383Y60513D03*
X1216021Y80581D03*
X1208103Y72615D03*
Y76587D03*
X1222511Y85731D03*
X1220151Y88801D03*
X1218204Y103621D03*
X1209542Y100625D03*
X1213915Y112083D03*
X1210121Y141247D03*
X1214608Y143518D03*
X1213708Y152373D03*
X1216858Y152562D03*
X1222353Y157370D03*
X1217550Y183834D03*
X1212265Y171523D03*
X1217723Y172665D03*
X1217660Y178560D03*
X1218536Y186629D03*
X1211795Y192490D03*
X1210268Y198671D03*
X1217840Y200864D03*
X1217070Y190185D03*
X1207753Y192300D03*
X1208250Y206767D03*
X1210750D03*
X1217863Y207037D03*
X1217929Y212455D03*
X1215230Y221642D03*
X1206995Y228221D03*
X1208380Y221708D03*
X1210880D03*
X1206995Y231021D03*
X1222110Y219379D03*
X1222738Y228631D03*
X1207546Y236189D03*
X1210046D03*
X1212546D03*
X1207487Y248765D03*
X1209987D03*
X1212487D03*
X1219144Y265897D03*
X1216644D03*
X1212984Y268195D03*
X1210184D03*
X1207684D03*
X1212984Y270695D03*
X1207684D03*
X1210184D03*
X1220723Y324466D03*
X1211892Y339559D03*
X1215776Y331072D03*
X1213173Y377912D03*
X1217177Y369925D03*
X1206693Y384410D03*
X1213173Y386500D03*
X1209872Y382047D03*
X1212173Y391496D03*
X1213261Y397912D03*
X1210173Y403500D03*
X1212173Y409000D03*
X1209426Y433069D03*
Y430469D03*
Y435669D03*
Y440869D03*
Y438269D03*
X1206626Y433069D03*
Y430469D03*
Y435669D03*
Y440869D03*
Y438269D03*
X1209980Y451677D03*
X1207480Y454177D03*
X1209980D03*
X1207480Y451677D03*
X1209184Y463618D03*
Y460218D03*
X1225243Y60438D03*
X1230924Y86012D03*
Y94374D03*
X1226065Y86046D03*
X1227017Y94279D03*
X1223068Y94351D03*
X1238230Y116594D03*
X1226261D03*
X1232204Y110784D03*
X1237204D03*
X1238230Y119594D03*
X1226261D03*
X1236783Y124663D03*
X1226695Y124283D03*
X1231761Y124879D03*
X1238127Y138838D03*
X1225102Y161306D03*
X1226437Y176665D03*
Y168665D03*
Y192665D03*
X1226550Y186778D03*
X1226469Y204864D03*
Y208864D03*
X1231518Y218085D03*
X1234318D03*
X1238118Y216385D03*
X1239465Y244571D03*
X1236845Y249108D03*
X1228226Y248371D03*
X1229252Y314890D03*
X1229028Y311740D03*
X1226436Y324518D03*
X1229922Y324550D03*
X1234904Y316942D03*
X1232197Y316964D03*
X1238293Y317296D03*
X1229438Y332584D03*
X1235589Y348015D03*
X1229942Y347937D03*
X1231506Y353470D03*
X1223431Y377912D03*
X1225755Y369391D03*
X1229122Y369355D03*
X1222601Y369251D03*
X1223431Y381912D03*
Y397912D03*
X1232833Y539315D03*
X1232149Y550137D03*
X1234941D03*
X1235930Y626229D03*
X1235292Y622912D03*
X1237500Y632405D03*
X1238034Y629961D03*
X1238695Y627313D03*
X1256307Y103411D03*
X1247847Y97667D03*
X1256701D03*
X1252097Y95111D03*
X1243503Y102495D03*
X1241764Y125107D03*
X1243237Y142862D03*
X1250378Y143762D03*
X1244278Y148717D03*
X1251826Y195176D03*
X1254326D03*
X1253844Y199248D03*
X1249326Y195176D03*
X1250844Y199248D03*
X1246826Y195176D03*
X1249407Y210509D03*
X1253844Y202048D03*
X1250844Y201748D03*
X1251180Y206806D03*
X1248680D03*
X1246907Y210509D03*
X1240831Y221970D03*
X1240897Y226320D03*
X1240831Y219470D03*
Y216970D03*
X1248599Y230556D03*
X1252854Y227824D03*
X1243858Y228646D03*
X1253460Y238714D03*
X1247584Y242078D03*
X1252941Y246874D03*
X1242815Y232971D03*
X1246808Y256394D03*
X1241205Y303962D03*
X1253245Y416888D03*
Y419488D03*
Y422088D03*
X1253087Y553101D03*
X1241629Y550065D03*
X1248106Y1004700D03*
X1245400Y1003700D03*
X1246000Y1014800D03*
X1252148Y1026223D03*
X1252500Y1014288D03*
X1246300Y1027800D03*
X1253424Y1138130D03*
X1250928Y1142828D03*
X1254200Y1146600D03*
X1249363Y1173065D03*
X1256218Y1175987D03*
X1249363Y1166065D03*
X1255439Y1172008D03*
X1255628Y1188345D03*
X1253056Y1194917D03*
X1254275Y1531334D03*
X1249894Y1527805D03*
X1253904Y1519645D03*
X1254275Y1539334D03*
X1250434Y1535334D03*
X1267497Y90650D03*
X1267247Y95236D03*
X1256466Y106561D03*
X1257444Y230117D03*
X1255161Y244297D03*
X1266962Y302167D03*
X1262665Y302730D03*
X1263328Y309003D03*
X1262075Y324075D03*
X1261659Y318258D03*
X1264088Y320382D03*
X1266616Y322456D03*
X1257000Y333500D03*
X1264215Y333215D03*
X1262500Y330655D03*
X1256000Y338000D03*
X1259991Y340691D03*
X1256000Y340500D03*
X1263500Y336000D03*
X1264659Y377173D03*
X1267944Y371767D03*
X1261764Y391533D03*
X1263484Y385644D03*
X1268659Y385123D03*
X1268067Y406060D03*
X1261231Y399918D03*
X1264336Y412106D03*
X1268328Y421489D03*
Y418889D03*
Y416289D03*
X1270397Y447081D03*
X1259223Y454334D03*
X1267540Y459330D03*
X1267493Y454214D03*
X1267836Y449045D03*
X1267843Y473571D03*
Y481071D03*
Y478571D03*
Y476071D03*
X1269629Y848124D03*
X1270892Y856343D03*
X1271121Y892513D03*
X1270276Y897062D03*
X1269221Y894760D03*
X1270586Y905324D03*
X1272661Y929858D03*
X1260539Y1134729D03*
X1267921D03*
X1266718Y1142666D03*
X1263921Y1134729D03*
X1268593Y1157544D03*
X1267104Y1167768D03*
X1272123D03*
X1271246Y1178240D03*
X1271256Y1185205D03*
X1262605Y1187215D03*
X1262298Y1180175D03*
X1260800Y1191096D03*
X1268571Y1201043D03*
X1264575D03*
X1261538Y1199814D03*
X1255296Y1196056D03*
X1263449Y1217228D03*
X1266113Y1219895D03*
X1269388Y1223170D03*
X1267333Y1531334D03*
X1262891Y1527334D03*
X1267183Y1539334D03*
X1262891Y1535334D03*
X1286044Y85539D03*
Y82939D03*
Y75139D03*
Y80339D03*
Y77739D03*
X1286088Y92874D03*
X1272809Y90615D03*
X1277130Y99961D03*
X1277180Y95236D03*
X1285137Y162368D03*
X1275992Y215478D03*
Y212978D03*
Y210478D03*
Y207978D03*
X1286448Y213213D03*
Y210713D03*
Y208213D03*
Y215713D03*
X1281821Y264180D03*
X1279321D03*
X1279246Y258880D03*
X1271571Y281185D03*
X1289345Y330655D03*
X1284419Y359377D03*
X1287437Y379429D03*
X1280699Y377173D03*
X1284659D03*
X1274436Y377350D03*
X1276659Y385123D03*
X1273659D03*
X1280659D03*
X1284333Y391569D03*
X1282760Y401066D03*
X1272421Y403300D03*
X1271828Y405889D03*
Y408489D03*
Y413689D03*
Y411089D03*
Y416289D03*
Y421489D03*
Y418889D03*
Y424089D03*
X1272215Y432718D03*
Y435518D03*
X1282092Y442118D03*
Y439318D03*
X1271828Y426689D03*
X1272927Y450091D03*
X1275927D03*
X1273397Y447081D03*
X1281737Y461034D03*
Y456034D03*
X1272927Y462060D03*
X1275927D03*
X1286005Y485580D03*
X1280631Y480194D03*
Y477694D03*
X1277897Y478876D03*
Y476376D03*
X1274415Y477053D03*
X1271915D03*
X1284900Y678800D03*
X1283400Y715500D03*
X1278255Y722241D03*
X1283400Y719700D03*
X1282539Y746076D03*
X1279539Y748576D03*
X1282539Y751076D03*
X1279539Y763576D03*
X1282539Y766076D03*
X1279539Y758576D03*
X1282539Y756076D03*
Y761076D03*
X1279539Y753576D03*
Y768576D03*
Y780576D03*
Y784576D03*
X1285092Y819500D03*
X1285500Y827500D03*
X1281388Y827388D03*
X1281777Y823500D03*
X1285500Y843500D03*
X1281331Y843331D03*
X1281269Y835492D03*
X1285500Y835500D03*
X1283025Y848305D03*
X1271438Y861846D03*
X1285500Y863500D03*
Y859500D03*
Y855500D03*
Y851500D03*
X1279460Y854487D03*
Y859487D03*
Y864487D03*
X1274396Y866896D03*
X1285500Y867500D03*
X1279460Y874487D03*
Y869487D03*
Y879487D03*
X1285302Y877283D03*
X1282285Y865602D03*
X1274264Y898591D03*
X1279460Y884487D03*
X1285302Y885783D03*
X1279299Y898813D03*
X1279460Y889487D03*
X1285302Y881783D03*
X1281075Y911075D03*
X1282184Y898854D03*
X1274400Y914123D03*
X1283494Y907176D03*
X1275493Y929858D03*
X1279493D03*
X1283493D03*
X1279693Y919800D03*
X1274670Y919808D03*
X1281400Y940256D03*
X1289547Y941000D03*
X1281733Y949475D03*
X1275788Y1124088D03*
X1282421Y1137129D03*
X1271921Y1134729D03*
X1275794D03*
X1282830Y1150087D03*
X1275050Y1157404D03*
X1280306Y1170767D03*
X1275965Y1187232D03*
X1280602Y1185238D03*
X1280395Y1180235D03*
X1272541Y1201043D03*
X1276575Y1201039D03*
X1280575Y1200969D03*
X1280694Y1208993D03*
X1274446Y1228226D03*
X1272235Y1226016D03*
X1297785Y33768D03*
X1302139Y26325D03*
X1302785Y31168D03*
X1294369Y98551D03*
X1304923Y97475D03*
X1297264Y114623D03*
Y111223D03*
X1297919Y103783D03*
X1288115Y104249D03*
Y107649D03*
X1297264Y128796D03*
Y125396D03*
X1294837Y162793D03*
X1287737Y162368D03*
X1294837Y165393D03*
Y167993D03*
Y170493D03*
X1301761Y177616D03*
X1302342Y172190D03*
X1299840Y181009D03*
X1293834Y181426D03*
X1297045Y181366D03*
X1294042Y184221D03*
X1296659Y184012D03*
X1301781Y213132D03*
X1298078Y211359D03*
Y213859D03*
X1290520Y211695D03*
X1293020D03*
X1290520Y208695D03*
X1293320D03*
X1301781Y215632D03*
X1302025Y256303D03*
X1296697Y265701D03*
X1301784Y265896D03*
X1293515Y270026D03*
X1291015D03*
X1288215D03*
Y267526D03*
X1293515D03*
X1291015D03*
X1304273Y281982D03*
X1298332Y281716D03*
X1294000Y324000D03*
X1303000Y326692D03*
X1293000Y338500D03*
X1303000Y331000D03*
X1302896Y343797D03*
Y340397D03*
X1292500Y335000D03*
X1299959Y356954D03*
X1294080Y349820D03*
X1291410Y371060D03*
X1295410Y371076D03*
X1293048Y379088D03*
X1298346Y379028D03*
X1293100Y409539D03*
X1296100D03*
X1293100Y406739D03*
X1296100Y407039D03*
X1295764Y401981D03*
X1298264D03*
X1300037Y398278D03*
X1297537D03*
X1292618Y413611D03*
X1295118D03*
X1300118D03*
X1297618D03*
X1292383Y424067D03*
X1294883D03*
X1299883D03*
X1297383D03*
X1299757Y438293D03*
Y441093D03*
X1290092Y442118D03*
Y439318D03*
X1299757Y443893D03*
X1287719Y470001D03*
X1290219D03*
X1299867Y477318D03*
X1299466Y466409D03*
X1299807Y472020D03*
X1288144Y489036D03*
X1291005Y485580D03*
X1288505D03*
X1301314Y484882D03*
X1299304Y487382D03*
X1290380Y495636D03*
Y492836D03*
X1300817Y568635D03*
X1301194Y565518D03*
X1305836Y660009D03*
X1298963Y659609D03*
X1289811Y677612D03*
X1289317Y706932D03*
X1291604Y781576D03*
Y776576D03*
Y771435D03*
X1295491Y798821D03*
X1298720Y798975D03*
X1289730Y806845D03*
X1302140Y812625D03*
X1302501Y824747D03*
X1297667Y832150D03*
X1293500Y827500D03*
X1296770Y828775D03*
X1293500Y843500D03*
Y835500D03*
X1296687Y839500D03*
X1293500Y851500D03*
X1294000Y863500D03*
X1293500Y879800D03*
Y871800D03*
Y875800D03*
X1288164Y892354D03*
X1296866Y894993D03*
X1305250Y889250D03*
X1293272Y887800D03*
X1293500Y883800D03*
X1291129Y892267D03*
X1294264Y905595D03*
X1301657Y899129D03*
X1288500Y901254D03*
X1298966Y899610D03*
X1296466D03*
X1298000Y917000D03*
X1294075D03*
X1304949Y928546D03*
X1292500Y928000D03*
X1295453Y928047D03*
X1291059Y917000D03*
X1302000D03*
X1302500Y939500D03*
X1300882Y937144D03*
X1296500Y961500D03*
X1289500Y949500D03*
X1300500Y960000D03*
X1290792Y961363D03*
X1300500Y970187D03*
X1297558Y970216D03*
X1292836Y975244D03*
X1292631Y979845D03*
X1299717Y1024136D03*
X1297852Y1014475D03*
X1295815Y1124943D03*
X1295893Y1122182D03*
X1310853Y37543D03*
X1314887Y45448D03*
X1318859D03*
X1311904Y100625D03*
X1320566Y103621D03*
X1304854Y106186D03*
X1316277Y112083D03*
X1307666Y118335D03*
Y132509D03*
Y121735D03*
Y135909D03*
X1305015Y168697D03*
X1319912Y183834D03*
X1314627Y171523D03*
X1320085Y172665D03*
X1320022Y178560D03*
X1306103Y191941D03*
X1319432Y190185D03*
X1314157Y192490D03*
X1320202Y200864D03*
X1310115Y192300D03*
X1308112Y206767D03*
X1313112D03*
X1310612D03*
X1320225Y207037D03*
X1320291Y212455D03*
X1313242Y221708D03*
X1310742D03*
X1309357Y231021D03*
Y228221D03*
X1317592Y221642D03*
X1308242Y221708D03*
X1307657Y224421D03*
X1309908Y236189D03*
X1314908D03*
X1312408D03*
X1312349Y248765D03*
X1309849D03*
X1314849D03*
X1306800Y266114D03*
X1310046Y268195D03*
X1312546D03*
X1315346D03*
X1319006Y265897D03*
X1312546Y270695D03*
X1310046D03*
X1315346D03*
X1318362Y310562D03*
X1305928Y318250D03*
X1308428D03*
X1315256Y336510D03*
X1313103Y339606D03*
X1312240Y334681D03*
X1315397Y333709D03*
X1308012Y348109D03*
X1305910Y377581D03*
X1310172Y367956D03*
X1308410Y379591D03*
X1311283Y370801D03*
X1308826Y389402D03*
X1306113Y383817D03*
X1312626Y387702D03*
X1315426D03*
X1306113Y386317D03*
Y388817D03*
X1309750Y438293D03*
Y441093D03*
Y443893D03*
X1311488Y471560D03*
X1307819Y474382D03*
X1307835Y470382D03*
X1319474Y467560D03*
X1319974Y475560D03*
X1311488D03*
X1318160Y520053D03*
X1317945Y523058D03*
X1319000Y562500D03*
Y558500D03*
Y586500D03*
Y574500D03*
Y578500D03*
Y605000D03*
Y590500D03*
X1319323Y598454D03*
X1319000Y621000D03*
Y609000D03*
Y633000D03*
Y625000D03*
Y637000D03*
Y653500D03*
Y649500D03*
Y641000D03*
Y669500D03*
Y665500D03*
Y681500D03*
Y677500D03*
X1313979Y677726D03*
X1319000Y685500D03*
Y696500D03*
Y700500D03*
Y712500D03*
Y716500D03*
Y724500D03*
Y728500D03*
Y732500D03*
X1321000Y796000D03*
X1313000D03*
X1317000Y799000D03*
Y788000D03*
X1313000D03*
X1315000Y811620D03*
X1319000D03*
X1317000Y804000D03*
X1313000D03*
X1321000D03*
X1310715Y820491D03*
Y822991D03*
Y817991D03*
X1310687Y830206D03*
Y832706D03*
Y827706D03*
X1310971Y842319D03*
X1305786Y867704D03*
X1310994Y866859D03*
X1309753Y877589D03*
X1305740Y877534D03*
X1310535Y870775D03*
X1308220Y889253D03*
X1311061Y889361D03*
X1314500Y911500D03*
X1319500Y901500D03*
X1314500Y905000D03*
X1305356Y902597D03*
X1319500Y905000D03*
X1309103Y917000D03*
X1313867Y925605D03*
X1311325Y928918D03*
X1319554Y925585D03*
X1309103Y936559D03*
X1306500Y936500D03*
X1315779Y943743D03*
X1313152Y936605D03*
X1312575Y943974D03*
X1321256Y943815D03*
X1311000Y961500D03*
X1307000Y960500D03*
X1315441Y960000D03*
X1307000Y970000D03*
X1311000Y970124D03*
X1307707Y979870D03*
X1317254Y990777D03*
X1317053Y988111D03*
X1319874Y989856D03*
X1307561Y986951D03*
X1315606Y1042825D03*
X1315756Y1039344D03*
X1312873Y1036543D03*
X1306385Y1036646D03*
X1319221Y1058097D03*
Y1060697D03*
X1316869Y1107997D03*
X1319069Y1112397D03*
X1318969Y1109397D03*
X1316869Y1113797D03*
Y1110897D03*
X1317437Y1160834D03*
X1318178Y1192621D03*
Y1190121D03*
X1319237Y1221428D03*
X1311237D03*
X1315237D03*
X1311237Y1233428D03*
Y1229428D03*
Y1225428D03*
X1315237Y1237428D03*
Y1233428D03*
Y1229428D03*
Y1225428D03*
X1319237Y1237428D03*
Y1233428D03*
Y1229428D03*
Y1225428D03*
X1315237Y1241428D03*
X1319237D03*
X1308107Y1283395D03*
X1310773Y1282411D03*
X1303900Y1288000D03*
X1318287Y1295381D03*
Y1291381D03*
X1324120Y22742D03*
X1331073Y33400D03*
X1328003Y32403D03*
X1328318Y27333D03*
X1336623Y30483D03*
X1322853Y37530D03*
X1328799Y168665D03*
Y176665D03*
X1320898Y186629D03*
X1328799Y192665D03*
Y196665D03*
X1328912Y186778D03*
X1328831Y204864D03*
Y208864D03*
X1324472Y219379D03*
X1325100Y228631D03*
X1321506Y265897D03*
X1334110Y310562D03*
X1321762D03*
X1329636Y307562D03*
X1326236D03*
X1332563Y326356D03*
X1325573Y326719D03*
X1332359Y322685D03*
X1326489Y356945D03*
X1331005Y356670D03*
X1331922Y359836D03*
X1325007Y370951D03*
X1334109Y373401D03*
X1334285Y386567D03*
X1331606D03*
X1328896D03*
X1320594Y387151D03*
Y382151D03*
Y384651D03*
X1329097Y435321D03*
Y438121D03*
X1326297Y435321D03*
Y438121D03*
X1329097Y440921D03*
X1326297D03*
X1329097Y443721D03*
X1326297D03*
X1335440Y452799D03*
X1329083Y448931D03*
X1329606Y459170D03*
X1332974Y474513D03*
X1321450Y520268D03*
X1321164Y523130D03*
X1326993Y556788D03*
X1331096Y549931D03*
X1327043Y573346D03*
X1327000Y562500D03*
X1326946Y567906D03*
X1338000Y562500D03*
X1327000Y578500D03*
Y583826D03*
X1335000Y594500D03*
X1327000Y605000D03*
Y594500D03*
Y609000D03*
X1333224Y615484D03*
X1327000Y613000D03*
Y621000D03*
X1335532Y622260D03*
X1338000Y609000D03*
X1327000Y629000D03*
X1327003Y623940D03*
X1335000Y641000D03*
X1338000Y653500D03*
X1327000Y641000D03*
X1327011Y646064D03*
X1327000Y657500D03*
X1335000Y685500D03*
X1327000D03*
Y695500D03*
Y700500D03*
X1338000D03*
X1327000Y711500D03*
Y716500D03*
X1335000Y732500D03*
X1327000D03*
X1330295Y746328D03*
X1326970Y736464D03*
X1336661Y753675D03*
Y745675D03*
Y737675D03*
X1330295Y751328D03*
X1330086Y763758D03*
X1330324Y779030D03*
X1336746Y781675D03*
X1329000Y796000D03*
X1325000Y799000D03*
X1337000Y796000D03*
X1333000Y799000D03*
Y788000D03*
X1329000D03*
X1321000D03*
X1325000D03*
X1331000Y811620D03*
X1327000D03*
X1329000Y804000D03*
X1325000D03*
X1333000D03*
X1323000Y811620D03*
X1335000D03*
X1335803Y826500D03*
X1331056Y904557D03*
X1336096Y905042D03*
X1336000Y900500D03*
X1324000Y901000D03*
X1331078Y900500D03*
X1330500Y925500D03*
X1334500D03*
X1326500D03*
X1333425Y930925D03*
X1324000D03*
X1333132Y933781D03*
X1336000Y943500D03*
X1329199Y933825D03*
X1323000Y934075D03*
X1326500Y943500D03*
X1335343Y961727D03*
X1321028Y961749D03*
X1332500Y961500D03*
X1325550Y960445D03*
X1332000Y969500D03*
X1327000D03*
X1329503Y991088D03*
X1334909Y990340D03*
X1332404Y988215D03*
X1329834Y988132D03*
X1324735Y989966D03*
X1327267Y988271D03*
X1322427Y988221D03*
X1333974Y1033483D03*
X1320549Y1037876D03*
X1322773Y1040599D03*
X1329221Y1058097D03*
X1321721D03*
X1324221D03*
X1326721D03*
Y1060697D03*
X1329221D03*
X1321721D03*
X1324221D03*
X1326163Y1082501D03*
X1326189Y1085205D03*
X1329163Y1082501D03*
X1329189Y1085205D03*
X1326189Y1088205D03*
X1326471Y1091227D03*
X1329189Y1088205D03*
X1323189Y1085205D03*
Y1087705D03*
X1323163Y1082501D03*
X1323021Y1090956D03*
X1337514Y1104335D03*
X1334956Y1105552D03*
X1321069Y1107997D03*
X1323021Y1093956D03*
X1331162Y1104792D03*
X1332669Y1106867D03*
X1321169Y1110597D03*
X1321954Y1113648D03*
X1326254D03*
X1328754D03*
X1323405Y1118801D03*
Y1116101D03*
X1325635Y1172384D03*
Y1162384D03*
Y1164884D03*
Y1167384D03*
Y1169884D03*
X1323135Y1172384D03*
Y1162384D03*
Y1164884D03*
Y1167384D03*
Y1169884D03*
X1334793Y1179421D03*
Y1181921D03*
Y1184421D03*
Y1186921D03*
X1320493Y1186709D03*
Y1184209D03*
Y1181709D03*
Y1179209D03*
X1325635Y1174884D03*
X1323135D03*
X1331643Y1192621D03*
Y1190121D03*
X1327237Y1221428D03*
X1331237D03*
X1335237D03*
X1323237D03*
X1327237Y1237428D03*
Y1233428D03*
Y1229428D03*
Y1225428D03*
X1331237Y1237428D03*
Y1233428D03*
Y1229428D03*
Y1225428D03*
X1335237Y1237428D03*
Y1233428D03*
Y1229428D03*
Y1225428D03*
X1323237Y1237428D03*
Y1233428D03*
Y1229428D03*
Y1225428D03*
X1335237Y1241428D03*
X1323237Y1245428D03*
Y1241428D03*
X1327237Y1245428D03*
Y1241428D03*
X1331237Y1245428D03*
Y1241428D03*
X1335237Y1245428D03*
X1333876Y1257160D03*
Y1260160D03*
X1336646Y22627D03*
X1336551Y26534D03*
X1340320Y147540D03*
X1344092Y141247D03*
X1351559Y143740D03*
X1348939Y148277D03*
X1348419Y265222D03*
X1340104Y279117D03*
X1344007Y279054D03*
X1337510Y310562D03*
X1347990Y322539D03*
X1341169Y325926D03*
X1346009Y336080D03*
X1346093Y340805D03*
X1349636Y340862D03*
X1346065Y347106D03*
X1338471Y356959D03*
X1337509Y373401D03*
X1349763Y371908D03*
X1342810Y408104D03*
X1345610D03*
X1348410D03*
X1336388Y424939D03*
X1342527Y420375D03*
X1345327D03*
X1348127D03*
X1336388Y427439D03*
X1346443Y431112D03*
X1352008Y435101D03*
X1352271Y442114D03*
X1346613Y440101D03*
X1352251Y447121D03*
X1346248Y452718D03*
X1340820Y452987D03*
X1352259Y452601D03*
X1347846Y461607D03*
X1339846D03*
X1339049Y471334D03*
X1343846Y461607D03*
X1346738Y564492D03*
X1339289Y568461D03*
X1342053Y579339D03*
X1346533Y576780D03*
X1340522Y586133D03*
X1343000Y590458D03*
X1346533Y581898D03*
X1344129Y606914D03*
X1344433Y601201D03*
X1339289Y614961D03*
X1344680Y619085D03*
X1346738Y611192D03*
X1346533Y628398D03*
X1346378Y623734D03*
X1342053Y625839D03*
X1340522Y632633D03*
X1343000Y636958D03*
X1346738Y655492D03*
X1339289Y659461D03*
X1346533Y667780D03*
X1342053Y670339D03*
X1346533Y672898D03*
X1340522Y677133D03*
X1343000Y681458D03*
X1350929Y687043D03*
X1340299Y686243D03*
X1346738Y702492D03*
X1346533Y719898D03*
X1339289Y706461D03*
X1342053Y717339D03*
X1346533Y714780D03*
X1340522Y724133D03*
X1343000Y728458D03*
X1344768Y737675D03*
Y741675D03*
Y745675D03*
Y749675D03*
Y753675D03*
Y761675D03*
Y757675D03*
X1336450Y765675D03*
X1344768Y773675D03*
Y781350D03*
X1345226Y777675D03*
X1341000Y799000D03*
X1345000Y796000D03*
X1341000Y788000D03*
X1345000D03*
X1337000D03*
X1348917Y796000D03*
Y788000D03*
X1352817Y796000D03*
X1349000Y804000D03*
X1351000Y811620D03*
X1347000D03*
X1343000D03*
X1337000Y804000D03*
X1345000D03*
X1341000D03*
X1349976Y829000D03*
X1350000Y825500D03*
X1340000Y900000D03*
X1351500Y903000D03*
Y906500D03*
X1340000Y906000D03*
Y903000D03*
X1351511Y900000D03*
X1350500Y925500D03*
X1338500D03*
X1342500D03*
X1346500D03*
X1353948Y943603D03*
X1345948D03*
X1349848Y936755D03*
X1338500Y930500D03*
X1350500D03*
X1342500D03*
X1346500D03*
X1337514Y988259D03*
X1343465Y1026123D03*
X1340665D03*
X1343465Y1028923D03*
X1340665D03*
X1347552Y1091816D03*
Y1089316D03*
X1345052Y1081816D03*
Y1084316D03*
Y1086816D03*
X1347552D03*
Y1084316D03*
X1350418Y1090288D03*
X1347552Y1081816D03*
X1344241Y1106298D03*
X1348997Y1107997D03*
X1350418Y1093088D03*
X1339234Y1101917D03*
X1339169Y1106897D03*
X1341984Y1110092D03*
X1345650Y1115896D03*
X1348997Y1113797D03*
Y1110897D03*
X1351197Y1112397D03*
X1351097Y1109397D03*
X1345650Y1118396D03*
X1347300Y1128332D03*
X1343725Y1128738D03*
X1343905Y1162384D03*
Y1164884D03*
Y1167384D03*
Y1169884D03*
Y1172384D03*
X1341405D03*
Y1169884D03*
Y1167384D03*
Y1164884D03*
Y1162384D03*
X1350963Y1172384D03*
Y1169884D03*
Y1167384D03*
Y1164884D03*
Y1162384D03*
X1351149Y1158200D03*
X1347423Y1186709D03*
Y1184209D03*
Y1181709D03*
Y1179209D03*
X1343905Y1174884D03*
X1341405D03*
X1350963D03*
X1337108Y1192621D03*
Y1190121D03*
X1345108D03*
Y1192621D03*
X1347237Y1221428D03*
X1343237D03*
X1339237D03*
X1347237Y1237428D03*
Y1233428D03*
Y1229428D03*
X1343237D03*
Y1233428D03*
Y1237428D03*
X1339237D03*
Y1233428D03*
Y1229428D03*
Y1225428D03*
X1347237Y1245428D03*
Y1241428D03*
X1343237D03*
Y1245428D03*
X1339237D03*
Y1241428D03*
X1339876Y1257160D03*
X1342876D03*
X1345876Y1260160D03*
Y1257160D03*
X1348876Y1260160D03*
Y1257160D03*
X1351876Y1260160D03*
Y1257160D03*
X1336876Y1260160D03*
Y1257160D03*
X1342876Y1260160D03*
X1339876D03*
X1360122Y141247D03*
X1364609Y143518D03*
X1363709Y152373D03*
X1366859Y152562D03*
X1363535Y327877D03*
X1366535Y335751D03*
Y339151D03*
X1363535Y331277D03*
Y343625D03*
X1366535Y354899D03*
Y351499D03*
X1363535Y347025D03*
X1360719Y424601D03*
X1352817Y788000D03*
X1367000Y811620D03*
X1365000Y804000D03*
X1355000Y811620D03*
X1363000D03*
X1353000Y804000D03*
X1359000Y811620D03*
X1357000Y804000D03*
X1361000D03*
X1354185Y906498D03*
X1367000Y904500D03*
X1363000Y900500D03*
X1367000D03*
X1354500Y925500D03*
X1366500D03*
X1358500D03*
X1362500D03*
X1365948Y939475D03*
X1357948Y938842D03*
X1361948Y943603D03*
X1369948D03*
X1362500Y930500D03*
X1366500D03*
X1354500D03*
X1358500D03*
X1364765Y1004766D03*
X1367444Y1003763D03*
X1357765Y1019766D03*
X1361265D03*
X1365049Y1028416D03*
X1365314Y1021793D03*
X1357265Y1026266D03*
Y1034266D03*
X1366265Y1039880D03*
X1369642Y1104335D03*
X1367084Y1105552D03*
X1353197Y1107997D03*
X1363290Y1104792D03*
X1364797Y1106867D03*
X1353297Y1110597D03*
X1354082Y1113648D03*
X1355533Y1116101D03*
Y1118801D03*
X1360882Y1113648D03*
X1358382D03*
X1353463Y1172384D03*
Y1169884D03*
Y1167384D03*
Y1164884D03*
Y1162384D03*
X1361723Y1179421D03*
Y1181921D03*
Y1184421D03*
Y1186921D03*
X1353463Y1174884D03*
X1364038Y1190121D03*
Y1192621D03*
X1363876Y1260160D03*
Y1257160D03*
X1354876Y1260160D03*
X1357876D03*
X1360876D03*
Y1257160D03*
X1357876D03*
X1354876D03*
X1366876Y1260160D03*
Y1257160D03*
X1376262Y116594D03*
X1382205Y110784D03*
X1387205D03*
X1376262Y119594D03*
X1386784Y124663D03*
X1376696Y124283D03*
X1381762Y124879D03*
X1375103Y161306D03*
X1372354Y157370D03*
X1384319Y218085D03*
X1381519D03*
X1386846Y249108D03*
X1378227Y248371D03*
X1384265Y320871D03*
Y325371D03*
X1383551Y337808D03*
X1384265Y329871D03*
X1383634Y342766D03*
X1384265Y334371D03*
X1375073Y356871D03*
Y361371D03*
X1383505Y349437D03*
X1384265Y352371D03*
X1372232Y361298D03*
X1383963Y366675D03*
X1377024Y397713D03*
X1375108Y420838D03*
X1375171Y424741D03*
X1375400Y435192D03*
X1375360Y432234D03*
X1383343Y508228D03*
X1383907Y516591D03*
X1383556Y554388D03*
X1378415Y558795D03*
X1383608Y571927D03*
X1378415Y563984D03*
Y569776D03*
X1378957Y584457D03*
X1383000Y584500D03*
X1382997Y581317D03*
X1383425Y590425D03*
X1378415Y605295D03*
X1383608Y618427D03*
X1378415Y610484D03*
Y616276D03*
X1383425Y636925D03*
X1378957Y630957D03*
X1384657Y631620D03*
X1378957Y627988D03*
X1378415Y649795D03*
Y654984D03*
Y660776D03*
X1386289Y672488D03*
X1383425Y681425D03*
X1378957Y675457D03*
X1383000Y675500D03*
X1378415Y696795D03*
Y701984D03*
X1378957Y719488D03*
X1378415Y707776D03*
X1383425Y728425D03*
X1378957Y722457D03*
X1385290Y722400D03*
X1371000Y811620D03*
X1381000Y804000D03*
X1373000D03*
X1369000D03*
X1385360Y811757D03*
X1381428Y812287D03*
X1375193Y811724D03*
X1376708Y901000D03*
X1378500Y925500D03*
X1374369Y925499D03*
X1370500Y925500D03*
X1382500D03*
X1382775Y930281D03*
X1373948Y940103D03*
X1374500Y930500D03*
X1370500D03*
X1378500D03*
X1381519Y996280D03*
X1383162Y991829D03*
X1373534Y1012325D03*
Y1004680D03*
X1378938Y1000586D03*
X1374034Y1015825D03*
X1374059Y1018860D03*
X1376359Y1016825D03*
X1378559Y1038534D03*
X1384784Y1033783D03*
X1385929Y1038665D03*
X1373874Y1032266D03*
Y1035716D03*
X1385152Y1046591D03*
X1377087Y1106365D03*
X1371362Y1101917D03*
X1371297Y1106897D03*
X1382456Y1107997D03*
X1374112Y1110092D03*
X1377778Y1115896D03*
X1384656Y1112397D03*
X1382456Y1110897D03*
Y1113797D03*
X1384556Y1109397D03*
X1377778Y1118396D03*
X1369233Y1169884D03*
Y1172384D03*
X1371733D03*
Y1169884D03*
Y1167384D03*
Y1164884D03*
Y1162384D03*
X1369233D03*
Y1164884D03*
Y1167384D03*
X1376861Y1160834D03*
X1383024D03*
X1369233Y1174884D03*
X1371733D03*
X1375459Y1197471D03*
Y1193471D03*
X1379959Y1197471D03*
Y1193471D03*
X1397848Y97667D03*
X1388231Y116594D03*
X1393504Y102495D03*
X1388231Y119594D03*
X1391765Y125107D03*
X1393238Y142862D03*
X1400379Y143762D03*
X1394279Y148717D03*
X1388128Y138838D03*
X1399327Y195176D03*
X1396827D03*
X1400845Y199248D03*
Y201748D03*
X1398681Y206806D03*
X1401181D03*
X1399408Y210509D03*
X1396908D03*
X1390832Y216970D03*
Y219470D03*
X1390898Y226320D03*
X1390832Y221970D03*
X1388119Y216385D03*
X1402855Y227824D03*
X1398600Y230556D03*
X1393859Y228646D03*
X1397585Y242078D03*
X1392816Y232971D03*
X1389466Y244571D03*
X1396809Y256394D03*
X1395726Y320529D03*
X1395568Y325529D03*
X1395726Y330529D03*
X1395736Y335529D03*
X1395726Y340529D03*
Y345529D03*
Y360529D03*
Y350529D03*
Y355529D03*
X1391896Y365529D03*
X1399884Y367165D03*
X1387847Y366710D03*
X1400231Y390256D03*
X1396528Y397454D03*
X1399571Y397418D03*
X1393575Y397310D03*
X1390553Y397436D03*
X1391623Y409900D03*
X1387125Y417312D03*
X1393177Y424804D03*
X1389557Y424678D03*
X1389431Y421593D03*
X1390271Y417578D03*
X1393208Y428109D03*
X1393336Y431100D03*
X1403085Y460565D03*
X1393944Y507856D03*
X1394044Y510990D03*
X1397079Y527726D03*
Y548726D03*
Y544726D03*
X1395605Y556217D03*
X1390741Y561000D03*
Y569000D03*
Y565000D03*
X1391087Y581317D03*
X1398946Y621311D03*
X1390741Y611500D03*
Y607500D03*
Y615500D03*
X1391586Y623692D03*
X1398946Y629311D03*
Y625311D03*
X1397000Y652000D03*
Y656000D03*
Y660000D03*
Y699000D03*
Y707000D03*
Y703000D03*
X1391040Y812027D03*
X1386335Y803704D03*
X1390537Y803679D03*
X1394537Y803653D03*
X1398530Y811717D03*
X1402417Y811692D03*
X1400069Y827515D03*
X1401300Y820485D03*
X1395955Y832697D03*
X1402000Y840000D03*
Y848000D03*
X1399872Y845109D03*
X1402000Y864000D03*
X1391316Y857849D03*
X1388488Y857822D03*
X1402000Y876000D03*
X1390182Y873460D03*
X1387582Y873487D03*
X1402000Y884000D03*
Y892000D03*
X1388479Y892923D03*
X1385979D03*
X1390979D03*
X1402000Y900000D03*
X1387520Y905307D03*
X1387753Y912629D03*
X1394891Y914783D03*
X1402187Y908270D03*
X1387504Y899931D03*
X1390541Y900086D03*
X1388980Y921075D03*
X1401000Y925789D03*
X1396869Y958707D03*
X1402064Y965913D03*
X1389192Y992568D03*
X1398854Y987277D03*
X1394885Y999941D03*
X1392031Y1004375D03*
X1385732Y1029482D03*
X1389762Y1043055D03*
X1387813Y1030952D03*
X1399807Y1036155D03*
X1399852Y1039779D03*
X1388523Y1090090D03*
X1392691Y1089224D03*
X1392086Y1092743D03*
X1392691Y1086724D03*
Y1084224D03*
Y1081724D03*
X1390191D03*
Y1084224D03*
Y1086724D03*
X1403101Y1104335D03*
X1400543Y1105552D03*
X1396749Y1104792D03*
X1388451Y1093048D03*
X1386656Y1107997D03*
X1398256Y1106867D03*
X1386756Y1110597D03*
X1394341Y1113648D03*
X1388992Y1118801D03*
Y1116101D03*
X1387541Y1113648D03*
X1391841D03*
X1388722Y1162384D03*
Y1164884D03*
Y1167384D03*
Y1169884D03*
Y1172384D03*
X1391222Y1162384D03*
Y1164884D03*
Y1167384D03*
Y1169884D03*
Y1172384D03*
X1388722Y1174884D03*
X1391222D03*
X1393695Y1186709D03*
Y1184209D03*
Y1181709D03*
Y1179209D03*
X1391380Y1190121D03*
Y1192621D03*
X1385821Y1260160D03*
X1391821Y1257160D03*
X1394821D03*
X1385821D03*
X1388821D03*
X1397821Y1260160D03*
Y1257160D03*
X1400821Y1260160D03*
Y1257160D03*
X1388821Y1260160D03*
X1394821D03*
X1391821D03*
X1385052Y1303139D03*
X1389052D03*
X1406308Y103411D03*
X1406702Y97667D03*
X1417498Y90650D03*
X1417248Y95236D03*
X1402098Y95111D03*
X1406467Y106561D03*
X1403845Y199248D03*
X1401827Y195176D03*
X1404327D03*
X1403845Y202048D03*
X1407445Y230117D03*
X1403461Y238714D03*
X1402942Y246874D03*
X1405162Y244297D03*
X1402921Y322403D03*
X1409830Y347649D03*
X1404690Y362209D03*
X1416912Y386903D03*
X1408854Y381207D03*
X1416470Y381397D03*
X1402968Y390177D03*
X1414369Y398056D03*
X1408254Y398041D03*
X1407844Y411033D03*
X1415610Y417644D03*
X1415674Y421278D03*
X1417856Y448419D03*
X1414903Y469905D03*
X1410903Y470419D03*
Y461919D03*
X1418903Y461419D03*
X1411269Y481467D03*
X1415623Y492268D03*
X1415823Y482165D03*
X1416061Y504825D03*
X1413561D03*
X1411061D03*
X1415064Y500202D03*
X1406910Y495982D03*
X1416413Y495649D03*
X1406910Y491982D03*
X1416002Y517401D03*
X1413502D03*
X1411002D03*
X1416553Y522569D03*
Y525369D03*
X1415168Y531882D03*
X1412668D03*
X1409618Y531948D03*
X1401438Y534211D03*
X1405992Y534909D03*
X1405619Y541135D03*
X1405685Y546553D03*
X1405708Y552726D03*
X1415103Y555194D03*
Y563194D03*
Y571194D03*
X1416660Y581222D03*
Y591215D03*
X1401383Y611071D03*
X1416832Y610562D03*
Y607762D03*
X1411622Y610548D03*
X1407566Y622285D03*
X1407754Y616905D03*
X1418439Y633736D03*
X1407952Y633724D03*
X1413432Y633716D03*
X1407835Y627713D03*
X1405229Y652028D03*
X1405000Y660000D03*
X1410000Y685000D03*
Y681000D03*
X1404500Y675000D03*
X1410000Y701000D03*
Y697000D03*
X1418000Y696000D03*
Y701000D03*
X1410000Y709000D03*
Y713000D03*
X1405000Y707000D03*
Y703000D03*
X1418000Y717000D03*
X1410000D03*
X1404500Y722000D03*
X1410000Y729000D03*
Y725000D03*
X1418000Y724000D03*
Y729000D03*
X1404249Y735858D03*
X1410000Y745000D03*
Y741000D03*
X1418000Y740000D03*
Y745000D03*
X1407482Y750853D03*
X1410000Y757000D03*
Y753000D03*
Y761000D03*
X1418000D03*
X1406867Y783273D03*
X1409115Y773520D03*
X1414597Y792375D03*
X1406483Y811717D03*
X1413500Y832000D03*
Y828000D03*
X1413449Y823934D03*
X1405402Y819917D03*
X1405500Y844000D03*
Y836000D03*
X1413500Y848000D03*
Y840000D03*
Y836000D03*
Y844000D03*
X1405500Y860000D03*
X1413500Y864000D03*
Y860000D03*
Y856000D03*
Y852000D03*
X1405500Y880000D03*
Y868000D03*
X1413500Y876000D03*
X1417797Y879501D03*
X1413500Y872000D03*
Y868000D03*
X1405500Y888000D03*
Y896000D03*
X1417081D03*
X1413500Y892000D03*
Y884000D03*
Y888000D03*
X1413733Y911137D03*
X1412376Y907848D03*
X1414876D03*
X1417376D03*
X1409876D03*
X1405500Y904000D03*
X1404760Y915186D03*
X1413500Y904000D03*
Y900000D03*
X1417284Y911009D03*
X1416802Y936845D03*
X1416244Y942285D03*
X1419337D03*
X1405214Y965074D03*
X1419446Y977192D03*
X1416618Y992307D03*
X1401265Y989465D03*
X1407265D03*
X1414143Y985486D03*
X1412698Y997590D03*
X1412609Y1008766D03*
X1412759Y1016266D03*
X1402215Y1020440D03*
X1414851Y1058097D03*
X1412351D03*
X1407351D03*
X1409851D03*
X1417351D03*
X1414851Y1060697D03*
X1412351D03*
X1407351D03*
X1409851D03*
X1417351D03*
X1405677Y1086796D03*
X1408177D03*
X1410677D03*
X1413177D03*
X1415677D03*
Y1084296D03*
X1413177D03*
X1410677D03*
X1408177D03*
X1405677D03*
X1416005Y1090288D03*
X1410546Y1106298D03*
X1404821Y1101917D03*
X1404756Y1106897D03*
X1416005Y1093088D03*
X1414584Y1107997D03*
X1411237Y1115896D03*
X1407571Y1110092D03*
X1414584Y1113797D03*
X1416784Y1112397D03*
X1414584Y1110897D03*
X1416684Y1109397D03*
X1411237Y1118396D03*
X1409425Y1129238D03*
X1413177Y1128894D03*
X1409492Y1167384D03*
Y1169884D03*
Y1172384D03*
X1406992D03*
Y1169884D03*
X1416550Y1162384D03*
Y1164884D03*
Y1167384D03*
Y1169884D03*
Y1172384D03*
X1406992Y1167384D03*
Y1164884D03*
Y1162384D03*
X1409492D03*
Y1164884D03*
X1416736Y1158200D03*
X1416550Y1174884D03*
X1409492D03*
X1406992D03*
X1407995Y1179421D03*
Y1181921D03*
Y1184421D03*
Y1186921D03*
X1410310Y1192621D03*
Y1190121D03*
X1404845D03*
Y1192621D03*
X1408736Y1222194D03*
X1412736D03*
X1416736D03*
X1408736Y1238194D03*
Y1234194D03*
Y1230194D03*
Y1226194D03*
X1412736Y1238194D03*
Y1234194D03*
Y1230194D03*
Y1226194D03*
X1416736Y1238194D03*
Y1234194D03*
Y1230194D03*
Y1226194D03*
X1412736Y1246194D03*
Y1242194D03*
X1416736Y1246194D03*
Y1242194D03*
X1408736D03*
Y1246194D03*
X1409821Y1260160D03*
X1412821D03*
Y1257160D03*
X1409821D03*
X1406821D03*
X1403821D03*
X1415821Y1260160D03*
Y1257160D03*
X1403821Y1260160D03*
X1406821D03*
X1417711Y1301729D03*
X1410817Y1305417D03*
X1407825Y1426975D03*
X1408536Y1536570D03*
X1407747Y1549054D03*
X1408044Y1559306D03*
X1407255Y1571732D03*
X1422810Y90615D03*
X1427131Y99961D03*
X1427181Y95236D03*
X1425993Y212978D03*
Y207978D03*
Y210478D03*
Y215478D03*
X1429322Y264180D03*
X1431822D03*
X1429247Y258880D03*
X1434166Y325361D03*
X1434164Y339232D03*
X1434038Y334114D03*
X1435818Y352361D03*
X1421005Y407616D03*
X1417903Y439919D03*
X1434997Y442603D03*
X1427117Y443071D03*
X1423427Y456839D03*
X1425927D03*
X1423427Y454339D03*
X1425927D03*
X1432414Y459371D03*
X1423427Y459339D03*
X1425927D03*
X1418903Y469905D03*
X1431484Y470045D03*
X1427484Y462004D03*
X1422499Y485138D03*
X1419650Y485128D03*
X1426384Y478625D03*
X1428084Y482425D03*
X1427499Y485138D03*
X1424999D03*
X1426384Y476125D03*
X1418253Y529169D03*
X1417668Y531882D03*
X1424129Y537658D03*
X1427832Y539731D03*
X1424129Y540458D03*
X1432590Y544895D03*
X1435390D03*
X1427832Y542231D03*
X1432890Y541895D03*
X1417903Y555194D03*
Y563194D03*
Y571194D03*
X1422260Y581222D03*
X1419460D03*
X1435119Y590801D03*
X1422260Y591215D03*
X1419460D03*
X1431000Y591000D03*
X1434944Y597130D03*
X1433114Y620653D03*
Y617853D03*
X1419632Y607762D03*
X1422432D03*
X1425232Y610562D03*
Y607762D03*
X1422432Y610562D03*
X1419632D03*
X1430944Y605443D03*
X1420452Y628078D03*
X1430175Y627852D03*
X1425452Y633473D03*
X1430481Y658153D03*
X1433529Y660564D03*
X1426615Y674112D03*
X1429000Y685000D03*
X1418000D03*
Y681000D03*
X1425909Y691120D03*
X1433464Y692658D03*
X1418000Y689000D03*
X1433053Y701839D03*
X1426000Y717000D03*
X1418000Y705000D03*
X1431522Y708633D03*
X1434000Y712958D03*
X1430289Y734961D03*
X1418000Y733000D03*
X1417969Y720894D03*
X1429000Y729000D03*
X1434000Y751958D03*
X1433153Y745839D03*
X1427000Y766500D03*
X1426000Y761000D03*
X1435000Y765500D03*
X1434000Y756958D03*
X1418023Y765343D03*
X1427000Y781834D03*
Y770500D03*
X1435000D03*
X1427000Y794500D03*
X1435000Y802500D03*
X1427000Y810500D03*
Y814500D03*
X1435000D03*
Y809500D03*
X1427000Y802500D03*
Y830500D03*
Y826500D03*
X1434975Y830500D03*
X1435000Y825500D03*
X1427000Y842500D03*
Y838500D03*
X1435000Y846500D03*
X1427000D03*
X1435043Y874694D03*
X1435082Y869475D03*
X1423190Y905295D03*
X1429059Y908579D03*
X1426085Y910281D03*
X1429907Y936998D03*
X1424897Y936777D03*
X1435516Y936000D03*
X1420699Y958452D03*
X1430839Y965546D03*
X1420740Y1008766D03*
X1428740Y1000766D03*
X1420740Y996766D03*
X1428864D03*
X1420740Y1012266D03*
X1428740Y1016266D03*
X1428823Y1020266D03*
X1435229Y1104335D03*
X1432671Y1105552D03*
X1428877Y1104792D03*
X1418784Y1107997D03*
X1430384Y1106867D03*
X1418884Y1110597D03*
X1421120Y1116101D03*
Y1118801D03*
X1426469Y1113648D03*
X1423969D03*
X1419669D03*
X1419050Y1162384D03*
Y1164884D03*
Y1167384D03*
Y1169884D03*
Y1172384D03*
Y1174884D03*
X1420625Y1186709D03*
Y1184209D03*
Y1181709D03*
Y1179209D03*
X1418310Y1192621D03*
Y1190121D03*
X1420736Y1222194D03*
X1424736D03*
X1428736D03*
X1432736D03*
X1420736Y1238194D03*
Y1234194D03*
Y1230194D03*
Y1226194D03*
X1424736Y1238194D03*
Y1234194D03*
Y1230194D03*
Y1226194D03*
X1428736Y1238194D03*
Y1234194D03*
Y1230194D03*
Y1226194D03*
X1432736Y1234194D03*
Y1230194D03*
Y1226194D03*
X1420736Y1246194D03*
Y1242194D03*
X1424736Y1246194D03*
Y1242194D03*
X1428736Y1246194D03*
Y1242194D03*
X1421821Y1257160D03*
X1418821D03*
Y1260160D03*
X1421821D03*
X1431080Y1301702D03*
X1421238Y1301712D03*
X1428009Y1301760D03*
X1424732Y1301603D03*
X1432258Y1414600D03*
X1430374Y1492474D03*
X1420877Y1494706D03*
X1421964Y1502813D03*
X1423930Y1520364D03*
X1429587Y1527450D03*
X1433405Y1546001D03*
X1432913Y1568679D03*
X1449685Y34228D03*
X1436045Y77393D03*
Y74793D03*
Y85193D03*
Y82593D03*
Y79993D03*
X1444370Y98551D03*
X1436089Y92874D03*
X1447265Y111223D03*
Y114623D03*
X1447920Y103783D03*
X1438116Y107649D03*
Y104249D03*
X1447265Y125396D03*
Y128796D03*
X1442682Y147540D03*
X1446454Y141247D03*
X1451301Y148277D03*
X1435138Y162368D03*
X1437738D03*
X1444838Y162793D03*
Y165393D03*
Y170493D03*
Y167993D03*
X1451762Y177616D03*
X1449841Y181009D03*
X1447046Y181366D03*
X1443835Y181426D03*
X1444043Y184221D03*
X1446660Y184012D03*
X1448079Y211359D03*
Y213859D03*
X1436449Y213213D03*
Y210713D03*
X1440521Y211695D03*
X1443021D03*
X1440521Y208695D03*
X1443321D03*
X1436449Y208213D03*
Y215713D03*
X1451785Y265896D03*
X1446698Y265701D03*
X1441016Y267526D03*
Y270026D03*
X1443516D03*
X1438216D03*
X1443516Y267526D03*
X1438216D03*
X1448333Y281716D03*
X1449060Y329861D03*
X1448948Y326448D03*
X1449060Y320861D03*
X1438829Y329861D03*
X1437064Y320861D03*
X1448822Y345324D03*
X1448734Y332910D03*
X1448500Y340575D03*
X1439712Y336673D03*
X1440420Y346833D03*
X1449060Y356861D03*
X1441180Y354909D03*
X1448572Y349441D03*
X1449060Y352361D03*
X1447502Y360785D03*
X1434697Y347125D03*
X1439719Y350387D03*
X1443041Y363648D03*
X1434608Y362584D03*
X1438768Y371655D03*
X1442633Y371502D03*
X1445906Y366030D03*
X1440523Y382747D03*
X1435424Y430361D03*
X1440390Y456652D03*
X1442890D03*
Y459152D03*
Y461652D03*
X1440390Y459152D03*
Y461652D03*
X1436930Y461818D03*
X1433960Y491214D03*
X1449293Y491133D03*
X1442721Y495151D03*
X1437663Y492987D03*
X1442421Y498151D03*
X1433960Y493714D03*
X1437663Y495487D03*
X1445221Y498151D03*
X1449293Y493633D03*
Y496133D03*
Y498633D03*
X1445221Y495151D03*
X1439462Y537877D03*
X1449393Y553297D03*
Y555897D03*
X1446988Y548418D03*
X1439462Y540377D03*
X1435390Y541895D03*
X1444488Y548418D03*
X1439488D03*
X1441988D03*
X1439462Y542877D03*
Y545377D03*
X1449393Y558497D03*
Y566797D03*
Y563697D03*
Y561097D03*
X1443388Y570686D03*
X1446183Y570478D03*
X1435668Y582747D03*
X1446600Y576484D03*
X1446243Y573689D03*
X1443597Y573303D03*
X1449993Y578405D03*
X1438944Y597232D03*
X1443775Y596089D03*
X1448994Y596782D03*
X1440930Y613913D03*
Y616713D03*
Y619513D03*
X1434944Y605443D03*
X1438944Y605637D03*
X1437790Y625013D03*
X1435952Y642184D03*
X1446323Y673183D03*
X1437738Y686992D03*
X1448991Y694392D03*
X1451976Y693844D03*
X1437533Y704398D03*
Y699280D03*
X1438930Y716363D03*
X1446860Y730735D03*
X1446538Y719548D03*
X1437738Y730992D03*
X1446717Y735536D03*
X1437533Y743280D03*
Y748398D03*
X1447289Y776461D03*
X1446000Y770500D03*
X1451000Y793458D03*
Y798458D03*
X1450253Y787339D03*
X1443000Y802500D03*
X1447000Y810500D03*
Y818500D03*
X1435000D03*
X1448000Y834500D03*
X1443000Y846500D03*
X1435000Y834500D03*
X1449000Y844500D03*
X1435212Y854042D03*
X1448726Y864400D03*
X1439891Y873821D03*
X1445367Y891888D03*
X1441223Y891957D03*
X1435745Y901500D03*
X1443231Y899006D03*
X1439103Y898564D03*
X1447261Y898571D03*
X1446022Y927000D03*
X1448137Y949440D03*
X1439031Y957683D03*
X1441088Y976409D03*
X1433996Y981437D03*
X1440700Y981763D03*
X1435669Y1005366D03*
X1440869Y1010256D03*
X1435197Y1028372D03*
X1442674Y1106365D03*
X1436949Y1101917D03*
X1436884Y1106897D03*
X1439699Y1110092D03*
X1443365Y1115896D03*
Y1118396D03*
X1442448Y1160834D03*
X1434820Y1162384D03*
Y1164884D03*
Y1167384D03*
Y1169884D03*
Y1172384D03*
X1437320D03*
Y1169884D03*
Y1167384D03*
Y1164884D03*
Y1162384D03*
X1434925Y1179421D03*
Y1181921D03*
Y1184421D03*
Y1186921D03*
X1434820Y1174884D03*
X1437320D03*
X1437240Y1192621D03*
Y1190121D03*
X1436736Y1222194D03*
Y1226194D03*
X1443660Y1310698D03*
X1440260D03*
X1446817Y1335846D03*
X1441200Y1338700D03*
X1435900Y1340800D03*
X1439258Y1414600D03*
X1446135Y1530876D03*
X1443103Y1527201D03*
X1441145Y1540415D03*
X1440153Y1563093D03*
X1443769Y1562173D03*
X1452717Y34052D03*
X1457347Y31518D03*
X1457829Y26425D03*
X1455013Y43128D03*
X1460466Y76587D03*
Y72615D03*
X1461905Y100625D03*
X1454924Y97475D03*
X1454855Y106186D03*
X1457667Y118335D03*
Y121735D03*
Y132509D03*
Y135909D03*
X1462484Y141247D03*
X1466971Y143518D03*
X1453921Y143740D03*
X1466071Y152373D03*
X1455016Y168697D03*
X1452343Y172190D03*
X1464628Y171523D03*
X1456104Y191941D03*
X1464158Y192490D03*
X1458113Y206767D03*
X1463113D03*
X1460613D03*
X1451782Y213132D03*
X1463243Y221708D03*
X1460743D03*
X1458243D03*
X1457658Y224421D03*
X1459358Y231021D03*
Y228221D03*
X1451782Y215632D03*
X1459909Y236189D03*
X1464909D03*
X1462409D03*
X1459850Y248765D03*
X1464850D03*
X1462350D03*
X1452026Y256303D03*
X1456801Y266114D03*
X1460047Y270695D03*
Y268195D03*
X1462547Y270695D03*
Y268195D03*
X1465347Y270695D03*
Y268195D03*
X1454274Y281982D03*
X1459060Y320861D03*
Y325361D03*
Y329861D03*
Y338861D03*
Y343361D03*
Y334361D03*
Y347861D03*
Y352361D03*
X1459873Y391705D03*
X1463145Y391579D03*
X1458214Y406231D03*
X1464536Y433114D03*
X1458912Y581659D03*
X1455419Y578986D03*
X1454944Y596729D03*
X1453000Y614158D03*
Y616958D03*
Y619758D03*
X1450944Y605443D03*
X1458944D03*
X1461474Y655807D03*
X1455761Y683448D03*
X1468372Y673812D03*
X1460111Y683536D03*
X1451428Y673252D03*
X1460816Y727964D03*
X1455291Y759656D03*
X1455159Y763714D03*
X1454504Y777575D03*
X1454533Y784780D03*
X1454738Y772492D03*
X1454533Y789898D03*
X1453102Y821102D03*
X1454541Y831339D03*
X1453102Y826500D03*
X1452619Y836457D03*
X1461113Y871389D03*
X1457218Y888764D03*
X1452641Y888033D03*
X1451286Y898549D03*
X1462500Y905295D03*
X1461888Y936055D03*
X1462000Y957000D03*
X1458202Y960288D03*
X1457937Y966712D03*
X1457352Y976277D03*
X1459519Y989432D03*
X1467096Y988813D03*
X1456966Y998507D03*
X1458892Y1007522D03*
X1465658Y1006648D03*
X1465846Y1023900D03*
X1463025Y1018307D03*
X1459267Y1013678D03*
X1456280Y1023405D03*
X1459683Y1028377D03*
X1479972Y40780D03*
X1472146Y55513D03*
X1468371Y68581D03*
X1474746Y60513D03*
X1477606Y60438D03*
X1468384Y80581D03*
X1474874Y85731D03*
X1483287Y86012D03*
X1472514Y88801D03*
X1478428Y86046D03*
X1475431Y94351D03*
X1479380Y94279D03*
X1470567Y103621D03*
X1478624Y116594D03*
X1466278Y112083D03*
X1484567Y110784D03*
X1478624Y119594D03*
X1479058Y124283D03*
X1484124Y124879D03*
X1477465Y161306D03*
X1469221Y152562D03*
X1474716Y157370D03*
X1478800Y168665D03*
Y176665D03*
X1469913Y183834D03*
X1470023Y178560D03*
X1470086Y172665D03*
X1470899Y186629D03*
X1469433Y190185D03*
X1478800Y192665D03*
Y196665D03*
X1470203Y200864D03*
X1478913Y186778D03*
X1478832Y204864D03*
X1470292Y212455D03*
X1470226Y207037D03*
X1478832Y208864D03*
X1467593Y221642D03*
X1474473Y219379D03*
X1475101Y228631D03*
X1480589Y248371D03*
X1471507Y265897D03*
X1469007D03*
X1477549Y327200D03*
Y322700D03*
Y345200D03*
Y340700D03*
Y331700D03*
Y358700D03*
Y349700D03*
Y354200D03*
X1480702Y368516D03*
X1468309Y408861D03*
X1475236Y412482D03*
X1466231Y423671D03*
X1469538Y416795D03*
X1466653Y428582D03*
X1471375Y433115D03*
X1477597Y682997D03*
X1475264Y680933D03*
X1474713Y685247D03*
X1479297Y693630D03*
X1476794Y691447D03*
X1476716Y704398D03*
X1479500Y689630D03*
Y697630D03*
X1474425Y712925D03*
X1479759Y720885D03*
X1469957Y706957D03*
X1474000Y707000D03*
X1479794Y709388D03*
X1472000Y727500D03*
X1469116Y719055D03*
X1480000Y731500D03*
X1479759Y743500D03*
X1479657Y735500D03*
X1469957Y750957D03*
X1476716Y748398D03*
X1480000Y739500D03*
X1471006Y744818D03*
X1470801Y739280D03*
X1474425Y756925D03*
X1479665Y754555D03*
X1474000Y753093D03*
X1476677Y827626D03*
X1473489Y861354D03*
X1474060Y877196D03*
X1473468Y874267D03*
X1482387Y872940D03*
X1474883Y868206D03*
X1473433Y891043D03*
X1473387Y897425D03*
X1482195Y885807D03*
X1470925Y920575D03*
X1480343Y914776D03*
X1480109Y943496D03*
X1480144Y946880D03*
X1479441Y961941D03*
X1480414Y952214D03*
X1476500Y974000D03*
X1482237Y966028D03*
X1479196Y970000D03*
X1480414Y975064D03*
X1475096Y980330D03*
X1471096D03*
X1479096Y988813D03*
X1471296D03*
X1475096D03*
X1483096D03*
X1475062Y1008300D03*
Y1002453D03*
X1482535Y1024254D03*
X1468869Y1018469D03*
X1476230Y1030672D03*
X1473230D03*
X1471374Y1118654D03*
X1474384Y1109564D03*
X1480231D03*
X1474384Y1122164D03*
X1480231D03*
X1474384Y1134764D03*
X1480231D03*
X1474384Y1147364D03*
X1480231D03*
X1474384Y1172564D03*
X1480231D03*
X1474384Y1159964D03*
X1480231D03*
X1474384Y1185164D03*
X1480231D03*
X1483308Y1214372D03*
X1479063Y1218169D03*
X1498621Y19043D03*
X1489556Y17645D03*
X1498621Y31043D03*
Y23043D03*
X1489829Y29424D03*
X1490563Y23043D03*
X1500210Y97667D03*
X1483287Y94374D03*
X1490593Y116594D03*
X1495866Y102495D03*
X1489567Y110784D03*
X1490593Y119594D03*
X1494127Y125107D03*
X1489146Y124663D03*
X1495600Y142862D03*
X1496641Y148717D03*
X1490490Y138838D03*
X1493260Y226320D03*
X1493194Y221970D03*
X1490481Y216385D03*
X1493194Y216970D03*
Y219470D03*
X1486681Y218085D03*
X1483881D03*
X1496221Y228646D03*
X1495178Y232971D03*
X1491828Y244571D03*
X1489208Y249108D03*
X1499171Y256394D03*
X1497446Y295877D03*
X1486860Y327200D03*
X1500659Y330024D03*
X1495605Y322700D03*
X1487318Y318200D03*
X1486360Y322700D03*
Y345200D03*
X1500386Y344642D03*
X1486913Y340327D03*
X1487152Y331272D03*
X1495689Y332534D03*
X1495521Y340700D03*
X1486360Y349700D03*
X1495521Y349681D03*
X1495925Y358700D03*
X1499839Y354001D03*
X1486890Y368576D03*
X1494286Y372699D03*
X1488000Y731500D03*
X1495500Y750500D03*
X1488731Y739500D03*
X1496629Y765000D03*
X1496763Y777000D03*
X1493301Y776911D03*
X1496814Y773000D03*
X1497000Y781000D03*
X1496756Y785000D03*
X1491425Y798425D03*
X1499633Y787794D03*
X1493716Y789898D03*
X1486957Y792457D03*
X1495170Y796670D03*
X1487050Y809413D03*
X1496845Y809000D03*
X1496806Y817000D03*
X1496621Y829000D03*
X1496447Y821000D03*
X1486386Y825296D03*
X1493092Y820444D03*
X1493038Y833898D03*
X1495240Y825000D03*
X1491425Y842425D03*
X1486957Y836457D03*
X1492625Y837324D03*
X1488138Y878339D03*
Y872839D03*
X1482566Y882154D03*
X1494954Y895264D03*
X1484824Y927324D03*
X1487240Y924453D03*
X1497063Y934000D03*
X1496072Y940201D03*
X1483324Y939324D03*
X1482921Y931324D03*
X1485500Y932500D03*
X1497075Y961000D03*
X1487240Y952012D03*
X1496072Y953981D03*
X1495500Y972500D03*
X1489500D03*
X1487096Y988813D03*
X1491096D03*
X1495096D03*
X1499096D03*
X1490235Y1004816D03*
X1487266Y1002046D03*
X1486030Y1016827D03*
X1491877D03*
X1486030Y1029427D03*
X1491877D03*
X1496140Y1105091D03*
X1496185Y1102091D03*
X1496140Y1117691D03*
X1496185Y1114691D03*
Y1127291D03*
X1496140Y1130291D03*
X1496185Y1139891D03*
X1496140Y1155491D03*
Y1142891D03*
X1496185Y1152491D03*
X1496140Y1168091D03*
X1496185Y1165091D03*
X1496140Y1180691D03*
X1496185Y1177691D03*
X1482705Y1200001D03*
X1489793Y1207737D03*
X1497693Y1230407D03*
X1508670Y103411D03*
X1509064Y97667D03*
X1504460Y95111D03*
X1508829Y106561D03*
X1502741Y143762D03*
X1506689Y195176D03*
X1506207Y199248D03*
X1501689Y195176D03*
X1503207Y199248D03*
X1499189Y195176D03*
X1504189D03*
X1506207Y202048D03*
X1503207Y201748D03*
X1499270Y210509D03*
X1501043Y206806D03*
X1501770Y210509D03*
X1503543Y206806D03*
X1509807Y230117D03*
X1500962Y230556D03*
X1505217Y227824D03*
X1505823Y238714D03*
X1499947Y242078D03*
X1505304Y246874D03*
X1507524Y244297D03*
X1503884Y295549D03*
X1501500Y321000D03*
X1501000Y317500D03*
X1501684Y336561D03*
X1516838Y347422D03*
X1515909Y354601D03*
X1516636Y458711D03*
X1513284Y552466D03*
X1504495Y796844D03*
X1510527Y833500D03*
X1504938Y859711D03*
X1500353Y859855D03*
X1500638Y873839D03*
X1512712Y867418D03*
X1502158Y899479D03*
X1510527Y908951D03*
X1513927D03*
X1504208Y909740D03*
X1509274Y921226D03*
X1505337Y921240D03*
X1509500Y937000D03*
Y944138D03*
X1516500Y947500D03*
X1501812Y938397D03*
X1512161Y957541D03*
X1509500Y950500D03*
X1498973Y975443D03*
X1511000Y970500D03*
X1511096Y988813D03*
X1507096D03*
X1503096D03*
X1515096D03*
X1513286Y1012354D03*
X1507831Y1009354D03*
X1507786Y1012354D03*
Y1024954D03*
X1513286D03*
X1507831Y1021954D03*
X1503572Y1034538D03*
X1501640Y1105091D03*
Y1117691D03*
Y1130291D03*
Y1142891D03*
Y1155491D03*
Y1168091D03*
Y1180691D03*
X1508356Y1220068D03*
X1500675Y1227300D03*
X1506807Y1234921D03*
X1507692Y1224472D03*
X1507058Y1229402D03*
X1525172Y90615D03*
X1519860Y90650D03*
X1529493Y99961D03*
X1529543Y95236D03*
X1519610D03*
X1528355Y210478D03*
Y215478D03*
Y212978D03*
Y207978D03*
X1519321Y378600D03*
Y382600D03*
X1519436Y458711D03*
X1521963Y453682D03*
X1520200Y455921D03*
X1518780Y463600D03*
X1519185Y603600D03*
Y619600D03*
Y623600D03*
X1520729Y634190D03*
X1524200Y646098D03*
X1518517Y878898D03*
X1518452Y873780D03*
X1525022Y909558D03*
X1522881Y901034D03*
X1522954Y897951D03*
X1521085Y921094D03*
X1515179D03*
X1527267Y932647D03*
X1522209Y937846D03*
X1521500Y947500D03*
X1528500Y947612D03*
X1529128Y952978D03*
X1521085Y957340D03*
X1525583Y968500D03*
X1530767Y972981D03*
X1519863Y977637D03*
X1525005Y974323D03*
X1530594Y979952D03*
X1531096Y988813D03*
X1523096D03*
X1519096D03*
X1527096Y997860D03*
X1526810Y1025090D03*
X1522904Y1021256D03*
X1521939Y1040818D03*
X1522099Y1035521D03*
X1531993Y1056453D03*
X1531961Y1050849D03*
X1524953Y1051037D03*
X1517855Y1053457D03*
X1538407Y85539D03*
Y82939D03*
Y75139D03*
Y80339D03*
Y77739D03*
X1546732Y98551D03*
X1538451Y92874D03*
X1540478Y107649D03*
Y104249D03*
X1545044Y147540D03*
X1540100Y162368D03*
X1537500D03*
X1547200Y162793D03*
Y165393D03*
Y167993D03*
Y170493D03*
X1546197Y181426D03*
X1546405Y184221D03*
X1538811Y213213D03*
Y210713D03*
X1542883Y211695D03*
X1545383D03*
X1542883Y208695D03*
X1545683D03*
X1538811Y208213D03*
Y215713D03*
X1534184Y264180D03*
X1531684D03*
X1531609Y258880D03*
X1549060Y265701D03*
X1545878Y270026D03*
X1543378D03*
X1540578D03*
X1543378Y267526D03*
X1540578D03*
X1545878D03*
X1544736Y305156D03*
X1545583Y316363D03*
X1539140Y320863D03*
X1545636Y325363D03*
X1542797Y329863D03*
X1545846Y334363D03*
X1544951Y343363D03*
X1538133Y354553D03*
X1545434Y352363D03*
X1546183Y541863D03*
Y545263D03*
X1544375Y553407D03*
X1546875D03*
X1544375Y550907D03*
X1546875D03*
X1542704Y572162D03*
X1543946Y569928D03*
X1546293Y570962D03*
X1546036Y568475D03*
X1548080Y910757D03*
X1547644Y903060D03*
X1532067Y1041832D03*
X1531947Y1046212D03*
X1531546Y1062769D03*
X1536909Y1151870D03*
Y1159350D03*
X1540649Y1155610D03*
X1562828Y72615D03*
Y76587D03*
X1564267Y100625D03*
X1557286Y97475D03*
X1549627Y111223D03*
Y114623D03*
X1557217Y106186D03*
X1550282Y103783D03*
X1549627Y128796D03*
X1560029Y132509D03*
Y121735D03*
Y118335D03*
X1549627Y125396D03*
X1560029Y135909D03*
X1548816Y141247D03*
X1564846D03*
X1556283Y143740D03*
X1553663Y148277D03*
X1552203Y181009D03*
X1549408Y181366D03*
X1557378Y168697D03*
X1554705Y172190D03*
X1554124Y177616D03*
X1558466Y191941D03*
X1549022Y184012D03*
X1560475Y206767D03*
X1562975D03*
X1554144Y213132D03*
X1550441Y211359D03*
Y213859D03*
X1560605Y221708D03*
X1560020Y224421D03*
X1563105Y221708D03*
X1561720Y231021D03*
Y228221D03*
X1554144Y215632D03*
X1562271Y236189D03*
X1562212Y248765D03*
X1554388Y256303D03*
X1559163Y266114D03*
X1554147Y265896D03*
X1562409Y268195D03*
Y270695D03*
X1556636Y281982D03*
X1550695Y281716D03*
X1550931Y305158D03*
X1554403Y316363D03*
X1553534Y327337D03*
X1553910Y331798D03*
X1553597Y336601D03*
X1553862Y344867D03*
X1551175Y347283D03*
X1556588Y545528D03*
X1548359Y569426D03*
X1548645Y566929D03*
X1562385Y610400D03*
X1564670Y650122D03*
X1565132Y668153D03*
X1561552Y665455D03*
X1548629Y927836D03*
X1548504Y915689D03*
X1548616Y931602D03*
X1551163Y952888D03*
X1552000Y969850D03*
X1571895Y58013D03*
X1570733Y68581D03*
X1577108Y60513D03*
X1570746Y80581D03*
X1577236Y85731D03*
X1574876Y88801D03*
X1581742Y94279D03*
X1577793Y94351D03*
X1572929Y103621D03*
X1568640Y112083D03*
X1581420Y124283D03*
X1569333Y143518D03*
X1568433Y152373D03*
X1579827Y161306D03*
X1571583Y152562D03*
X1577078Y157370D03*
X1572275Y183834D03*
X1566990Y171523D03*
X1572385Y178560D03*
X1572448Y172665D03*
X1573261Y186629D03*
X1571795Y190185D03*
X1566520Y192490D03*
X1572565Y200864D03*
X1565475Y206767D03*
X1572654Y212455D03*
X1572588Y207037D03*
X1581194Y208864D03*
X1565605Y221708D03*
X1569955Y221642D03*
X1576835Y219379D03*
X1577463Y228631D03*
X1564771Y236189D03*
X1567271D03*
X1564712Y248765D03*
X1567212D03*
X1567709Y270695D03*
X1573869Y265897D03*
X1571369D03*
X1567709Y268195D03*
X1564909Y270695D03*
Y268195D03*
X1563877Y325363D03*
Y316363D03*
X1571625Y344131D03*
X1574775Y333549D03*
X1563877Y329863D03*
Y343363D03*
Y334363D03*
X1578587Y341787D03*
X1578420Y338309D03*
X1574775Y344127D03*
X1563877Y352363D03*
X1575935Y382109D03*
X1577862Y554121D03*
X1575934Y561420D03*
Y558917D03*
X1565323Y577716D03*
X1571755Y577937D03*
X1579760Y595500D03*
X1574760Y606929D03*
X1579260Y604567D03*
X1574720Y618400D03*
X1575001Y612592D03*
X1580418Y610072D03*
X1580354Y616317D03*
X1576297Y627600D03*
X1577077Y631712D03*
X1574880Y645891D03*
X1571888Y649380D03*
X1572141Y662981D03*
X1578000Y678776D03*
X1569434Y677111D03*
X1568872Y686971D03*
X1575192Y707592D03*
X1579968Y60438D03*
X1585649Y86012D03*
Y94374D03*
X1580790Y86046D03*
X1592955Y116594D03*
X1580986D03*
X1586929Y110784D03*
X1591929D03*
X1592955Y119594D03*
X1580986D03*
X1596489Y125107D03*
X1586486Y124879D03*
X1591508Y124663D03*
X1592852Y138838D03*
X1581162Y168665D03*
Y176665D03*
Y192665D03*
Y196665D03*
X1581275Y186778D03*
X1581194Y204864D03*
X1586243Y218085D03*
X1595622Y226320D03*
X1592843Y216385D03*
X1595556Y216970D03*
Y219470D03*
Y221970D03*
X1589043Y218085D03*
X1594190Y244571D03*
X1591570Y249108D03*
X1582951Y248371D03*
X1595069Y337361D03*
X1595109Y342663D03*
X1594466Y350984D03*
X1592635Y455911D03*
X1591443Y465332D03*
X1595460Y549800D03*
X1595260Y547075D03*
X1594760Y568000D03*
X1595364Y562800D03*
X1595300Y558800D03*
X1596790Y1442557D03*
X1592643Y1460707D03*
X1593019Y1457557D03*
X1591775Y1473090D03*
X1596038Y1492000D03*
X1591925Y1512075D03*
X1591333Y1501980D03*
X1590748Y1523377D03*
X1602572Y97667D03*
X1611032Y103411D03*
X1611426Y97667D03*
X1606822Y95111D03*
X1598228Y102495D03*
X1611191Y106561D03*
X1597962Y142862D03*
X1605103Y143762D03*
X1599003Y148717D03*
X1604051Y195176D03*
X1605569Y199248D03*
X1601551Y195176D03*
X1606551D03*
X1609051D03*
X1608569Y199248D03*
X1603405Y206806D03*
X1605905D03*
X1601632Y210509D03*
X1604132D03*
X1608569Y202048D03*
X1605569Y201748D03*
X1603324Y230556D03*
X1607579Y227824D03*
X1612169Y230117D03*
X1598583Y228646D03*
X1608185Y238714D03*
X1602309Y242078D03*
X1607666Y246874D03*
X1597540Y232971D03*
X1609886Y244297D03*
X1604677Y253198D03*
X1596691Y287397D03*
X1596197Y293477D03*
X1607947Y332326D03*
X1605966Y343794D03*
X1602138Y351047D03*
X1596253Y375633D03*
X1596534Y379760D03*
X1599527Y396718D03*
X1596760Y530000D03*
X1596260Y540500D03*
X1611316Y685800D03*
X1611027Y722427D03*
X1611327Y735973D03*
X1611627Y780327D03*
X1609500Y776100D03*
X1611873Y795127D03*
X1606190Y803774D03*
X1606709Y819165D03*
X1600333Y1440504D03*
X1596836Y1446488D03*
X1600333Y1449068D03*
X1601968Y1453442D03*
X1597457Y1460662D03*
X1605430Y1468023D03*
X1597039Y1475100D03*
X1599726Y1474990D03*
X1600008Y1488492D03*
X1601500Y1514500D03*
X1608500Y1506000D03*
Y1515000D03*
X1613790Y1531334D03*
X1609348Y1527334D03*
X1613790Y1523334D03*
X1604000Y1519000D03*
X1600732Y1539334D03*
X1609348Y1535334D03*
X1598574Y1543373D03*
X1622222Y90650D03*
X1627534Y90615D03*
X1621972Y95236D03*
X1626147Y351033D03*
X1628636Y422088D03*
X1623955Y442956D03*
X1625772Y438323D03*
X1621596Y456386D03*
X1625938Y445873D03*
X1620385Y465874D03*
X1616622Y546712D03*
Y542712D03*
X1618538Y618288D03*
X1614538D03*
X1627224Y643252D03*
X1613362Y656321D03*
X1621362D03*
X1617362D03*
X1616260Y678462D03*
X1619950Y678519D03*
X1615913Y692245D03*
X1628200Y711417D03*
X1612800Y705900D03*
X1620600D03*
X1620500Y723200D03*
X1628343Y747288D03*
X1616683Y744517D03*
X1620100Y738300D03*
X1624000Y760900D03*
X1612573Y761427D03*
X1628027Y801427D03*
X1613117Y828117D03*
X1640769Y85539D03*
Y82939D03*
Y75139D03*
Y80339D03*
Y77739D03*
X1640813Y92874D03*
X1631905Y95236D03*
X1631855Y99961D03*
X1642840Y104249D03*
Y107649D03*
X1639862Y162368D03*
X1642462D03*
X1641173Y213213D03*
Y210713D03*
Y208213D03*
X1630717Y210478D03*
Y215478D03*
Y212978D03*
Y207978D03*
X1641173Y215713D03*
X1634046Y264180D03*
X1636546D03*
X1633971Y258880D03*
X1642940Y267526D03*
Y270026D03*
X1629553Y329067D03*
X1629302Y334402D03*
X1640030Y335550D03*
X1636561Y343072D03*
X1629514Y331727D03*
X1630691Y347432D03*
X1640197Y374690D03*
X1638340Y379536D03*
X1641615Y379600D03*
X1635170Y442856D03*
X1632439Y452265D03*
X1633225Y458455D03*
X1636271Y453881D03*
X1635185Y446595D03*
X1635283Y728117D03*
X1630327Y774627D03*
X1629927Y787327D03*
X1644552Y871353D03*
X1635176Y886761D03*
X1644718Y909263D03*
X1635000Y919263D03*
X1644325Y942120D03*
X1637771Y952120D03*
X1640581Y1551907D03*
X1649094Y98551D03*
X1659648Y97475D03*
X1651989Y114623D03*
Y111223D03*
X1652644Y103783D03*
X1659579Y106186D03*
X1651989Y125396D03*
Y128796D03*
X1647406Y147540D03*
X1651178Y141247D03*
X1658645Y143740D03*
X1656025Y148277D03*
X1649562Y162793D03*
Y165393D03*
Y167993D03*
Y170493D03*
X1656486Y177616D03*
X1654565Y181009D03*
X1648559Y181426D03*
X1651770Y181366D03*
X1659740Y168697D03*
X1657067Y172190D03*
X1660828Y191941D03*
X1651384Y184012D03*
X1648767Y184221D03*
X1647745Y211695D03*
X1645245Y208695D03*
X1648045D03*
X1656506Y213132D03*
X1652803Y211359D03*
Y213859D03*
X1645245Y211695D03*
X1656506Y215632D03*
X1656750Y256303D03*
X1656509Y265896D03*
X1661525Y266114D03*
X1651422Y265701D03*
X1648240Y267526D03*
X1645740D03*
Y270026D03*
X1648240D03*
X1653057Y281716D03*
X1658998Y281982D03*
X1658200Y315039D03*
X1654771Y352088D03*
X1645685Y381500D03*
X1648835Y390500D03*
X1650044Y435158D03*
X1649789Y440489D03*
X1646209Y442606D03*
X1650087Y444841D03*
X1649773Y449961D03*
X1653490Y458572D03*
X1645826Y446606D03*
X1647133Y463479D03*
X1647604Y467367D03*
X1656112Y768669D03*
X1657042Y773604D03*
X1647402Y881460D03*
X1648375Y886766D03*
X1650205Y925911D03*
X1647763Y919268D03*
X1648387Y945554D03*
X1647470Y952125D03*
X1651443Y981515D03*
X1647565Y981432D03*
X1652944Y993796D03*
X1653414Y990590D03*
X1676870Y55513D03*
X1673095Y68581D03*
X1679470Y60513D03*
X1673108Y80581D03*
X1665190Y76587D03*
Y72615D03*
X1679598Y85731D03*
X1677238Y88801D03*
X1675291Y103621D03*
X1666629Y100625D03*
X1671002Y112083D03*
X1662391Y118335D03*
Y121735D03*
Y132509D03*
Y135909D03*
X1667208Y141247D03*
X1671695Y143518D03*
X1670795Y152373D03*
X1673945Y152562D03*
X1674637Y183834D03*
X1669352Y171523D03*
X1674810Y172665D03*
X1674747Y178560D03*
X1675623Y186629D03*
X1674157Y190185D03*
X1668882Y192490D03*
X1667318Y198828D03*
X1674927Y200864D03*
X1664840Y192300D03*
X1662837Y206767D03*
X1667837D03*
X1665337D03*
X1674950Y207037D03*
X1675016Y212455D03*
X1667967Y221708D03*
X1665467D03*
X1664082Y231021D03*
Y228221D03*
X1672317Y221642D03*
X1662967Y221708D03*
X1662382Y224421D03*
X1669633Y236189D03*
X1667133D03*
X1664633D03*
X1667074Y248765D03*
X1664574D03*
X1669574D03*
X1676231Y265897D03*
X1673731D03*
X1670071Y268195D03*
Y270695D03*
X1667271Y268195D03*
X1664771D03*
Y270695D03*
X1667271D03*
X1673203Y328867D03*
X1668979Y339559D03*
X1666860Y353661D03*
X1663650Y353283D03*
X1673723Y353881D03*
X1670323Y353534D03*
X1670260Y377912D03*
X1669260Y391496D03*
X1663618Y393858D03*
X1663780Y384410D03*
X1666959Y382047D03*
X1670260Y386500D03*
X1669260Y409000D03*
X1665260Y398583D03*
X1670348Y397912D03*
X1667260Y403500D03*
X1663713Y440869D03*
Y438269D03*
X1666513Y433069D03*
Y430469D03*
Y435669D03*
Y440869D03*
Y438269D03*
X1663713Y433069D03*
Y430469D03*
Y435669D03*
X1664567Y451677D03*
X1667067D03*
X1664567Y454177D03*
X1667067D03*
X1666271Y460218D03*
Y463618D03*
X1682330Y60438D03*
X1688011Y86012D03*
Y94374D03*
X1683152Y86046D03*
X1680155Y94351D03*
X1684104Y94279D03*
X1683348Y116594D03*
X1694291Y110784D03*
X1689291D03*
X1683348Y119594D03*
X1683782Y124283D03*
X1693870Y124663D03*
X1688848Y124879D03*
X1695214Y138838D03*
X1682189Y161306D03*
X1679440Y157370D03*
X1683524Y168665D03*
Y176665D03*
Y192665D03*
X1683637Y186778D03*
X1683556Y204864D03*
Y208864D03*
X1688605Y218085D03*
X1691405D03*
X1679197Y219379D03*
X1679825Y228631D03*
X1693932Y249108D03*
X1685313Y248371D03*
X1686339Y314890D03*
X1686115Y311740D03*
X1683523Y324518D03*
X1677810Y324466D03*
X1686408Y332584D03*
X1687424Y347937D03*
X1692676Y348015D03*
X1688593Y353470D03*
X1691182Y357016D03*
X1680518Y377912D03*
Y381912D03*
Y397912D03*
X1689920Y539315D03*
X1689236Y550137D03*
X1692028D03*
X1693000Y626912D03*
X1692379Y622912D03*
X1704934Y97667D03*
X1709184Y95111D03*
X1695317Y116594D03*
X1700590Y102495D03*
X1695317Y119594D03*
X1698851Y125107D03*
X1700324Y142862D03*
X1707465Y143762D03*
X1701365Y148717D03*
X1708913Y195176D03*
X1710931Y199248D03*
X1706413Y195176D03*
X1703913D03*
X1707931Y199248D03*
Y201748D03*
X1706494Y210509D03*
X1703994D03*
X1705767Y206806D03*
X1708267D03*
X1697984Y226320D03*
X1695205Y216385D03*
X1697918Y216970D03*
Y219470D03*
Y221970D03*
X1705686Y230556D03*
X1709941Y228747D03*
X1700945Y228646D03*
X1704671Y242078D03*
X1699902Y232971D03*
X1696552Y244571D03*
X1703895Y256394D03*
X1700223Y292141D03*
X1703609Y287320D03*
X1698292Y303962D03*
X1698716Y550065D03*
X1708015Y1142700D03*
X1711333Y1146609D03*
X1706450Y1173065D03*
X1703400Y1174400D03*
X1713394Y103411D03*
X1713788Y97667D03*
X1724584Y90650D03*
X1724334Y95236D03*
X1713553Y106561D03*
X1711413Y195176D03*
X1710931Y202048D03*
X1714531Y230117D03*
X1710547Y238714D03*
X1710028Y246874D03*
X1712248Y244297D03*
X1716755Y326179D03*
X1712226Y344028D03*
X1715930Y340969D03*
X1715590Y331719D03*
X1721746Y377173D03*
X1715228Y387966D03*
X1718851Y391533D03*
X1720571Y385644D03*
X1725746Y385123D03*
X1718318Y399918D03*
X1725154Y406060D03*
X1725415Y416289D03*
Y418889D03*
Y421489D03*
X1721423Y412106D03*
X1716310Y454334D03*
X1724627Y459330D03*
X1724580Y454214D03*
X1724923Y449045D03*
X1724930Y473571D03*
Y476071D03*
Y478571D03*
Y481071D03*
X1710174Y553101D03*
X1717626Y1134729D03*
X1710511Y1138130D03*
X1721008Y1134729D03*
X1723805Y1142666D03*
X1725008Y1134636D03*
X1725680Y1157544D03*
X1724191Y1167768D03*
X1713239Y1176038D03*
X1712526Y1171950D03*
X1728343Y1185205D03*
X1719692Y1187215D03*
X1719385Y1180175D03*
X1712715Y1188500D03*
X1721662Y1201043D03*
X1725658D03*
X1718625Y1199814D03*
X1712542Y1196600D03*
X1720536Y1217228D03*
X1723200Y1219895D03*
X1710825Y1231688D03*
X1712966Y1229841D03*
X1743175Y92874D03*
X1729896Y90615D03*
X1734267Y95236D03*
X1734217Y99961D03*
X1742224Y162368D03*
X1733079Y207978D03*
Y210478D03*
Y215478D03*
Y212978D03*
X1736408Y264180D03*
X1738908D03*
X1736333Y258880D03*
X1744524Y379429D03*
X1741746Y377173D03*
X1737786D03*
X1729751D03*
X1733746Y385123D03*
X1730746D03*
X1737746D03*
X1741420Y391569D03*
X1739847Y401066D03*
X1729508Y403300D03*
X1728915Y405889D03*
Y408489D03*
Y413689D03*
Y411089D03*
Y416289D03*
Y421489D03*
Y418889D03*
Y424089D03*
X1729302Y432718D03*
Y435518D03*
X1739179Y439318D03*
X1728915Y426689D03*
X1739179Y442118D03*
X1733014Y450091D03*
X1730014D03*
X1727404Y447209D03*
X1730404D03*
X1738824Y456034D03*
Y461034D03*
X1733014Y462060D03*
X1730014D03*
X1734952Y479217D03*
X1737646Y477213D03*
Y479713D03*
X1729002Y477053D03*
X1731502D03*
X1734952Y476717D03*
X1741800Y917900D03*
X1742029Y1116251D03*
X1739508Y1137129D03*
X1729008Y1134729D03*
X1732881D03*
X1739917Y1150087D03*
X1732137Y1157404D03*
X1737393Y1170767D03*
X1729210Y1167768D03*
X1728333Y1178240D03*
X1733052Y1187310D03*
X1737689Y1185238D03*
X1737482Y1180235D03*
X1733662Y1201039D03*
X1729628Y1201043D03*
X1737662Y1200969D03*
X1737781Y1208993D03*
X1726475Y1223170D03*
X1731533Y1228226D03*
X1729322Y1226016D03*
X1743131Y85539D03*
Y82939D03*
Y75139D03*
Y80339D03*
Y77739D03*
X1751456Y98551D03*
X1754351Y111223D03*
Y114623D03*
X1755006Y103783D03*
X1745202Y104249D03*
Y107649D03*
X1754351Y128796D03*
Y125396D03*
X1744824Y162368D03*
X1751924Y162793D03*
Y165393D03*
Y167993D03*
Y170493D03*
X1758848Y177616D03*
X1759429Y172190D03*
X1756927Y181009D03*
X1750921Y181426D03*
X1754132Y181366D03*
X1751129Y184221D03*
X1753746Y184012D03*
X1747607Y211695D03*
X1755165Y211359D03*
Y213859D03*
X1750107Y211695D03*
X1747607Y208695D03*
X1750407D03*
X1743535Y208213D03*
Y213213D03*
Y210713D03*
Y215713D03*
X1753784Y265701D03*
X1758871Y265896D03*
X1750602Y267526D03*
X1745302D03*
X1748102D03*
X1745302Y270026D03*
X1748102D03*
X1750602D03*
X1755419Y281716D03*
X1748497Y371060D03*
X1752497Y371076D03*
X1750135Y379088D03*
X1755433Y379028D03*
X1744180Y383966D03*
X1750187Y409539D03*
X1753187D03*
X1750187Y406739D03*
X1753187Y407039D03*
X1752851Y401981D03*
X1755351D03*
X1757124Y398278D03*
X1754624D03*
X1749470Y424067D03*
X1751970D03*
X1756970D03*
X1754470D03*
X1749705Y413611D03*
X1752205D03*
X1757205D03*
X1754705D03*
X1756844Y438293D03*
X1747179Y439318D03*
X1756844Y441093D03*
X1747179Y442118D03*
X1756844Y443893D03*
X1747306Y470001D03*
X1744806D03*
X1756894Y472020D03*
X1756553Y466409D03*
X1756954Y477318D03*
X1745231Y489036D03*
X1743092Y485580D03*
X1745592D03*
X1748092D03*
X1758401Y484882D03*
X1756391Y487382D03*
X1747467Y492836D03*
Y495636D03*
X1756089Y542952D03*
X1750879Y541940D03*
X1754906Y824333D03*
Y820737D03*
X1746897Y879199D03*
X1746884Y884649D03*
X1747900Y900160D03*
X1744900D03*
X1750915Y902055D03*
X1749267Y918413D03*
X1751200Y931100D03*
X1746600Y935100D03*
X1751854Y991297D03*
X1749314Y987904D03*
X1745824Y987058D03*
X1748677Y993986D03*
X1753860Y997271D03*
X1759569Y1021944D03*
X1744529Y1116251D03*
X1758390Y1577905D03*
X1759947Y1599029D03*
X1750685Y1621654D03*
X1767552Y76587D03*
Y72615D03*
X1762010Y97475D03*
X1768991Y100625D03*
X1761941Y106186D03*
X1773364Y112083D03*
X1764753Y121735D03*
Y118335D03*
Y132509D03*
Y135909D03*
X1771714Y171523D03*
X1776999Y183834D03*
X1762102Y168697D03*
X1763190Y191941D03*
X1771244Y192490D03*
X1776519Y190185D03*
X1767202Y192300D03*
X1765199Y206767D03*
X1770199D03*
X1767699D03*
X1758868Y213132D03*
X1765329Y221708D03*
X1770329D03*
X1767829D03*
X1764744Y224421D03*
X1766444Y231021D03*
Y228221D03*
X1774679Y221642D03*
X1758868Y215632D03*
X1771995Y236189D03*
X1769495D03*
X1766995D03*
X1771936Y248765D03*
X1769436D03*
X1766936D03*
X1759112Y256303D03*
X1763887Y266114D03*
X1767133Y270695D03*
X1769633D03*
X1772433Y268195D03*
Y270695D03*
X1769633Y268195D03*
X1767133D03*
X1761360Y281982D03*
X1762997Y377581D03*
X1765497Y379591D03*
X1772513Y387702D03*
X1769713D03*
X1765913Y389402D03*
X1763200Y388817D03*
Y383817D03*
Y386317D03*
X1766837Y438293D03*
Y441093D03*
Y443893D03*
X1768586Y467560D03*
X1764903Y470382D03*
X1764906Y474382D03*
X1776561Y467560D03*
X1777061Y475560D03*
X1768575D03*
X1770135Y490711D03*
X1758957Y543036D03*
X1773789Y927663D03*
X1765664Y923724D03*
X1769064D03*
X1773789Y930663D03*
X1774476Y995049D03*
X1773810Y990821D03*
X1762486Y990260D03*
X1760201Y992475D03*
X1758881Y995633D03*
X1769004Y1019395D03*
X1768844Y1023694D03*
Y1027248D03*
X1771773Y1028829D03*
X1772188Y1428369D03*
X1766313Y1580198D03*
X1761072Y1590719D03*
X1765040Y1599511D03*
X1760422Y1640303D03*
X1768422D03*
X1772422D03*
X1762041Y1631511D03*
X1768422Y1632245D03*
X1773820Y1631238D03*
X1779232Y55513D03*
X1775457Y68581D03*
X1785246Y60660D03*
X1781832Y60513D03*
X1775470Y80581D03*
X1781960Y85731D03*
X1790712Y81713D03*
X1790664Y71908D03*
X1779600Y88801D03*
X1790373Y94663D03*
X1786466Y85923D03*
Y94279D03*
X1782517Y94351D03*
X1777653Y103621D03*
X1785886Y168665D03*
Y176665D03*
X1777172Y172665D03*
X1777109Y178560D03*
X1777985Y186629D03*
X1785779Y192665D03*
X1785886Y196665D03*
X1777289Y200864D03*
X1785999Y186778D03*
X1785918Y204864D03*
X1777378Y212455D03*
X1777312Y207037D03*
X1785918Y208864D03*
X1781559Y219379D03*
X1782187Y228631D03*
X1778593Y265897D03*
X1776093D03*
X1787674Y303130D03*
X1777681Y387151D03*
Y382151D03*
Y384651D03*
X1786184Y435321D03*
Y438121D03*
X1783384Y435321D03*
Y438121D03*
X1786184Y440921D03*
X1783384D03*
X1786184Y443721D03*
X1783384D03*
X1786170Y448931D03*
X1792527Y452799D03*
X1786693Y459170D03*
X1790061Y474513D03*
X1779404Y826570D03*
X1791041Y818795D03*
X1780016Y874400D03*
X1775904Y924546D03*
X1778047Y916120D03*
X1789537Y930498D03*
X1780158Y953295D03*
X1785758Y956095D03*
Y953295D03*
X1782958D03*
Y956095D03*
X1780158D03*
X1789363Y969160D03*
X1782563Y979660D03*
X1785663D03*
X1779363D03*
X1786863Y985060D03*
X1779143Y995203D03*
X1779033Y1023432D03*
X1786740Y1019237D03*
X1780802Y1019474D03*
X1774863Y1019237D03*
X1774844Y1023694D03*
X1783844D03*
X1786844Y1027248D03*
X1780844D03*
X1774844D03*
X1789844Y1023694D03*
X1775998Y1074707D03*
Y1072207D03*
X1781198Y1074707D03*
X1778598D03*
X1783798D03*
Y1072207D03*
X1778598D03*
X1781198D03*
X1790736Y1072090D03*
Y1074590D03*
X1780326Y1089851D03*
X1777726D03*
X1782926D03*
Y1092351D03*
X1777726D03*
X1780326D03*
X1775126Y1089851D03*
Y1092351D03*
X1790639Y1082585D03*
X1790572Y1085152D03*
X1780662Y1108413D03*
X1783262D03*
X1778062D03*
X1775462D03*
X1785321Y1121122D03*
X1787921D03*
X1790521D03*
X1780566Y1111038D03*
X1783166D03*
X1777966D03*
X1775366D03*
X1790521Y1130822D03*
X1781874Y1139822D03*
X1787921Y1130822D03*
X1785321D03*
X1784374Y1139822D03*
X1781802Y1147822D03*
X1784302D03*
X1783278Y1208140D03*
X1778227Y1438099D03*
X1786091Y1443715D03*
X1787745Y1437765D03*
X1783178Y1437550D03*
X1778104Y1470289D03*
X1791088Y77296D03*
X1804758Y294429D03*
X1793524Y303343D03*
X1805196Y300952D03*
X1799897Y408104D03*
X1802697D03*
X1805497D03*
X1793475Y424939D03*
X1799614Y420375D03*
X1802414D03*
X1805214D03*
X1793475Y427439D03*
X1809095Y435101D03*
X1803700Y440101D03*
X1803530Y431112D03*
X1809358Y442114D03*
X1803335Y452718D03*
X1809346Y452601D03*
X1797907Y452987D03*
X1809338Y447121D03*
X1804933Y461607D03*
X1796933D03*
X1796136Y471334D03*
X1800933Y461607D03*
X1802000Y892447D03*
X1797365Y930761D03*
X1793474Y930374D03*
X1805463Y969260D03*
X1801963Y969160D03*
X1802363Y989660D03*
X1803351Y1027471D03*
X1805188Y1019078D03*
X1799646Y1018999D03*
X1793470Y1018762D03*
X1801844Y1023694D03*
X1795844D03*
X1798844Y1027248D03*
X1792844D03*
X1795936Y1072090D03*
X1793336D03*
X1798536D03*
Y1074590D03*
X1793336D03*
X1795936D03*
X1801961Y1081717D03*
X1795819Y1088553D03*
X1800813Y1103246D03*
X1806206Y1114589D03*
X1803506D03*
X1800906D03*
X1798306D03*
X1798702Y1124328D03*
X1801302D03*
X1803902D03*
X1806602D03*
X1793221Y1121122D03*
Y1130822D03*
X1804532Y1133356D03*
X1807232D03*
X1807035Y1136912D03*
Y1144912D03*
X1806835Y1214668D03*
X1800489Y1220598D03*
X1807243Y1219955D03*
X1802670Y1210905D03*
X1805126Y1225745D03*
X1799845Y1261044D03*
X1794845D03*
X1797345D03*
X1799845Y1263544D03*
X1797345D03*
X1794845D03*
X1803885Y1435046D03*
X1806428Y1444543D03*
X1795374D03*
X1802813Y1464015D03*
X1803762Y1467236D03*
X1819900Y906900D03*
X1807663Y966660D03*
Y963860D03*
X1808014Y984832D03*
X1812538Y1026859D03*
X1811468Y1021084D03*
X1807844Y1023694D03*
Y1027248D03*
X1810349Y1031264D03*
X1816756Y1089145D03*
Y1094145D03*
X1816235Y1083970D03*
X1810346Y1082250D03*
X1816756Y1097145D03*
Y1101145D03*
X1810310Y1104819D03*
X1809535Y1136912D03*
Y1144912D03*
X1812130Y1205349D03*
X1822594Y1211054D03*
Y1215324D03*
X1814741Y1217093D03*
X1811482Y1226423D03*
X1810018Y1295944D03*
X1812818D03*
X1815618Y1298744D03*
Y1295944D03*
X1812818Y1298744D03*
X1810018D03*
X1812202Y1432624D03*
X1809342Y1476733D03*
X1824706Y1085145D03*
X1824949Y1077145D03*
X1824706Y1100185D03*
Y1106145D03*
X1828272Y1095968D03*
X1824706Y1093150D03*
X1830915Y1109146D03*
X1834665Y1213239D03*
G54D23*
X51750Y617861D03*
X48207D03*
X44664D03*
X51750Y620661D03*
X48207D03*
X44664D03*
X55294Y617861D03*
Y620661D03*
X146948Y1088287D03*
X143208D03*
X146948Y1099507D03*
X143208D03*
X146948Y1106988D03*
X143208D03*
X146948Y1114468D03*
Y1121948D03*
X143208Y1114468D03*
Y1121948D03*
X146948Y1129429D03*
X143208D03*
X146948Y1136909D03*
X143208D03*
X146948Y1148129D03*
X143208D03*
X146947Y1170570D03*
X143207D03*
X146947Y1178051D03*
X143207D03*
X165649Y1073326D03*
X158169D03*
X150689D03*
X165649Y1092027D03*
X158169D03*
X150689D03*
X165649Y1077066D03*
X161909Y1084547D03*
X158169Y1077066D03*
X154429Y1084547D03*
X161909Y1080807D03*
X154429D03*
X165649Y1095767D03*
X161909Y1103247D03*
X158169Y1095767D03*
X154429Y1103247D03*
X150689Y1095767D03*
X161909Y1099507D03*
X154429D03*
X161909Y1118208D03*
Y1121948D03*
X165649Y1110728D03*
X161909D03*
X154429D03*
Y1118208D03*
X150689Y1110728D03*
Y1118208D03*
X154429Y1125688D03*
X150689D03*
Y1133169D03*
X165649D03*
X161909D03*
X154429D03*
X165649Y1148129D03*
Y1144389D03*
Y1155610D03*
X160039Y1176180D03*
X156299D03*
X169389Y1084547D03*
Y1080807D03*
Y1103247D03*
X173129Y1136909D03*
X169389D03*
X176870Y1151870D03*
Y1148129D03*
Y1144389D03*
X169389Y1151870D03*
Y1148129D03*
X176870Y1166830D03*
Y1159350D03*
X169389D03*
X176870Y1174310D03*
Y1178051D03*
Y1181791D03*
X188090Y1114468D03*
X184350D03*
X191830D03*
X195570D03*
X191830Y1140649D03*
Y1136909D03*
X195570Y1140649D03*
X184350Y1136909D03*
X191830Y1133169D03*
Y1129429D03*
Y1144389D03*
Y1151869D03*
X195570Y1148129D03*
Y1155610D03*
X184350Y1144389D03*
X188090Y1155610D03*
X184350Y1151870D03*
X188090Y1148129D03*
X191830Y1159350D03*
Y1170570D03*
X195570Y1166830D03*
X184350Y1159350D03*
Y1170570D03*
X188090Y1166830D03*
X191830Y1185531D03*
Y1178051D03*
X195570Y1181791D03*
Y1174310D03*
X184350Y1185531D03*
X188090Y1181791D03*
Y1174310D03*
X184350Y1178051D03*
X191830Y1193011D03*
X195570Y1215452D03*
X197440Y1217322D03*
X186220D03*
X189960D03*
Y1213582D03*
X203051Y1114468D03*
X199311D03*
X206791D03*
X210531D03*
X206791Y1136909D03*
X203051D03*
X199311D03*
X214271D03*
X210531D03*
X199311Y1129429D03*
X206791D03*
X214271D03*
X210531D03*
X203051D03*
X210531Y1155610D03*
X203051D03*
X206791Y1144389D03*
X203051D03*
X199311D03*
X214271D03*
X210531D03*
X214271Y1151870D03*
X210531D03*
X206791D03*
X203051D03*
X199311D03*
X214271Y1170570D03*
X210531Y1166830D03*
X214271Y1159350D03*
X206791Y1170570D03*
X203051Y1166830D03*
X199311Y1170570D03*
X206791Y1159350D03*
X199311D03*
X203051Y1174310D03*
X210531D03*
X203051Y1185531D03*
X199311D03*
X206791D03*
X214271D03*
X210531D03*
X206791Y1178051D03*
X203051D03*
X199311D03*
X214271D03*
X210531D03*
X214271Y1193011D03*
X210531D03*
X199311D03*
X203051D03*
X206791D03*
X214271Y1200491D03*
X210531D03*
X199311D03*
X206791D03*
X203051D03*
X201181Y1213582D03*
X214271Y1211712D03*
X208661Y1213582D03*
X203051Y1215452D03*
X214271D03*
X201181Y1217322D03*
X208661D03*
X210531Y1215452D03*
X204921Y1213582D03*
X225492Y1114468D03*
X221752D03*
X218011D03*
X225492Y1136909D03*
X221751D03*
X218011D03*
X229232D03*
Y1129429D03*
X218011D03*
X221751D03*
X225492D03*
X218011Y1155610D03*
X225492D03*
Y1144389D03*
X221751D03*
X218011D03*
X229232D03*
Y1151870D03*
X221752D03*
X218011D03*
X225492D03*
Y1166830D03*
X221751Y1170570D03*
X218011Y1166830D03*
X221751Y1159350D03*
X229232Y1170570D03*
Y1159350D03*
X225492Y1174310D03*
X218011D03*
X225492Y1185531D03*
X218011D03*
X221751D03*
X229232D03*
X225492Y1178051D03*
X221751D03*
X218011D03*
X229232D03*
X218011Y1193011D03*
X221751D03*
X225492D03*
X229232D03*
X218011Y1200491D03*
X221751D03*
X225492D03*
X229232D03*
X218011Y1215452D03*
X229232Y1211712D03*
Y1215452D03*
X225492Y1211712D03*
X221752D03*
Y1215452D03*
X240452Y1114468D03*
X244192D03*
X236712Y1118208D03*
X244192D03*
X236712Y1114468D03*
X240452Y1118208D03*
Y1136909D03*
X236712D03*
X244192D03*
Y1129429D03*
X240452D03*
X236712D03*
Y1155610D03*
X244192D03*
X240452Y1151869D03*
X236712D03*
X244192D03*
X240452Y1144389D03*
X236712D03*
X244192D03*
X236712Y1166830D03*
X240452Y1170570D03*
Y1159350D03*
X244192Y1166830D03*
X236712Y1174310D03*
X244192D03*
X240452Y1185531D03*
X236712D03*
X244192D03*
X240452Y1178051D03*
X236712D03*
X244192D03*
X240452Y1193011D03*
X236712D03*
X244192D03*
X236712Y1200491D03*
X244192D03*
X240452D03*
X244192Y1215452D03*
X240452D03*
X242322Y1217322D03*
X236712Y1211712D03*
Y1215452D03*
X238582Y1217322D03*
X262893Y1118208D03*
X259153Y1114468D03*
X262893D03*
X255413Y1118208D03*
Y1114468D03*
X247933D03*
X259153Y1118208D03*
X251673Y1114468D03*
X247933Y1118208D03*
X251673D03*
X255413Y1136909D03*
X251673D03*
X247933D03*
X259153D03*
X262893D03*
X247933Y1129429D03*
X259153D03*
X262893D03*
X255413D03*
X251673D03*
Y1155610D03*
X259153D03*
X251673Y1144389D03*
X247933D03*
X255413D03*
X259153Y1151869D03*
X262893D03*
X247933D03*
X255413D03*
X251673D03*
X262893Y1144389D03*
X259153D03*
X251673Y1166830D03*
X255413Y1170570D03*
X247933D03*
X255413Y1159350D03*
X247933D03*
X259153Y1166830D03*
X262893Y1170570D03*
Y1159350D03*
X251673Y1174310D03*
X259153D03*
X247933Y1185531D03*
X255413D03*
X251673D03*
X259153D03*
X262893D03*
X251673Y1178051D03*
X247933D03*
X255413D03*
X259153D03*
X262893D03*
X251673Y1193011D03*
X255413D03*
X247933D03*
X262893D03*
X259153D03*
Y1200491D03*
X262893D03*
X251673D03*
X247933D03*
X255413D03*
Y1215452D03*
X262893D03*
X247932Y1215451D03*
X259153Y1215452D03*
X251673D03*
X247932Y1211711D03*
X251673D03*
X270373Y1114468D03*
X274114D03*
X277854D03*
X266633Y1136909D03*
Y1129429D03*
X274114D03*
Y1140649D03*
Y1136909D03*
X266633Y1155610D03*
X277854D03*
X266633Y1151869D03*
Y1144389D03*
X274114D03*
X277854Y1159350D03*
Y1166830D03*
Y1170570D03*
X266633D03*
X270373D03*
X266633Y1159350D03*
X270373D03*
Y1166830D03*
X266633D03*
Y1174310D03*
X277854D03*
X266633Y1185531D03*
Y1178051D03*
X270373Y1181791D03*
X274114Y1185531D03*
Y1189271D03*
Y1178051D03*
X266633Y1193011D03*
Y1200491D03*
X274114D03*
Y1193011D03*
X277854Y1204232D03*
Y1196751D03*
Y1200491D03*
X274114Y1215452D03*
X277854D03*
X266633D03*
X274114Y1211712D03*
X277854Y1207972D03*
X285334Y1118208D03*
X281594D03*
X285334Y1114468D03*
X281594D03*
X289074Y1140649D03*
X285334D03*
Y1136909D03*
X292815Y1140649D03*
X285334Y1155610D03*
X281594Y1144389D03*
X285334Y1148129D03*
Y1144389D03*
X289074Y1148129D03*
X292815D03*
Y1155610D03*
X285334Y1170570D03*
Y1166830D03*
Y1159350D03*
X292815Y1170570D03*
X285334Y1174310D03*
X289074Y1189271D03*
X285334D03*
X281594Y1181791D03*
X285334Y1178051D03*
X289074Y1181791D03*
X285334Y1196751D03*
Y1204232D03*
X281594Y1200491D03*
X285334D03*
Y1207972D03*
Y1215452D03*
Y1211712D03*
X281594Y1215452D03*
Y1207972D03*
X311515Y1140649D03*
X304035Y1144389D03*
Y1151869D03*
X307775Y1144389D03*
Y1151869D03*
X296555Y1155610D03*
X311515Y1148129D03*
Y1155610D03*
X304035Y1166830D03*
Y1159350D03*
X307775Y1166830D03*
X296555Y1170570D03*
X311515D03*
X304035Y1174310D03*
Y1181791D03*
Y1189271D03*
X307775Y1174310D03*
Y1181791D03*
Y1189271D03*
X311515Y1178051D03*
Y1185531D03*
Y1193011D03*
X322736Y1136909D03*
X326476D03*
X315255Y1140649D03*
X322736Y1144389D03*
Y1151870D03*
X326476Y1144389D03*
X315255Y1148129D03*
X326476Y1151870D03*
X315255Y1155610D03*
X322736Y1159350D03*
X326476D03*
X315255Y1170570D03*
X322736Y1174310D03*
Y1181791D03*
Y1189271D03*
X326476Y1174310D03*
X315255Y1178051D03*
X326476Y1181791D03*
X315255Y1185531D03*
X326476Y1189271D03*
X315255Y1193011D03*
X425023Y441086D03*
Y433999D03*
Y437543D03*
X422223Y441086D03*
Y433999D03*
Y437543D03*
X425023Y444629D03*
X422223D03*
X501750Y620661D03*
X505293D03*
X501750Y617861D03*
X505293D03*
X512380D03*
X508836Y620661D03*
Y617861D03*
X512380Y620661D03*
X600295Y1088287D03*
X604035D03*
X600295Y1099507D03*
X604035D03*
X600295Y1106988D03*
X604035D03*
Y1121948D03*
X600295D03*
Y1114468D03*
X604035D03*
X600295Y1136909D03*
X604035D03*
X600295Y1129429D03*
X604035D03*
Y1148129D03*
X600295D03*
X604034Y1170570D03*
X600294D03*
X604034Y1178051D03*
X600294D03*
X615256Y1073326D03*
X607776D03*
X618996Y1084547D03*
Y1080807D03*
X615256Y1077066D03*
X611516Y1080807D03*
Y1084547D03*
X607776Y1092027D03*
X615256D03*
X607776Y1095767D03*
X615256D03*
X618996Y1103247D03*
X611516D03*
X618996Y1099507D03*
X611516D03*
X618996Y1118208D03*
Y1121948D03*
X611516Y1118208D03*
X607776D03*
X611516Y1110728D03*
X618996D03*
X607776D03*
X611516Y1125688D03*
X607776D03*
Y1133169D03*
X615256Y1178051D03*
X611516D03*
X622736Y1073326D03*
Y1077066D03*
X626476Y1084547D03*
X622736Y1092027D03*
X626476Y1080807D03*
X622736Y1095767D03*
X626476Y1103247D03*
X622736Y1118208D03*
X626476Y1114468D03*
X622736Y1110728D03*
X630216Y1114468D03*
X633957Y1151870D03*
Y1148129D03*
Y1144389D03*
X626476Y1148129D03*
X622736Y1144389D03*
Y1148129D03*
X626476Y1151870D03*
X622736Y1155610D03*
X633957Y1166830D03*
Y1159350D03*
X626476D03*
X633957Y1174310D03*
Y1178051D03*
Y1181791D03*
X645177Y1114468D03*
X641437D03*
X648917D03*
X652657D03*
X648917Y1140649D03*
Y1136909D03*
X652657Y1140649D03*
X641437Y1136909D03*
X648917Y1129429D03*
Y1133169D03*
X652657Y1148129D03*
Y1155610D03*
X648917Y1144389D03*
Y1151869D03*
X641437Y1144389D03*
Y1151870D03*
X645177Y1155610D03*
Y1148129D03*
X648917Y1159350D03*
Y1170570D03*
X652657Y1166830D03*
X641437Y1170570D03*
X645177Y1166830D03*
X641437Y1159350D03*
X648917Y1185531D03*
Y1178051D03*
X652657Y1181791D03*
Y1174310D03*
X641437Y1185531D03*
Y1178051D03*
X645177Y1181791D03*
Y1174310D03*
X648917Y1193011D03*
X652657Y1215452D03*
Y1219192D03*
X641437Y1215452D03*
X648917D03*
X645177D03*
X660138Y1114468D03*
X656398D03*
X663878D03*
X667618D03*
Y1129429D03*
X660138D03*
X656398D03*
X663878D03*
Y1136909D03*
X660138D03*
X656398D03*
X667618D03*
X660138Y1155610D03*
X667618D03*
Y1144389D03*
X663878D03*
X660138D03*
X656398D03*
X667618Y1151870D03*
X663878D03*
X660138D03*
X656398D03*
X663878Y1170570D03*
X660138Y1166830D03*
X656398Y1170570D03*
X663878Y1159350D03*
X656398D03*
X667618Y1166830D03*
Y1174310D03*
X660138D03*
X667618Y1185531D03*
X660138D03*
X656398D03*
X663878D03*
X667618Y1178051D03*
X663878D03*
X660138D03*
X656398D03*
X667618Y1200491D03*
X656398D03*
X663878D03*
X660138D03*
X663878Y1193011D03*
X660138D03*
X656398D03*
X667618D03*
X663878Y1211712D03*
X656398D03*
X660138Y1215452D03*
X656398D03*
X663878D03*
X667618D03*
X660138Y1211712D03*
X682579Y1114468D03*
X678839D03*
X675098D03*
Y1129429D03*
X671358D03*
X678838D03*
X682579D03*
Y1136909D03*
X678838D03*
X675098D03*
X671358D03*
X682579Y1155610D03*
X675098D03*
X678839Y1151870D03*
X675098D03*
X671358D03*
X682579D03*
Y1144389D03*
X671358D03*
X678838D03*
X675098D03*
X682579Y1166830D03*
X678838Y1170570D03*
X671358D03*
X675098Y1166830D03*
X671358Y1159350D03*
X678838D03*
X682579Y1174310D03*
X675098D03*
X682579Y1185531D03*
X675098D03*
X671358D03*
X678838D03*
X682579Y1178051D03*
X678838D03*
X675098D03*
X671358D03*
X675098Y1200491D03*
X671358D03*
X678838D03*
X682579D03*
Y1193011D03*
X678838D03*
X675098D03*
X671358D03*
X682579Y1211712D03*
X678839D03*
Y1215452D03*
X671358Y1211712D03*
Y1215452D03*
X675098D03*
X693799Y1114468D03*
Y1118208D03*
X701279Y1114468D03*
X697539Y1118208D03*
Y1114468D03*
X701279Y1118208D03*
Y1129429D03*
X697539D03*
X693799D03*
X686319D03*
X697539Y1136909D03*
X693799D03*
X701279D03*
X686319D03*
X701279Y1155610D03*
X693799D03*
X701279Y1151869D03*
X697539D03*
X693799D03*
X701279Y1144389D03*
X697539D03*
X693799D03*
X686319D03*
Y1151870D03*
X693799Y1166830D03*
X697539Y1170570D03*
Y1159350D03*
X701279Y1166830D03*
X686319Y1170570D03*
Y1159350D03*
X701279Y1174310D03*
X693799D03*
X701279Y1185531D03*
X697539D03*
X693799D03*
X701279Y1178051D03*
X697539D03*
X693799D03*
X686319Y1185531D03*
Y1178051D03*
X701279Y1200491D03*
X697539D03*
X693799D03*
X686319D03*
X701279Y1193011D03*
X697539D03*
X693799D03*
X686319D03*
Y1211712D03*
Y1215452D03*
X699409Y1217322D03*
X697539Y1215452D03*
X693799D03*
Y1211712D03*
X701279Y1215452D03*
X695669Y1217322D03*
X708760Y1114468D03*
X716240Y1118208D03*
X705020Y1114468D03*
X712500D03*
X716240D03*
X705020Y1118208D03*
X712500D03*
X708760D03*
X705020Y1129429D03*
X708760D03*
X712500D03*
X716240D03*
Y1136909D03*
X705020D03*
X708760D03*
X712500D03*
X708760Y1155610D03*
X716240D03*
Y1151869D03*
X708760D03*
X712500D03*
X705020D03*
X712500Y1144389D03*
X705020D03*
X708760D03*
X716240D03*
Y1166830D03*
X705020Y1159350D03*
X712500D03*
X705020Y1170570D03*
X712500D03*
X708760Y1166830D03*
X716240Y1174310D03*
X708760D03*
X716240Y1185531D03*
X708760D03*
X712500D03*
X705020D03*
X716240Y1178051D03*
X712500D03*
X705020D03*
X708760D03*
X712500Y1200491D03*
X705020D03*
X708760D03*
X716240D03*
X708760Y1193011D03*
X712500D03*
X705020D03*
X716240D03*
Y1215452D03*
X708760D03*
X712500D03*
X705019Y1215451D03*
Y1211711D03*
X708760D03*
X731201Y1114468D03*
X734941D03*
X727460D03*
X719980Y1118208D03*
Y1114468D03*
Y1129429D03*
X723720D03*
X731201D03*
X719980Y1136909D03*
X723720D03*
X731201D03*
Y1140649D03*
X723720Y1155610D03*
X719980Y1151869D03*
X723720D03*
Y1144389D03*
X719980D03*
X734941Y1155610D03*
X731201Y1144389D03*
X719980Y1159350D03*
X727460D03*
X723720D03*
Y1166830D03*
X727460D03*
X719980Y1170570D03*
X727460D03*
X723720D03*
X734941Y1159350D03*
Y1166830D03*
Y1170570D03*
X723720Y1174310D03*
X727460Y1181791D03*
X719980Y1185531D03*
Y1178051D03*
X723720D03*
Y1185531D03*
X734941Y1174310D03*
X731201Y1189271D03*
Y1185531D03*
Y1178051D03*
X719980Y1200491D03*
X723720D03*
X731201D03*
X719980Y1193011D03*
X723720D03*
X731201D03*
X734941Y1196751D03*
Y1204232D03*
Y1200491D03*
X731201Y1215452D03*
X734941D03*
X723720D03*
X719980D03*
X731201Y1211712D03*
X734941Y1207972D03*
X727461Y1215452D03*
X738681Y1118208D03*
X742421D03*
X738681Y1114468D03*
X742421D03*
Y1140649D03*
Y1136909D03*
X746161Y1140649D03*
X749902D03*
X742421Y1155610D03*
X746161Y1148129D03*
X738681Y1144389D03*
X742421Y1148129D03*
Y1144389D03*
X749902Y1155610D03*
Y1148129D03*
X742421Y1159350D03*
Y1166830D03*
Y1170570D03*
X749902D03*
X742421Y1189271D03*
X746161D03*
X742421Y1174310D03*
X738681Y1181791D03*
X746161D03*
X742421Y1178051D03*
Y1196751D03*
X738681Y1200491D03*
X742421Y1204232D03*
Y1200491D03*
Y1211712D03*
Y1215452D03*
Y1207972D03*
X738681Y1215452D03*
Y1207972D03*
Y1211712D03*
X761122Y1144389D03*
Y1151869D03*
X753642Y1155610D03*
X764862Y1151869D03*
Y1144389D03*
Y1166830D03*
X761122D03*
Y1159350D03*
X753642Y1170570D03*
X764862Y1174310D03*
X761122Y1181791D03*
X764862D03*
X761122Y1174310D03*
X768602Y1140649D03*
X772342D03*
Y1148129D03*
Y1155610D03*
X783563Y1151870D03*
X779823D03*
Y1144389D03*
X783563D03*
X768602Y1155610D03*
Y1148129D03*
X779823Y1159350D03*
X772342Y1170570D03*
X768602D03*
X783563Y1159350D03*
Y1189271D03*
X768602Y1185531D03*
X772342Y1178051D03*
X779823Y1189271D03*
X772342Y1185531D03*
X783563Y1174310D03*
X779823D03*
X783563Y1181791D03*
X768602Y1178051D03*
X779823Y1181791D03*
X768602Y1193011D03*
X772342D03*
X920349Y450340D03*
X917549D03*
X920349Y453884D03*
Y457427D03*
X917549Y453884D03*
Y457427D03*
X920349Y460970D03*
X917549D03*
X962380Y617861D03*
X958837D03*
X962380Y620661D03*
X958837D03*
X969467D03*
X965923Y617861D03*
Y620661D03*
X969467Y617861D03*
X1057381Y1088287D03*
Y1106988D03*
Y1099507D03*
Y1114468D03*
Y1121948D03*
Y1129429D03*
Y1136909D03*
Y1148129D03*
X1057380Y1170570D03*
Y1178051D03*
X1072342Y1073326D03*
X1064862D03*
Y1092027D03*
X1072342Y1077066D03*
X1068602Y1084547D03*
Y1080807D03*
X1061121Y1088287D03*
X1072342Y1092027D03*
X1068602Y1099507D03*
X1072342Y1095767D03*
X1061121Y1106988D03*
X1068602Y1103247D03*
X1064862Y1095767D03*
X1061121Y1099507D03*
Y1114468D03*
X1068602Y1110728D03*
Y1118208D03*
X1064862Y1110728D03*
Y1118208D03*
X1061121Y1121948D03*
X1064862Y1125688D03*
X1068602D03*
X1061121Y1129429D03*
X1064862Y1133169D03*
X1061121Y1136909D03*
Y1148129D03*
X1061120Y1170570D03*
X1072342Y1178051D03*
X1068602D03*
X1061120D03*
X1079822Y1073326D03*
Y1092027D03*
X1083562Y1084547D03*
X1079822Y1077066D03*
X1076082Y1084547D03*
Y1080807D03*
X1083562D03*
X1076082Y1103247D03*
X1079822Y1095767D03*
X1076082Y1099507D03*
X1083562Y1103247D03*
X1079822Y1118208D03*
X1076082Y1121948D03*
Y1118208D03*
X1079822Y1110728D03*
X1083562Y1114468D03*
X1087302D03*
X1076082Y1110728D03*
X1091043Y1151870D03*
Y1148129D03*
Y1144389D03*
X1083562Y1148129D03*
X1079822Y1144389D03*
Y1148129D03*
X1083562Y1151870D03*
X1079822Y1155610D03*
X1091043Y1166830D03*
Y1159350D03*
X1083562D03*
X1091043Y1181791D03*
Y1178051D03*
Y1174310D03*
X1102263Y1114468D03*
X1098523D03*
X1106003D03*
Y1140649D03*
Y1136909D03*
X1098523D03*
X1106003Y1129429D03*
Y1133169D03*
Y1151869D03*
Y1144389D03*
X1098523D03*
Y1151870D03*
X1102263Y1148129D03*
Y1155610D03*
X1106003Y1170570D03*
Y1159350D03*
X1102263Y1166830D03*
X1098523Y1159350D03*
Y1170570D03*
X1106003Y1178051D03*
Y1185531D03*
X1098523D03*
X1102263Y1174310D03*
X1098523Y1178051D03*
X1102263Y1181791D03*
X1106003Y1193011D03*
Y1215452D03*
X1098523D03*
X1102263D03*
X1117224Y1114468D03*
X1113484D03*
X1120964D03*
X1124704D03*
X1109743D03*
X1120964Y1129429D03*
X1113484D03*
X1117224D03*
X1124704D03*
Y1136909D03*
X1113484D03*
X1117224D03*
X1120964D03*
X1109743Y1140649D03*
X1124704Y1144389D03*
X1113484D03*
X1117224D03*
X1120964D03*
X1113484Y1151870D03*
X1117224D03*
X1120964D03*
X1124704D03*
Y1155610D03*
X1109743D03*
Y1148129D03*
X1117224Y1155610D03*
X1113484Y1159350D03*
X1120964D03*
X1109743Y1166830D03*
X1113484Y1170570D03*
X1117224Y1166830D03*
X1120964Y1170570D03*
X1124704Y1166830D03*
X1113484Y1178051D03*
X1117224D03*
X1120964D03*
X1124704D03*
X1120964Y1185531D03*
X1113484D03*
X1117224D03*
X1124704D03*
X1109743Y1174310D03*
Y1181791D03*
X1117224Y1174310D03*
X1124704D03*
X1117224Y1200491D03*
X1120964D03*
X1113484D03*
X1124704D03*
X1120964Y1193011D03*
X1117224D03*
X1113484D03*
X1124704D03*
Y1215452D03*
X1120964D03*
Y1211712D03*
X1117224Y1215452D03*
X1109743D03*
X1113484Y1211712D03*
X1111613Y1217322D03*
X1115354D03*
X1117224Y1211712D03*
X1139665Y1114468D03*
X1135925D03*
X1132184D03*
Y1129429D03*
X1128444D03*
X1135924D03*
X1139665D03*
Y1136909D03*
X1135924D03*
X1132184D03*
X1128444D03*
Y1144389D03*
X1135924D03*
X1132184D03*
X1139665D03*
X1135925Y1151870D03*
X1132184D03*
X1128444D03*
X1139665D03*
Y1155610D03*
X1132184D03*
X1139665Y1166830D03*
X1135924Y1170570D03*
X1128444D03*
X1132184Y1166830D03*
X1128444Y1159350D03*
X1135924D03*
X1139665Y1178051D03*
X1135924D03*
X1132184D03*
X1128444D03*
X1139665Y1185531D03*
X1132184D03*
X1128444D03*
X1135924D03*
X1139665Y1174310D03*
X1132184D03*
Y1200491D03*
X1128444D03*
X1135924D03*
X1139665D03*
X1128444Y1193011D03*
X1132184D03*
X1135924D03*
X1139665D03*
Y1211712D03*
X1135925D03*
Y1215452D03*
X1128444D03*
X1132184D03*
X1128444Y1211712D03*
X1154625Y1118208D03*
X1150885D03*
X1154625Y1114468D03*
X1150885D03*
X1154625Y1129429D03*
X1150885D03*
X1143405D03*
Y1136909D03*
X1154625D03*
X1150885D03*
X1143405Y1144389D03*
X1150885Y1151869D03*
X1154625D03*
Y1144389D03*
X1150885D03*
X1143405Y1151870D03*
X1150885Y1155610D03*
X1143405Y1170570D03*
X1154625Y1159350D03*
X1143405D03*
X1150885Y1166830D03*
X1154625Y1170570D03*
X1143405Y1178051D03*
Y1185531D03*
X1154625D03*
X1150885D03*
X1154625Y1178051D03*
X1150885D03*
Y1174310D03*
X1143405Y1200491D03*
X1154625D03*
X1150885D03*
Y1193011D03*
X1154625D03*
X1143405D03*
Y1211712D03*
Y1215452D03*
X1150885Y1211712D03*
Y1215452D03*
X1154625D03*
X1156495Y1217322D03*
X1152755D03*
X1162106Y1114468D03*
X1169586D03*
X1162106Y1118208D03*
X1173326Y1114468D03*
X1158365Y1118208D03*
X1173326D03*
X1165846Y1114468D03*
X1158365D03*
X1169586Y1118208D03*
X1165846D03*
X1169586Y1129429D03*
X1165846D03*
X1162106D03*
X1158365D03*
X1173326D03*
Y1136909D03*
X1169586D03*
X1165846D03*
X1158365D03*
X1162106D03*
X1173326Y1151869D03*
X1158365D03*
X1162106D03*
X1169586D03*
X1165846D03*
X1173326Y1144389D03*
X1165846D03*
X1158365D03*
X1162106D03*
X1169586D03*
X1173326Y1155610D03*
X1165846D03*
X1158365D03*
X1173326Y1166830D03*
X1165846D03*
X1169586Y1170570D03*
X1158365Y1166830D03*
X1162106Y1170570D03*
X1169586Y1159350D03*
X1162106D03*
X1158365Y1185531D03*
X1162106D03*
X1169586D03*
X1165846D03*
X1173326D03*
X1165846Y1178051D03*
X1158365D03*
X1162106D03*
X1169586D03*
X1173326D03*
X1165846Y1174310D03*
X1158365D03*
X1173326D03*
Y1200491D03*
X1165846D03*
X1162106D03*
X1158365D03*
X1169586D03*
X1165846Y1193011D03*
X1169586D03*
X1158365D03*
X1162106D03*
X1173326D03*
Y1215452D03*
X1165846D03*
X1169586D03*
X1162105Y1215451D03*
X1158365Y1215452D03*
X1162105Y1211711D03*
X1165846D03*
X1188287Y1114468D03*
X1177066D03*
Y1118208D03*
X1184546Y1114468D03*
X1180806Y1129429D03*
X1177066D03*
X1188287D03*
X1180806Y1136909D03*
X1177066D03*
X1188287D03*
Y1140649D03*
X1180806Y1151869D03*
X1177066D03*
Y1144389D03*
X1180806D03*
Y1155610D03*
X1188287Y1144389D03*
X1180806Y1170570D03*
X1184546D03*
X1177066D03*
X1184546Y1166830D03*
X1180806D03*
X1177066Y1159350D03*
X1180806D03*
X1184546D03*
X1177066Y1185531D03*
Y1178051D03*
X1180806Y1185531D03*
Y1178051D03*
Y1174310D03*
X1184546Y1181791D03*
X1188287Y1185531D03*
Y1189271D03*
Y1178051D03*
X1180806Y1200491D03*
X1177066D03*
X1188287D03*
X1177066Y1193011D03*
X1180806D03*
X1188287D03*
Y1215452D03*
X1180806D03*
X1177066D03*
X1188287Y1211712D03*
X1199507Y1118208D03*
X1195767D03*
Y1114468D03*
X1192027D03*
X1199507D03*
Y1140649D03*
Y1136909D03*
X1203247Y1140649D03*
X1199507Y1155610D03*
X1192027D03*
X1203247Y1148129D03*
X1195767Y1144389D03*
X1199507Y1148129D03*
Y1144389D03*
Y1170570D03*
Y1166830D03*
Y1159350D03*
X1192027Y1166830D03*
Y1170570D03*
Y1159350D03*
X1203247Y1189271D03*
X1199507D03*
Y1174310D03*
X1195767Y1181791D03*
X1192027Y1174310D03*
X1199507Y1178051D03*
X1203247Y1181791D03*
X1199507Y1196751D03*
Y1204232D03*
X1195767Y1200491D03*
X1192027Y1196751D03*
Y1200491D03*
Y1204232D03*
X1199507Y1200491D03*
X1192027Y1215452D03*
X1199507Y1211712D03*
Y1215452D03*
Y1207972D03*
X1195767Y1215452D03*
X1192027Y1207972D03*
X1195767D03*
Y1211712D03*
X1206988Y1140649D03*
X1218208Y1144389D03*
Y1151869D03*
X1206988Y1155610D03*
Y1148129D03*
X1210728Y1155610D03*
X1221948Y1151869D03*
Y1144389D03*
X1218208Y1166830D03*
Y1159350D03*
X1221948Y1166830D03*
X1210728Y1170570D03*
X1206988D03*
X1218208Y1189271D03*
Y1174310D03*
X1221948Y1181791D03*
Y1174310D03*
X1218208Y1181791D03*
X1221948Y1189271D03*
X1236909Y1136909D03*
X1225688Y1140649D03*
X1229428D03*
X1236909Y1151870D03*
X1225688Y1148129D03*
X1229428D03*
X1225688Y1155610D03*
X1236909Y1144389D03*
X1229428Y1155610D03*
Y1170570D03*
X1225688D03*
X1236909Y1159350D03*
Y1181791D03*
X1225688Y1185531D03*
X1236909Y1189271D03*
X1229428Y1178051D03*
Y1185531D03*
X1236909Y1174310D03*
X1225688Y1178051D03*
Y1193011D03*
X1229428D03*
X1240649Y1136909D03*
Y1151870D03*
Y1144389D03*
Y1159350D03*
Y1174310D03*
Y1181791D03*
Y1189271D03*
X1339196Y441086D03*
Y433999D03*
Y437543D03*
X1336396Y441086D03*
Y433999D03*
Y437543D03*
X1339196Y444629D03*
X1336396D03*
X1415924Y620661D03*
Y617861D03*
X1423010Y620661D03*
X1419467Y617861D03*
X1423010D03*
X1426554Y620661D03*
Y617861D03*
X1419467Y620661D03*
X1514468Y1088287D03*
Y1099507D03*
Y1106988D03*
Y1121948D03*
Y1114468D03*
Y1129429D03*
Y1136909D03*
Y1148129D03*
Y1155610D03*
X1514467Y1170570D03*
Y1178051D03*
X1521949Y1073326D03*
X1529429D03*
Y1077066D03*
X1525689Y1084547D03*
X1529429Y1092027D03*
X1521949D03*
X1518208Y1088287D03*
X1525689Y1080807D03*
X1518208Y1099507D03*
X1525689D03*
X1529429Y1095767D03*
X1525689Y1103247D03*
X1518208Y1106988D03*
X1521949Y1095767D03*
Y1110728D03*
X1518208Y1114468D03*
X1525689Y1110728D03*
X1518208Y1121948D03*
X1521949Y1118208D03*
X1525689D03*
Y1125688D03*
X1518208Y1129429D03*
X1521949Y1125688D03*
X1518208Y1136909D03*
X1521949Y1133169D03*
X1518208Y1148129D03*
Y1155610D03*
X1518207Y1170570D03*
X1527559Y1176180D03*
X1518207Y1178051D03*
X1536909Y1073326D03*
X1533169Y1080807D03*
Y1084547D03*
X1540649Y1080807D03*
X1536909Y1077066D03*
X1540649Y1084547D03*
X1536909Y1092027D03*
Y1095767D03*
X1533169Y1099507D03*
X1540649Y1103247D03*
X1533169D03*
X1536909Y1118208D03*
X1533169D03*
Y1121948D03*
X1544389Y1114468D03*
X1536909Y1110728D03*
X1533169D03*
X1540649Y1114468D03*
X1536909Y1148129D03*
X1540649Y1151870D03*
Y1148129D03*
X1536909Y1144389D03*
Y1155610D03*
X1540649Y1159350D03*
Y1170570D03*
Y1174310D03*
Y1178050D03*
X1531299Y1176180D03*
X1559350Y1114468D03*
X1555610D03*
X1563090D03*
Y1140649D03*
Y1136909D03*
X1555610D03*
X1563090Y1129429D03*
Y1133169D03*
Y1144389D03*
Y1151869D03*
X1555610Y1144389D03*
X1548130Y1151870D03*
Y1148129D03*
Y1144389D03*
X1559350Y1155610D03*
X1555610Y1151870D03*
X1559350Y1148129D03*
X1563090Y1159350D03*
Y1170570D03*
X1548130Y1166830D03*
Y1159350D03*
X1555610Y1170570D03*
X1559350Y1166830D03*
X1555610Y1159350D03*
X1548130Y1174310D03*
Y1178051D03*
Y1181791D03*
X1563090Y1185531D03*
Y1178051D03*
X1555610Y1185531D03*
X1559350Y1174310D03*
Y1181791D03*
X1555610Y1178051D03*
X1563090Y1193011D03*
X1555610Y1215452D03*
X1563090D03*
X1559350D03*
X1574311Y1114468D03*
X1570571D03*
X1578051D03*
X1566830D03*
X1578051Y1136909D03*
X1574311D03*
X1570571D03*
X1574311Y1129429D03*
X1570571D03*
X1578051D03*
X1566830Y1140649D03*
X1578051Y1144389D03*
X1574311D03*
X1570571D03*
X1578051Y1151870D03*
X1574311D03*
X1570571D03*
X1574311Y1155610D03*
X1566830Y1148129D03*
Y1155610D03*
X1578051Y1170570D03*
X1574311Y1166830D03*
X1570571Y1170570D03*
X1566830Y1166830D03*
X1578051Y1159350D03*
X1570571D03*
X1574311Y1185531D03*
X1570571D03*
X1578051D03*
Y1178051D03*
X1574311D03*
X1570571D03*
X1574311Y1174310D03*
X1566830Y1181791D03*
Y1174310D03*
X1570571Y1193011D03*
X1574311D03*
X1578051D03*
X1570571Y1200491D03*
X1578051D03*
X1574311D03*
X1578051Y1215452D03*
X1566830D03*
X1570571Y1211712D03*
X1566830Y1219192D03*
X1574311Y1215452D03*
X1570571D03*
X1578051Y1211712D03*
X1574311D03*
X1593012Y1114468D03*
X1589271D03*
X1581791D03*
X1593011Y1136909D03*
X1589271D03*
X1585531D03*
X1581791D03*
X1589271Y1129429D03*
X1585531D03*
X1581791D03*
X1593011D03*
X1585531Y1144389D03*
X1581791D03*
X1593011D03*
X1589271D03*
X1593012Y1151870D03*
X1589271D03*
X1585531D03*
X1581791D03*
Y1155610D03*
X1589271D03*
X1593011Y1170570D03*
X1585531D03*
X1589271Y1166830D03*
X1581791D03*
X1585531Y1159350D03*
X1593011D03*
X1589271Y1185531D03*
X1585531D03*
X1581791D03*
X1593011D03*
X1581791Y1178051D03*
X1593011D03*
X1589271D03*
X1585531D03*
X1589271Y1174310D03*
X1581791D03*
X1585531Y1193011D03*
X1589271D03*
X1593011D03*
X1581791D03*
X1589271Y1200491D03*
X1585531D03*
X1581791D03*
X1593011D03*
X1593012Y1211712D03*
Y1215452D03*
X1581791D03*
X1589271D03*
X1585531D03*
Y1211712D03*
X1596752Y1114468D03*
X1607972D03*
X1611712Y1118208D03*
X1607972D03*
X1611712Y1114468D03*
X1600492Y1136909D03*
X1596752D03*
X1611712D03*
X1607972D03*
X1611712Y1129429D03*
X1607972D03*
X1600492D03*
X1596752D03*
X1600492Y1144389D03*
X1596752D03*
X1611712Y1151869D03*
X1607972D03*
X1611712Y1144389D03*
X1607972D03*
X1600492Y1151870D03*
X1596752D03*
Y1155610D03*
X1607972D03*
Y1166830D03*
X1611712Y1170570D03*
X1600492D03*
X1596752Y1166830D03*
X1611712Y1159350D03*
X1600492D03*
Y1185531D03*
X1596752D03*
X1600492Y1178051D03*
X1596752D03*
X1611712Y1185531D03*
X1607972D03*
X1611712Y1178051D03*
X1607972D03*
Y1174310D03*
X1596752D03*
X1607972Y1193011D03*
X1611712D03*
X1600492D03*
X1596752D03*
X1600492Y1200491D03*
X1596752D03*
X1611712D03*
X1607972D03*
X1600492Y1211712D03*
Y1215452D03*
X1596752Y1211712D03*
X1611712Y1215452D03*
X1607972D03*
Y1211712D03*
X1609842Y1217322D03*
X1615452Y1118208D03*
X1619193D03*
X1615452Y1114468D03*
X1619193D03*
X1622933D03*
X1626673D03*
Y1118208D03*
X1622933D03*
X1626673Y1136909D03*
X1622933D03*
X1615452D03*
X1619193D03*
X1626673Y1129429D03*
X1622933D03*
X1619193D03*
X1615452D03*
Y1151869D03*
X1619193D03*
X1626673D03*
X1622933D03*
Y1144389D03*
X1615452D03*
X1619193D03*
X1626673D03*
X1622933Y1155610D03*
X1615452D03*
Y1166830D03*
X1619193Y1170570D03*
X1626673Y1159350D03*
X1619193D03*
X1622933Y1166830D03*
X1626673Y1170570D03*
X1619193Y1185531D03*
X1626673D03*
X1622933D03*
Y1178051D03*
X1615452D03*
X1619193D03*
X1626673D03*
X1615452Y1185531D03*
X1622933Y1174310D03*
X1615452D03*
X1622933Y1193011D03*
X1626673D03*
X1615452D03*
X1619193D03*
X1622933Y1200491D03*
X1619193D03*
X1615452D03*
X1626673D03*
X1622933Y1215452D03*
X1619192Y1215451D03*
X1626673Y1215452D03*
X1615452D03*
X1613582Y1217322D03*
X1619192Y1211711D03*
X1622933D03*
X1637893Y1118208D03*
Y1114468D03*
X1634153D03*
X1630413D03*
X1641633D03*
X1634153Y1118208D03*
X1630413D03*
Y1136909D03*
X1637893D03*
X1634153D03*
X1630413Y1129429D03*
X1637893D03*
X1634153D03*
X1630413Y1151869D03*
X1637893D03*
X1634153D03*
Y1144389D03*
X1630413D03*
X1637893D03*
Y1155610D03*
X1630413D03*
X1637893Y1170570D03*
X1641633D03*
X1634153D03*
X1641633Y1166830D03*
X1637893D03*
Y1159350D03*
X1641633D03*
X1634153D03*
X1630413Y1166830D03*
X1641633Y1181791D03*
X1630413Y1185531D03*
X1634153D03*
X1630413Y1178051D03*
X1634153D03*
X1637893Y1185531D03*
Y1178051D03*
Y1174310D03*
X1630413D03*
X1634153Y1193011D03*
X1637893D03*
X1630413D03*
Y1200491D03*
X1637893D03*
X1634153D03*
X1630413Y1215452D03*
X1637893D03*
X1634153D03*
X1656594Y1118208D03*
X1652854D03*
Y1114468D03*
X1645374D03*
X1649114D03*
X1656594D03*
X1645374Y1129429D03*
Y1136909D03*
Y1140649D03*
X1656594Y1133169D03*
Y1140649D03*
Y1136909D03*
X1660334Y1140649D03*
X1649114Y1155610D03*
X1656594D03*
X1645374Y1144389D03*
X1660334Y1148129D03*
X1652854Y1144389D03*
X1656594Y1148129D03*
Y1144389D03*
X1649114Y1159350D03*
Y1170570D03*
Y1166830D03*
X1656594Y1170570D03*
Y1166830D03*
Y1159350D03*
Y1189271D03*
X1649114Y1174310D03*
X1656594D03*
X1652854Y1181791D03*
X1660334Y1189271D03*
X1645374Y1185531D03*
Y1189271D03*
X1660334Y1181791D03*
X1656594Y1178051D03*
X1645374D03*
Y1200491D03*
Y1193011D03*
X1656594Y1196751D03*
Y1204232D03*
X1652854Y1200491D03*
X1649114Y1204232D03*
Y1196751D03*
Y1200491D03*
X1656594D03*
X1645374Y1215452D03*
X1649114D03*
X1652854D03*
X1656594Y1211712D03*
X1645374D03*
X1656594Y1215452D03*
Y1207972D03*
X1649114D03*
X1652854D03*
Y1211712D03*
X1664075Y1140649D03*
X1667815Y1155610D03*
X1664075Y1148129D03*
Y1155610D03*
X1675295Y1144389D03*
Y1151869D03*
Y1166830D03*
Y1159350D03*
X1664075Y1170570D03*
X1667815D03*
X1675295Y1189271D03*
Y1174310D03*
Y1181791D03*
X1686515Y1140649D03*
X1682775D03*
X1679035Y1151869D03*
Y1144389D03*
X1682775Y1148129D03*
X1686515Y1155610D03*
Y1148129D03*
X1682775Y1155610D03*
X1679035Y1166830D03*
X1686515Y1170570D03*
X1682775D03*
X1679035Y1181791D03*
Y1189271D03*
Y1174310D03*
X1686515Y1185531D03*
X1682775Y1178051D03*
X1686515D03*
X1682775Y1185531D03*
X1686515Y1193011D03*
X1682775D03*
Y1222932D03*
X1693996Y1136909D03*
X1697736D03*
X1693996Y1151870D03*
X1697736D03*
X1693996Y1144389D03*
X1697736D03*
Y1159350D03*
X1693996D03*
X1697736Y1174310D03*
X1693996Y1189271D03*
X1697736D03*
Y1181791D03*
X1693996D03*
Y1174310D03*
X1796283Y441086D03*
Y433999D03*
Y437543D03*
X1793483Y441086D03*
Y433999D03*
Y437543D03*
X1796283Y444629D03*
X1793483D03*
G54D53*
X970071Y1365652D03*
Y1409152D03*
G54D33*
X109882Y1458622D03*
Y1463741D03*
Y1489331D03*
Y1494449D03*
Y1560985D03*
Y1566103D03*
Y1591693D03*
Y1596811D03*
Y1622402D03*
X127205Y1458622D03*
Y1463741D03*
X118543Y1452717D03*
Y1462953D03*
Y1468071D03*
X127205Y1489331D03*
Y1494449D03*
X118543Y1493662D03*
Y1498780D03*
X127205Y1560985D03*
Y1566103D03*
X118543Y1565315D03*
Y1570434D03*
X127205Y1591693D03*
X118543Y1596024D03*
X127205Y1596811D03*
X118543Y1601142D03*
X127205Y1622402D03*
X144528Y1458622D03*
Y1463741D03*
X135866Y1452717D03*
Y1462953D03*
Y1468071D03*
X144528Y1489331D03*
Y1494449D03*
X135866Y1493662D03*
Y1498780D03*
X144528Y1560985D03*
Y1566103D03*
X135866Y1565315D03*
Y1570434D03*
X144528Y1591693D03*
X135866Y1596024D03*
X144528Y1596811D03*
X135866Y1601142D03*
X144528Y1622402D03*
X161850Y1458622D03*
Y1463741D03*
X153189Y1452717D03*
Y1462953D03*
Y1468071D03*
X161850Y1489331D03*
Y1494449D03*
X153189Y1493662D03*
Y1498780D03*
X161850Y1560985D03*
Y1566103D03*
X153189Y1565315D03*
Y1570434D03*
X161850Y1591693D03*
X153189Y1596024D03*
X161850Y1596811D03*
X153189Y1601142D03*
X161850Y1622402D03*
X179173Y1458622D03*
Y1463741D03*
X170512Y1452717D03*
Y1462953D03*
X179173Y1473977D03*
Y1479095D03*
X170512Y1468071D03*
X179173Y1489331D03*
Y1494449D03*
X170512Y1493662D03*
Y1498780D03*
X179173Y1504685D03*
Y1509804D03*
Y1560985D03*
Y1566103D03*
Y1576339D03*
X170512Y1565315D03*
Y1570434D03*
X179173Y1581457D03*
Y1591693D03*
X170512Y1596024D03*
X179173Y1596811D03*
Y1607048D03*
Y1612166D03*
X170512Y1601142D03*
X179173Y1622402D03*
X187835Y1452717D03*
Y1462953D03*
Y1468071D03*
Y1478308D03*
Y1483426D03*
Y1493662D03*
Y1498780D03*
Y1509016D03*
Y1514134D03*
Y1565315D03*
Y1570434D03*
Y1580670D03*
Y1585788D03*
Y1596024D03*
Y1601142D03*
Y1611378D03*
Y1616496D03*
X291771Y1452717D03*
X283110Y1504685D03*
X291771Y1509016D03*
X283110Y1509804D03*
X291771Y1514134D03*
X283110Y1607048D03*
X291771Y1611378D03*
X283110Y1612166D03*
X291771Y1616496D03*
X283110Y1622402D03*
X309094Y1452717D03*
X300433Y1504685D03*
X309094Y1509016D03*
X300433Y1509804D03*
X309094Y1514134D03*
X300433Y1607048D03*
X309094Y1611378D03*
X300433Y1612166D03*
X309094Y1616496D03*
X300433Y1622402D03*
X326417Y1452717D03*
X317756Y1504685D03*
X326417Y1509016D03*
X317756Y1509804D03*
X326417Y1514134D03*
X317756Y1607048D03*
X326417Y1611378D03*
X317756Y1612166D03*
X326417Y1616496D03*
X317756Y1622402D03*
X343740Y1452717D03*
X335078Y1504685D03*
X343740Y1509016D03*
X335078Y1509804D03*
X343740Y1514134D03*
X335078Y1607048D03*
X343740Y1611378D03*
X335078Y1612166D03*
X343740Y1616496D03*
X335078Y1622402D03*
X361063Y1452717D03*
X352401Y1458622D03*
Y1463741D03*
X361063Y1462953D03*
Y1468071D03*
X352401Y1473977D03*
Y1479095D03*
X361063Y1478308D03*
Y1483426D03*
X352401Y1489331D03*
Y1494449D03*
X361063Y1493662D03*
Y1498780D03*
X352401Y1504685D03*
Y1509804D03*
X361063Y1509016D03*
Y1514134D03*
X352401Y1560985D03*
Y1566103D03*
X361063Y1565315D03*
Y1570434D03*
X352401Y1576339D03*
Y1581457D03*
X361063Y1580670D03*
Y1585788D03*
X352401Y1591693D03*
X361063Y1596024D03*
X352401Y1596811D03*
X361063Y1601142D03*
X352401Y1607048D03*
Y1612166D03*
X361063Y1611378D03*
Y1616496D03*
X352401Y1622402D03*
X456339Y1458622D03*
Y1463741D03*
Y1489331D03*
Y1494449D03*
Y1576339D03*
Y1581457D03*
Y1607048D03*
Y1612166D03*
Y1622402D03*
X473662Y1458622D03*
Y1463741D03*
X465000Y1452717D03*
Y1462953D03*
Y1468071D03*
X473662Y1489331D03*
Y1494449D03*
X465000Y1493662D03*
Y1498780D03*
X473662Y1576339D03*
Y1581457D03*
X465000Y1580670D03*
Y1585788D03*
X473662Y1607048D03*
Y1612166D03*
X465000Y1611378D03*
X473662Y1622402D03*
X465000Y1616496D03*
X490985Y1458622D03*
Y1463741D03*
X482323Y1452717D03*
Y1462953D03*
Y1468071D03*
X490985Y1489331D03*
Y1494449D03*
X482323Y1493662D03*
Y1498780D03*
X490985Y1576339D03*
Y1581457D03*
X482323Y1580670D03*
Y1585788D03*
X490985Y1607048D03*
Y1612166D03*
X482323Y1611378D03*
X490985Y1622402D03*
X482323Y1616496D03*
X499646Y1452717D03*
Y1462953D03*
Y1468071D03*
Y1493662D03*
Y1498780D03*
Y1580670D03*
Y1585788D03*
Y1611378D03*
Y1616496D03*
X516969Y1452717D03*
X508307Y1458622D03*
X516969Y1462953D03*
X508307Y1463741D03*
X516969Y1468071D03*
X508307Y1489331D03*
X516969Y1493662D03*
X508307Y1494449D03*
X516969Y1498780D03*
X508307Y1576339D03*
X516969Y1580670D03*
X508307Y1581457D03*
X516969Y1585788D03*
X508307Y1607048D03*
X516969Y1611378D03*
X508307Y1612166D03*
X516969Y1616496D03*
X508307Y1622402D03*
X534292Y1452717D03*
X525630Y1458622D03*
Y1463741D03*
X534292Y1462953D03*
Y1468071D03*
X525630Y1473977D03*
Y1479095D03*
X534292Y1478308D03*
Y1483426D03*
X525630Y1489331D03*
Y1494449D03*
X534292Y1493662D03*
Y1498780D03*
X525630Y1504685D03*
Y1509804D03*
X534292Y1509016D03*
Y1514134D03*
X525630Y1560985D03*
Y1566103D03*
X534292Y1565315D03*
Y1570434D03*
X525630Y1576339D03*
Y1581457D03*
X534292Y1580670D03*
Y1585788D03*
X525630Y1591693D03*
X534292Y1596024D03*
X525630Y1596811D03*
X534292Y1601142D03*
X525630Y1607048D03*
Y1612166D03*
X534292Y1611378D03*
Y1616496D03*
X525630Y1622402D03*
X629567Y1473977D03*
Y1479095D03*
Y1576339D03*
Y1581457D03*
Y1622402D03*
X638228Y1452717D03*
X646890Y1473977D03*
Y1479095D03*
X638228Y1478308D03*
Y1483426D03*
X646890Y1576339D03*
Y1581457D03*
X638228Y1580670D03*
Y1585788D03*
X646890Y1622402D03*
X655551Y1452717D03*
X664213Y1473977D03*
Y1479095D03*
X655551Y1478308D03*
Y1483426D03*
X664213Y1576339D03*
Y1581457D03*
X655551Y1580670D03*
Y1585788D03*
X664213Y1622402D03*
X672874Y1452717D03*
X681535Y1473977D03*
Y1479095D03*
X672874Y1478308D03*
Y1483426D03*
X681535Y1576339D03*
Y1581457D03*
X672874Y1580670D03*
Y1585788D03*
X681535Y1622402D03*
X698858Y1458622D03*
Y1463741D03*
X690197Y1452717D03*
X698858Y1473977D03*
Y1479095D03*
X690197Y1478308D03*
X698858Y1489331D03*
Y1494449D03*
X690197Y1483426D03*
X698858Y1504685D03*
Y1509804D03*
Y1560985D03*
Y1566103D03*
Y1576339D03*
Y1581457D03*
Y1591693D03*
X690197Y1580670D03*
Y1585788D03*
X698858Y1596811D03*
Y1607048D03*
Y1612166D03*
Y1622402D03*
X707520Y1452717D03*
Y1462953D03*
Y1468071D03*
Y1478308D03*
Y1483426D03*
Y1493662D03*
Y1498780D03*
Y1509016D03*
Y1514134D03*
Y1565315D03*
Y1570434D03*
Y1580670D03*
Y1585788D03*
Y1596024D03*
Y1601142D03*
Y1611378D03*
Y1616496D03*
X1140511Y1452717D03*
X1131850Y1458622D03*
X1140511Y1462953D03*
X1131850Y1463741D03*
X1140511Y1468071D03*
X1131850Y1489331D03*
X1140511Y1493662D03*
X1131850Y1494449D03*
X1140511Y1498780D03*
X1131850Y1560985D03*
X1140511Y1565315D03*
X1131850Y1566103D03*
X1140511Y1570434D03*
X1131850Y1591693D03*
X1140511Y1596024D03*
X1131850Y1596811D03*
X1140511Y1601142D03*
X1131850Y1622402D03*
X1149173Y1458622D03*
Y1463741D03*
Y1489331D03*
Y1494449D03*
Y1560985D03*
Y1566103D03*
Y1591693D03*
Y1596811D03*
Y1622402D03*
X1166496Y1458622D03*
Y1463741D03*
X1157834Y1452717D03*
Y1462953D03*
Y1468071D03*
X1166496Y1489331D03*
Y1494449D03*
X1157834Y1493662D03*
Y1498780D03*
X1166496Y1560985D03*
Y1566103D03*
X1157834Y1565315D03*
Y1570434D03*
X1166496Y1591693D03*
X1157834Y1596024D03*
X1166496Y1596811D03*
X1157834Y1601142D03*
X1166496Y1622402D03*
X1183818Y1458622D03*
Y1463741D03*
X1175157Y1452717D03*
Y1462953D03*
Y1468071D03*
X1183818Y1489331D03*
Y1494449D03*
X1175157Y1493662D03*
Y1498780D03*
X1183818Y1560985D03*
Y1566103D03*
X1175157Y1565315D03*
Y1570434D03*
X1183818Y1591693D03*
X1175157Y1596024D03*
X1183818Y1596811D03*
X1175157Y1601142D03*
X1183818Y1622402D03*
X1201141Y1458622D03*
Y1463741D03*
X1192480Y1452717D03*
Y1462953D03*
X1201141Y1473977D03*
Y1479095D03*
X1192480Y1468071D03*
X1201141Y1489331D03*
Y1494449D03*
X1192480Y1493662D03*
Y1498780D03*
X1201141Y1504685D03*
Y1509804D03*
Y1560985D03*
Y1566103D03*
Y1576339D03*
X1192480Y1565315D03*
Y1570434D03*
X1201141Y1581457D03*
Y1591693D03*
X1192480Y1596024D03*
X1201141Y1596811D03*
Y1607048D03*
Y1612166D03*
X1192480Y1601142D03*
X1201141Y1622402D03*
X1209803Y1452717D03*
Y1462953D03*
Y1468071D03*
Y1478308D03*
Y1483426D03*
Y1493662D03*
Y1498780D03*
Y1509016D03*
Y1514134D03*
Y1565315D03*
Y1570434D03*
Y1580670D03*
Y1585788D03*
Y1596024D03*
Y1601142D03*
Y1611378D03*
Y1616496D03*
X1313740Y1452717D03*
X1305079Y1504685D03*
X1313740Y1509016D03*
X1305079Y1509804D03*
X1313740Y1514134D03*
X1305079Y1607048D03*
X1313740Y1611378D03*
X1305079Y1612166D03*
X1313740Y1616496D03*
X1305079Y1622402D03*
X1331063Y1452717D03*
X1322402Y1504685D03*
X1331063Y1509016D03*
X1322402Y1509804D03*
X1331063Y1514134D03*
X1322402Y1607048D03*
X1331063Y1611378D03*
X1322402Y1612166D03*
X1331063Y1616496D03*
X1322402Y1622402D03*
X1348386Y1452717D03*
X1339725Y1504685D03*
X1348386Y1509016D03*
X1339725Y1509804D03*
X1348386Y1514134D03*
X1339725Y1607048D03*
X1348386Y1611378D03*
X1339725Y1612166D03*
X1348386Y1616496D03*
X1339725Y1622402D03*
X1365709Y1452717D03*
X1357047Y1504685D03*
X1365709Y1509016D03*
X1357047Y1509804D03*
X1365709Y1514134D03*
X1357047Y1607048D03*
X1365709Y1611378D03*
X1357047Y1612166D03*
X1365709Y1616496D03*
X1357047Y1622402D03*
X1383032Y1452717D03*
X1374370Y1458622D03*
Y1463741D03*
X1383032Y1462953D03*
Y1468071D03*
X1374370Y1473977D03*
Y1479095D03*
X1383032Y1478308D03*
Y1483426D03*
X1374370Y1489331D03*
Y1494449D03*
X1383032Y1493662D03*
Y1498780D03*
X1374370Y1504685D03*
Y1509804D03*
X1383032Y1509016D03*
Y1514134D03*
X1374370Y1560985D03*
Y1566103D03*
X1383032Y1565315D03*
Y1570434D03*
X1374370Y1576339D03*
Y1581457D03*
X1383032Y1580670D03*
Y1585788D03*
X1374370Y1591693D03*
X1383032Y1596024D03*
X1374370Y1596811D03*
X1383032Y1601142D03*
X1374370Y1607048D03*
Y1612166D03*
X1383032Y1611378D03*
Y1616496D03*
X1374370Y1622402D03*
X1478307Y1458622D03*
Y1463741D03*
Y1489331D03*
Y1494449D03*
Y1576339D03*
Y1581457D03*
Y1607048D03*
Y1612166D03*
Y1622402D03*
X1495630Y1458622D03*
Y1463741D03*
X1486968Y1452717D03*
Y1462953D03*
Y1468071D03*
X1495630Y1489331D03*
Y1494449D03*
X1486968Y1493662D03*
Y1498780D03*
X1495630Y1576339D03*
Y1581457D03*
X1486968Y1580670D03*
Y1585788D03*
X1495630Y1607048D03*
Y1612166D03*
X1486968Y1611378D03*
X1495630Y1622402D03*
X1486968Y1616496D03*
X1512953Y1458622D03*
Y1463741D03*
X1504291Y1452717D03*
Y1462953D03*
Y1468071D03*
X1512953Y1489331D03*
Y1494449D03*
X1504291Y1493662D03*
Y1498780D03*
X1512953Y1576339D03*
Y1581457D03*
X1504291Y1580670D03*
Y1585788D03*
X1512953Y1607048D03*
Y1612166D03*
X1504291Y1611378D03*
X1512953Y1622402D03*
X1504291Y1616496D03*
X1530275Y1458622D03*
Y1463741D03*
X1521614Y1452717D03*
Y1462953D03*
Y1468071D03*
X1530275Y1489331D03*
Y1494449D03*
X1521614Y1493662D03*
Y1498780D03*
X1530275Y1576339D03*
Y1581457D03*
X1521614Y1580670D03*
Y1585788D03*
X1530275Y1607048D03*
Y1612166D03*
X1521614Y1611378D03*
X1530275Y1622402D03*
X1521614Y1616496D03*
X1538937Y1452717D03*
Y1462953D03*
Y1468071D03*
Y1493662D03*
Y1498780D03*
Y1580670D03*
Y1585788D03*
Y1611378D03*
Y1616496D03*
X1556260Y1452717D03*
X1547598Y1458622D03*
Y1463741D03*
X1556260Y1462953D03*
Y1468071D03*
X1547598Y1473977D03*
Y1479095D03*
X1556260Y1478308D03*
Y1483426D03*
X1547598Y1489331D03*
Y1494449D03*
X1556260Y1493662D03*
Y1498780D03*
X1547598Y1504685D03*
Y1509804D03*
X1556260Y1509016D03*
Y1514134D03*
X1547598Y1560985D03*
Y1566103D03*
X1556260Y1565315D03*
Y1570434D03*
X1547598Y1576339D03*
Y1581457D03*
X1556260Y1580670D03*
Y1585788D03*
X1547598Y1591693D03*
X1556260Y1596024D03*
X1547598Y1596811D03*
X1556260Y1601142D03*
X1547598Y1607048D03*
Y1612166D03*
X1556260Y1611378D03*
Y1616496D03*
X1547598Y1622402D03*
X1660196Y1452717D03*
X1651535Y1473977D03*
X1660196Y1478308D03*
X1651535Y1479095D03*
X1660196Y1483426D03*
X1651535Y1576339D03*
X1660196Y1580670D03*
X1651535Y1581457D03*
X1660196Y1585788D03*
X1651535Y1622402D03*
X1668858Y1473977D03*
Y1479095D03*
Y1576339D03*
Y1581457D03*
Y1622402D03*
X1677519Y1452717D03*
X1686181Y1473977D03*
Y1479095D03*
X1677519Y1478308D03*
Y1483426D03*
X1686181Y1576339D03*
Y1581457D03*
X1677519Y1580670D03*
Y1585788D03*
X1686181Y1622402D03*
X1694842Y1452717D03*
X1703503Y1473977D03*
Y1479095D03*
X1694842Y1478308D03*
Y1483426D03*
X1703503Y1576339D03*
Y1581457D03*
X1694842Y1580670D03*
Y1585788D03*
X1703503Y1622402D03*
X1720826Y1458622D03*
Y1463741D03*
X1712165Y1452717D03*
X1720826Y1473977D03*
Y1479095D03*
X1712165Y1478308D03*
X1720826Y1489331D03*
Y1494449D03*
X1712165Y1483426D03*
X1720826Y1504685D03*
Y1509804D03*
Y1560985D03*
Y1566103D03*
Y1576339D03*
Y1581457D03*
Y1591693D03*
X1712165Y1580670D03*
Y1585788D03*
X1720826Y1596811D03*
Y1607048D03*
Y1612166D03*
Y1622402D03*
X1729488Y1452717D03*
Y1462953D03*
Y1468071D03*
Y1478308D03*
Y1483426D03*
Y1493662D03*
Y1498780D03*
Y1509016D03*
Y1514134D03*
Y1565315D03*
Y1570434D03*
Y1580670D03*
Y1585788D03*
Y1596024D03*
Y1601142D03*
Y1611378D03*
Y1616496D03*
G54D54*
X1030635Y754546D03*
Y774546D03*
Y784546D03*
Y794546D03*
Y804546D03*
Y814546D03*
Y824546D03*
G54D28*
X76112Y1348187D03*
X79512D03*
X76112Y1360099D03*
X79512D03*
X100592Y1348187D03*
Y1360099D03*
X91752Y1372385D03*
X88352D03*
Y1384297D03*
X91752D03*
X100592Y1396583D03*
Y1408495D03*
X103992Y1348187D03*
Y1360099D03*
X112832Y1384297D03*
X116232Y1372385D03*
Y1384297D03*
X112832Y1372385D03*
X103992Y1396583D03*
Y1408495D03*
X125072Y1348187D03*
X128472D03*
Y1360099D03*
X125072D03*
Y1396583D03*
X128472D03*
X125072Y1408495D03*
X128472D03*
X149552Y1348187D03*
Y1360099D03*
X140712Y1372385D03*
Y1384297D03*
X137312D03*
Y1372385D03*
X149552Y1396583D03*
Y1408495D03*
X152952Y1348187D03*
Y1360099D03*
X161792Y1384297D03*
X165192Y1372385D03*
Y1384297D03*
X161792Y1372385D03*
X152952Y1396583D03*
Y1408495D03*
X177432Y1348187D03*
X174032D03*
Y1360099D03*
X177432D03*
Y1396583D03*
X174032D03*
X177432Y1408495D03*
X174032D03*
X198512Y1348187D03*
Y1360099D03*
X186272Y1384297D03*
X189672D03*
Y1372385D03*
X186272D03*
X198512Y1396583D03*
Y1408495D03*
X201912Y1348187D03*
Y1360099D03*
Y1396583D03*
Y1408495D03*
X241623Y1348187D03*
X245023D03*
Y1360099D03*
X241623D03*
X253863Y1372385D03*
X257263D03*
X253863Y1384297D03*
X257263D03*
X281594Y1211712D03*
X270374Y1215452D03*
X269503Y1348187D03*
X266103D03*
Y1360099D03*
X269503D03*
X278343Y1372385D03*
Y1384297D03*
X269503Y1396583D03*
X266103D03*
X269503Y1408495D03*
X266103D03*
X293983Y1348187D03*
X290583D03*
X293983Y1360099D03*
X290583D03*
X281743Y1372385D03*
Y1384297D03*
X293983Y1396583D03*
X290583D03*
X293983Y1408495D03*
X290583D03*
X306223Y1372385D03*
X302823D03*
X306223Y1384297D03*
X302823D03*
X315063Y1348187D03*
X318463D03*
X315063Y1360099D03*
X318463D03*
X327303Y1372385D03*
Y1384297D03*
X315063Y1396583D03*
X318463D03*
Y1408495D03*
X315063D03*
X339543Y1348187D03*
X342943D03*
Y1360099D03*
X339543D03*
X330703Y1372385D03*
Y1384297D03*
X339543Y1396583D03*
X342943D03*
Y1408495D03*
X339543D03*
X351783Y1372385D03*
X355183D03*
Y1384297D03*
X351783D03*
X364023Y1348187D03*
X367423D03*
Y1360099D03*
X364023D03*
Y1396583D03*
X367423D03*
X364023Y1408495D03*
X367423D03*
X393094Y1423600D03*
X395894D03*
X440402Y1348187D03*
Y1360099D03*
X443802Y1348187D03*
Y1360099D03*
X452642Y1372385D03*
X456042D03*
X452642Y1384297D03*
X456042D03*
X468282Y1348187D03*
X464882D03*
X468282Y1360099D03*
X464882D03*
X468282Y1396583D03*
X464882D03*
Y1408495D03*
X468282D03*
X489362Y1348187D03*
Y1360099D03*
X477122Y1372385D03*
X480522D03*
Y1384297D03*
X477122D03*
X489362Y1396583D03*
Y1408495D03*
X492762Y1348187D03*
Y1360099D03*
X505002Y1372385D03*
X501602D03*
X505002Y1384297D03*
X501602D03*
X492762Y1396583D03*
Y1408495D03*
X517242Y1348187D03*
X513842D03*
Y1360099D03*
X517242D03*
Y1396583D03*
X513842D03*
X517242Y1408495D03*
X513842D03*
X538322Y1348187D03*
Y1360099D03*
X529482Y1372385D03*
Y1384297D03*
X526082Y1372385D03*
Y1384297D03*
X538322Y1396583D03*
Y1408495D03*
X541722Y1348187D03*
Y1360099D03*
X550562Y1372385D03*
X553962Y1384297D03*
X550562D03*
X553962Y1372385D03*
X541722Y1396583D03*
Y1408495D03*
X562802Y1348187D03*
X566202D03*
Y1360099D03*
X562802D03*
X566202Y1396583D03*
X562802D03*
X566202Y1408495D03*
X562802D03*
X629688Y1396583D03*
X626288D03*
Y1408495D03*
X629688D03*
X650768Y1384297D03*
Y1372385D03*
X641928Y1396583D03*
X638528D03*
Y1408495D03*
X641928D03*
X666408Y1348187D03*
X663008D03*
X666408Y1360099D03*
X663008D03*
X654168Y1384297D03*
Y1372385D03*
X666408Y1396583D03*
X663008D03*
X666408Y1408495D03*
X663008D03*
X675248Y1384297D03*
X678648D03*
Y1372385D03*
X675248D03*
X690888Y1348187D03*
X687488D03*
Y1360099D03*
X690888D03*
X699728Y1372385D03*
Y1384297D03*
X690888Y1396583D03*
X687488D03*
Y1408495D03*
X690888D03*
X715368Y1348187D03*
X711968D03*
X715368Y1360099D03*
X711968D03*
X703128Y1372385D03*
Y1384297D03*
X715368Y1396583D03*
X711968D03*
X715368Y1408495D03*
X711968D03*
X724208Y1372385D03*
Y1384297D03*
X727608D03*
Y1372385D03*
X739848Y1348187D03*
X736448D03*
Y1360099D03*
X739848D03*
X748688Y1372385D03*
Y1384297D03*
X739848Y1396489D03*
X736448D03*
X739848Y1408401D03*
X736448D03*
X760928Y1348187D03*
X764328D03*
Y1360099D03*
X760928D03*
X752088Y1372385D03*
Y1384297D03*
X878220Y848442D03*
Y845293D03*
Y835844D03*
Y851592D03*
X877800Y876500D03*
X897118Y848442D03*
X881370Y835844D03*
X893968Y845293D03*
X884519Y848442D03*
X897118Y842143D03*
X893968D03*
X887669Y848442D03*
X886093Y835318D03*
X897118Y845293D03*
X893968Y838994D03*
X890818Y842143D03*
X893968Y835846D03*
X887669Y845293D03*
X890818D03*
X893968Y848442D03*
X884519Y845293D03*
X881370D03*
X884519Y842143D03*
X887669D03*
X881370Y848442D03*
X890818D03*
X887669Y851592D03*
X890818Y854742D03*
X887669D03*
X897118Y851592D03*
X890818Y864189D03*
Y857891D03*
X887669Y864189D03*
X884519Y854742D03*
Y851592D03*
Y857891D03*
X887669D03*
X890818Y851592D03*
X893967Y851591D03*
X881370Y851592D03*
X887669Y867338D03*
X890818Y870488D03*
X887669D03*
X897118Y876787D03*
X890818Y867338D03*
X881370D03*
X897118Y879937D03*
X884519Y873638D03*
X887669D03*
X884519Y876787D03*
X890818Y879937D03*
X881370Y876787D03*
X887669Y879937D03*
X884519Y867338D03*
X890818Y873638D03*
X893968Y876787D03*
Y879937D03*
X890818Y876787D03*
X884519Y879937D03*
Y870488D03*
X881370D03*
Y883086D03*
X884585Y886354D03*
X885126Y889742D03*
X881370Y886236D03*
X906565Y848442D03*
X900267D03*
X906565Y838994D03*
X900267Y838992D03*
X909714Y848442D03*
X906565Y842143D03*
X900267Y845293D03*
Y842143D03*
X906565Y845293D03*
X900266Y835844D03*
X900267Y851592D03*
X906565D03*
X909714D03*
Y876787D03*
X900267Y879937D03*
Y876787D03*
X906565D03*
X912864Y873638D03*
Y879937D03*
X909714D03*
X906565D03*
X912864Y876787D03*
X922313Y845293D03*
X916014Y848442D03*
Y842143D03*
X919163Y845293D03*
X922313Y842143D03*
X916014Y845293D03*
X919163Y835844D03*
Y838994D03*
Y842143D03*
X925462Y845293D03*
X919163Y854742D03*
Y857891D03*
X922313Y854742D03*
X916014Y857891D03*
Y854742D03*
Y851592D03*
Y864189D03*
X925462Y851592D03*
X922313Y864189D03*
Y857891D03*
X925462D03*
X928612Y864189D03*
X919163D03*
X925462D03*
X916014Y870488D03*
X925462Y873638D03*
X922313Y876787D03*
X928612Y870488D03*
X925462D03*
X916014Y873638D03*
X922313D03*
X916014Y876787D03*
X928612Y873638D03*
X925462Y876787D03*
X928612D03*
Y879937D03*
X916014D03*
X922313D03*
X919163D03*
X925462D03*
X916014Y867338D03*
X919163Y873638D03*
Y870488D03*
X922313D03*
X919163Y876787D03*
X922313Y867338D03*
X919163D03*
X925462D03*
X922313Y883086D03*
Y886236D03*
X925462D03*
X919163Y883086D03*
X928612Y886236D03*
X925462Y883086D03*
X928612D03*
X1058113Y1348187D03*
X1054713D03*
X1058113Y1360099D03*
X1054713D03*
X1066953Y1384297D03*
Y1372385D03*
X1070353D03*
Y1384297D03*
X1082593Y1348187D03*
X1079193D03*
X1082593Y1360099D03*
X1079193D03*
X1091433Y1384297D03*
Y1372385D03*
X1082593Y1396583D03*
X1079193D03*
X1082593Y1408495D03*
X1079193D03*
X1107073Y1348187D03*
X1103673D03*
Y1360099D03*
X1107073D03*
X1094833Y1384297D03*
Y1372385D03*
X1107073Y1396583D03*
X1103673D03*
X1107073Y1408495D03*
X1103673D03*
X1119313Y1384297D03*
X1115913Y1372385D03*
X1119313D03*
X1115913Y1384297D03*
X1131553Y1348187D03*
X1128153D03*
X1131553Y1360099D03*
X1128153D03*
X1140393Y1384297D03*
Y1372385D03*
X1131553Y1396583D03*
X1128153D03*
Y1408495D03*
X1131553D03*
X1156033Y1348187D03*
X1152633D03*
Y1360099D03*
X1156033D03*
X1143793Y1372385D03*
Y1384297D03*
X1156033Y1396583D03*
X1152633D03*
Y1408495D03*
X1156033D03*
X1168273Y1384297D03*
X1164873D03*
X1168273Y1372385D03*
X1164873D03*
X1184547Y1215452D03*
X1177113Y1348187D03*
X1180513D03*
X1177113Y1360099D03*
X1180513D03*
Y1396583D03*
X1177113D03*
Y1408495D03*
X1180513D03*
X1230326Y1348187D03*
X1233726D03*
X1230326Y1360099D03*
X1233726D03*
X1254806Y1348187D03*
Y1360099D03*
X1242566Y1372385D03*
X1245966D03*
X1242566Y1384297D03*
X1245966D03*
X1254806Y1396583D03*
Y1408495D03*
X1258206Y1348187D03*
Y1360099D03*
X1270446Y1372385D03*
X1267046D03*
X1270446Y1384297D03*
X1267046D03*
X1258206Y1396583D03*
Y1408495D03*
X1282686Y1348187D03*
X1279286D03*
Y1360099D03*
X1282686D03*
X1279286Y1396583D03*
X1282686D03*
X1279286Y1408495D03*
X1282686D03*
X1291526Y1372385D03*
X1294926D03*
X1291526Y1384297D03*
X1294926D03*
X1316906Y829871D03*
Y833021D03*
Y848769D03*
X1313756Y833021D03*
Y836170D03*
X1316906Y839320D03*
X1310555Y848675D03*
X1313756Y848769D03*
X1316906Y836170D03*
X1313756Y842470D03*
Y858218D03*
X1316906Y855068D03*
X1313756Y855066D03*
X1316906Y858218D03*
X1307166Y1348187D03*
X1303766D03*
X1307166Y1360099D03*
X1303766D03*
X1316006Y1372385D03*
X1319406D03*
X1316006Y1384297D03*
X1319406D03*
X1303766Y1396583D03*
X1307166D03*
Y1408495D03*
X1303766D03*
X1335803Y829871D03*
X1323205D03*
X1326355Y839320D03*
X1335803D03*
X1329504Y833021D03*
X1332654Y842470D03*
X1329504Y845619D03*
X1332654D03*
X1326355Y836170D03*
X1335803Y842470D03*
X1329504Y836170D03*
X1335803Y845619D03*
Y848769D03*
X1329504Y839320D03*
X1323205Y836170D03*
X1335803D03*
X1329504Y842470D03*
X1335803Y833021D03*
X1323205D03*
X1320055Y845619D03*
X1326355D03*
X1320055Y836170D03*
X1326355Y842470D03*
X1320055Y848769D03*
X1323205Y845619D03*
X1332654Y848769D03*
X1320055Y839320D03*
X1326355Y848769D03*
X1323205D03*
X1329504D03*
X1323204Y839319D03*
X1332654Y839320D03*
X1320055Y842470D03*
X1323205D03*
X1329504Y855068D03*
Y858218D03*
X1320055Y851918D03*
X1332654Y855068D03*
X1326355D03*
Y858218D03*
X1329504Y861367D03*
X1323205Y858218D03*
X1320055D03*
X1332654Y861367D03*
X1329504Y851918D03*
X1323205D03*
X1326355Y861367D03*
X1320055Y855068D03*
X1332654Y858218D03*
X1335803Y855068D03*
Y858218D03*
Y861367D03*
X1320055D03*
X1323204Y855067D03*
X1326355Y851918D03*
X1332654D03*
X1326355Y880263D03*
X1329504Y877114D03*
X1335803Y880263D03*
X1326355Y867665D03*
Y870814D03*
X1323205D03*
X1320055D03*
X1329504Y867665D03*
X1326355Y873964D03*
X1332654Y880263D03*
X1329504D03*
X1332654Y877114D03*
X1326355D03*
X1329504Y870814D03*
X1320055Y873964D03*
X1332654Y870814D03*
X1323204Y873965D03*
X1332654Y867665D03*
X1320055Y880263D03*
Y867665D03*
X1323205Y880263D03*
Y877114D03*
X1320055D03*
X1335803Y867665D03*
Y873964D03*
Y870814D03*
X1332654Y873964D03*
X1329504D03*
X1323205Y867665D03*
Y886562D03*
X1326355Y889712D03*
X1335803Y883413D03*
X1329504Y892862D03*
X1332654Y889712D03*
X1335803Y892862D03*
Y889712D03*
X1326355Y892862D03*
X1329504Y889712D03*
X1320055Y892862D03*
X1323205D03*
X1329504Y886562D03*
X1332654Y883413D03*
X1320055Y886562D03*
X1326355Y883413D03*
X1323205D03*
X1332654Y892862D03*
X1320055Y883413D03*
X1332654Y886562D03*
X1335803D03*
X1320055Y889712D03*
X1323204Y889713D03*
X1329504Y883413D03*
X1328246Y1348187D03*
X1331646D03*
X1328246Y1360099D03*
X1331646D03*
Y1396583D03*
X1328246D03*
X1331646Y1408495D03*
X1328246D03*
X1342103Y845619D03*
X1345252Y836170D03*
X1338953Y845619D03*
X1345252Y833021D03*
X1342103Y836170D03*
X1351550D03*
X1342103Y842470D03*
X1345252Y845619D03*
X1342103Y839320D03*
X1338953Y848769D03*
X1338952Y839319D03*
X1345252Y842470D03*
X1342103Y848769D03*
X1338953Y842470D03*
X1345252Y848769D03*
X1338953Y836170D03*
X1351550Y842470D03*
Y848769D03*
Y845619D03*
X1345252Y839320D03*
X1351550Y858218D03*
X1345252D03*
Y861367D03*
X1342103Y858218D03*
X1351550Y861367D03*
X1338953Y851918D03*
X1342103D03*
X1345252D03*
X1351550D03*
X1338953Y880263D03*
X1351550D03*
X1345252D03*
X1342103Y870814D03*
X1345252D03*
Y867665D03*
X1351550Y870814D03*
Y867665D03*
X1338953Y877114D03*
X1345252D03*
X1351550D03*
X1342103Y880263D03*
X1338953Y883413D03*
X1345252Y889712D03*
Y886562D03*
X1342103Y883413D03*
X1345252D03*
X1338952Y889713D03*
X1338953Y892862D03*
X1342103Y886562D03*
Y892862D03*
Y889712D03*
X1338953Y886562D03*
X1351550Y883413D03*
Y889712D03*
Y886562D03*
Y892862D03*
X1343886Y1372385D03*
X1340486D03*
Y1384297D03*
X1343886D03*
X1364148Y829871D03*
X1367298D03*
X1359425Y829000D03*
X1354699Y842470D03*
Y848769D03*
X1357849D03*
X1364148Y845619D03*
X1354699Y836170D03*
X1357849Y833021D03*
X1367298Y845619D03*
X1364148Y842470D03*
X1357850Y839319D03*
X1357849Y836170D03*
X1360999Y842470D03*
X1354699Y845619D03*
X1357849D03*
X1360999Y839320D03*
X1367298Y842470D03*
X1360999Y848769D03*
Y845619D03*
X1367298Y833021D03*
X1354699Y839320D03*
X1360999Y836170D03*
X1367298Y848769D03*
X1364148Y839320D03*
X1357849Y842470D03*
X1364148Y833021D03*
X1367298Y836170D03*
Y839320D03*
X1364148Y848769D03*
Y851918D03*
X1367298Y861367D03*
X1364148Y858218D03*
Y855068D03*
Y861367D03*
X1367298Y858218D03*
Y851918D03*
X1354699Y858218D03*
X1367298Y855068D03*
X1360999D03*
Y858218D03*
Y861367D03*
X1354699Y851918D03*
X1357849D03*
X1364148Y867665D03*
X1367298Y877114D03*
X1364148Y870814D03*
X1367298Y873964D03*
X1364148D03*
Y877114D03*
X1367298Y870814D03*
X1364148Y880263D03*
X1367298D03*
X1357849D03*
X1360999D03*
X1367298Y867665D03*
X1354699Y870814D03*
X1357849Y877114D03*
X1354699Y880263D03*
X1360999Y867665D03*
Y870814D03*
Y873964D03*
X1367298Y883413D03*
X1354699Y892862D03*
X1360999D03*
X1367298D03*
X1360999Y883413D03*
X1357850Y889713D03*
X1364148Y889712D03*
X1357849Y883413D03*
X1367298Y889712D03*
X1354699D03*
X1357849Y886562D03*
X1364148D03*
X1357849Y892862D03*
X1360999Y889712D03*
X1354699Y883413D03*
X1360999Y886562D03*
X1364148Y892862D03*
Y883413D03*
X1367298Y886562D03*
X1354699D03*
X1356126Y1348187D03*
X1352726D03*
X1356126Y1360099D03*
X1352726D03*
X1356126Y1396583D03*
X1352726D03*
Y1408495D03*
X1356126D03*
X1370447Y829871D03*
Y839320D03*
X1383046Y845619D03*
X1379896D03*
X1373597D03*
Y842470D03*
X1370447Y848769D03*
X1379896D03*
Y839320D03*
X1373597Y848769D03*
X1376747D03*
X1373597Y833021D03*
X1370447D03*
X1373597Y836170D03*
X1370447D03*
X1373598Y839319D03*
X1370447Y842470D03*
Y845619D03*
X1383046Y842470D03*
X1376747Y836170D03*
Y842470D03*
X1379896Y833021D03*
X1383046Y839320D03*
X1376747Y845619D03*
Y839320D03*
X1379896Y855068D03*
Y861367D03*
X1376747Y858218D03*
Y851918D03*
X1373597Y861367D03*
X1376747Y855068D03*
X1373597Y858218D03*
X1376747Y861367D03*
X1383046Y851918D03*
X1373597D03*
X1373598Y855067D03*
X1379896Y851918D03*
X1370447D03*
Y858218D03*
X1383046D03*
Y861367D03*
X1370447Y855068D03*
Y861367D03*
X1383046Y873964D03*
X1376747Y880263D03*
X1370447Y877114D03*
X1373598Y873965D03*
X1370447Y873964D03*
X1379896Y877114D03*
X1373597Y880263D03*
X1383046Y877114D03*
X1370447Y880263D03*
X1376747Y873964D03*
X1383046Y880263D03*
X1370447Y870814D03*
X1376747D03*
X1373597D03*
X1376747Y867665D03*
Y877114D03*
X1373597Y867665D03*
X1379896D03*
X1383046Y870814D03*
X1379896Y880263D03*
X1373597Y877114D03*
X1379896Y873964D03*
X1383046Y892862D03*
X1379896Y886562D03*
X1370447Y883413D03*
X1373598Y889713D03*
X1376747Y886562D03*
X1383046Y883413D03*
X1376747Y889712D03*
X1383046D03*
X1379896D03*
X1373597Y883413D03*
Y886562D03*
X1370447Y892862D03*
X1376747D03*
X1370447Y889712D03*
X1373597Y892862D03*
X1383046Y886562D03*
X1379896Y892862D03*
X1376747Y883413D03*
X1464770Y1348187D03*
X1461370D03*
X1464770Y1360099D03*
X1461370D03*
X1473610Y1372385D03*
X1477010D03*
X1473610Y1384297D03*
X1477010D03*
X1489250Y1348187D03*
X1485850D03*
Y1360099D03*
X1489250D03*
X1498090Y1372385D03*
Y1384297D03*
X1485850Y1396583D03*
X1489250D03*
Y1408495D03*
X1485850D03*
X1513730Y1348187D03*
X1510330D03*
Y1360099D03*
X1513730D03*
X1501490Y1372385D03*
Y1384297D03*
X1510330Y1396583D03*
X1513730D03*
X1510330Y1408495D03*
X1513730D03*
X1525970Y1372385D03*
X1522570D03*
X1525970Y1384297D03*
X1522570D03*
X1538210Y1348187D03*
X1534810D03*
X1538210Y1360099D03*
X1534810D03*
X1547050Y1372385D03*
Y1384297D03*
X1538210Y1396583D03*
X1534810D03*
X1538210Y1408495D03*
X1534810D03*
X1559290Y1348187D03*
X1562690D03*
X1559290Y1360099D03*
X1562690D03*
X1550450Y1372385D03*
Y1384297D03*
X1562690Y1396583D03*
X1559290D03*
Y1408495D03*
X1562690D03*
X1574930Y1372385D03*
X1571530D03*
Y1384297D03*
X1574930D03*
X1587170Y1348187D03*
X1583770D03*
X1587170Y1360099D03*
X1583770D03*
Y1396583D03*
X1587170D03*
X1583770Y1408495D03*
X1587170D03*
X1611398Y1348187D03*
Y1360099D03*
X1614798Y1348187D03*
Y1360099D03*
X1627038Y1372385D03*
X1623638D03*
X1627038Y1384297D03*
X1623638D03*
X1641634Y1215452D03*
X1639278Y1348187D03*
X1635878D03*
X1639278Y1360099D03*
X1635878D03*
X1639278Y1396583D03*
X1635878D03*
Y1408495D03*
X1639278D03*
X1660358Y1348187D03*
Y1360099D03*
X1648118Y1372385D03*
X1651518D03*
X1648118Y1384297D03*
X1651518D03*
X1660358Y1396583D03*
Y1408495D03*
X1663758Y1348187D03*
Y1360099D03*
X1675998Y1372385D03*
X1672598D03*
Y1384297D03*
X1675998D03*
X1663758Y1396583D03*
Y1408495D03*
X1688238Y1348187D03*
X1684838D03*
X1688238Y1360099D03*
X1684838D03*
Y1396583D03*
X1688238D03*
Y1408495D03*
X1684838D03*
X1709318Y1348187D03*
Y1360099D03*
X1697078Y1372385D03*
X1700478D03*
X1697078Y1384297D03*
X1700478D03*
X1709318Y1396583D03*
Y1408495D03*
X1712718Y1348187D03*
Y1360099D03*
X1721558Y1372385D03*
X1724958D03*
Y1384297D03*
X1721558D03*
X1712718Y1396583D03*
Y1408495D03*
X1733798Y1348187D03*
X1737198D03*
X1733798Y1360099D03*
X1737198D03*
Y1396583D03*
X1733798D03*
X1737198Y1408495D03*
X1733798D03*
G54D29*
X116731Y1052235D03*
X106619Y1056423D03*
X102431Y1066535D03*
X106619Y1076647D03*
X116731Y1080835D03*
Y1249086D03*
X106619Y1253274D03*
X102431Y1263386D03*
X106619Y1273498D03*
X116731Y1277686D03*
X126843Y1056423D03*
Y1076647D03*
X131031Y1066535D03*
X126843Y1253274D03*
X131031Y1263386D03*
X126843Y1273498D03*
X342840Y1056423D03*
X338652Y1066535D03*
X342840Y1076647D03*
Y1253274D03*
X338652Y1263386D03*
X342840Y1273498D03*
X352952Y1052235D03*
Y1080835D03*
Y1249086D03*
Y1277686D03*
X363064Y1056423D03*
Y1076647D03*
X367252Y1066535D03*
X363064Y1253274D03*
X367252Y1263386D03*
X363064Y1273498D03*
X563706Y1056423D03*
X559518Y1066535D03*
X563706Y1076647D03*
Y1253274D03*
X559518Y1263386D03*
X563706Y1273498D03*
X583930Y1056423D03*
X573818Y1052235D03*
X583930Y1076647D03*
X588118Y1066535D03*
X573818Y1080835D03*
X583930Y1253274D03*
X573818Y1249086D03*
X588118Y1263386D03*
X573818Y1277686D03*
X583930Y1273498D03*
X760433Y1480906D03*
X756274Y1490945D03*
X760433Y1500984D03*
X780511Y1480906D03*
X770472Y1476747D03*
Y1505143D03*
X780511Y1500984D03*
X799926Y1056423D03*
X795738Y1066535D03*
X799926Y1076647D03*
Y1253274D03*
X795738Y1263386D03*
X799926Y1273498D03*
X784670Y1490945D03*
X810040Y378544D03*
X805881Y388583D03*
X810040Y398622D03*
X810038Y1052235D03*
Y1080835D03*
Y1249086D03*
Y1277686D03*
X820079Y374385D03*
X830118Y378544D03*
X820079Y402781D03*
X830118Y398622D03*
X820150Y1056423D03*
Y1076647D03*
X824338Y1066535D03*
X820150Y1253274D03*
X824338Y1263386D03*
X820150Y1273498D03*
X834277Y388583D03*
X1010827Y378544D03*
X1006668Y388583D03*
X1010827Y398622D03*
X1020866Y374385D03*
Y402781D03*
X1020793Y1056423D03*
X1016605Y1066535D03*
X1020793Y1076647D03*
Y1253274D03*
X1016605Y1263386D03*
X1020793Y1273498D03*
X1030905Y378544D03*
X1035064Y388583D03*
X1030905Y398622D03*
X1041017Y1056423D03*
X1030905Y1052235D03*
X1041017Y1076647D03*
X1030905Y1080835D03*
X1041017Y1253274D03*
X1030905Y1249086D03*
Y1277686D03*
X1041017Y1273498D03*
X1045205Y1066535D03*
Y1263386D03*
X1060433Y1480906D03*
X1056274Y1490945D03*
X1060433Y1500984D03*
X1070472Y1476747D03*
Y1505143D03*
X1080511Y1480906D03*
X1084670Y1490945D03*
X1080511Y1500984D03*
X1252825Y1066535D03*
Y1263386D03*
X1267125Y1052235D03*
X1257013Y1056423D03*
Y1076647D03*
X1267125Y1080835D03*
Y1249086D03*
X1257013Y1253274D03*
Y1273498D03*
X1267125Y1277686D03*
X1277237Y1056423D03*
Y1076647D03*
X1281425Y1066535D03*
X1277237Y1253274D03*
X1281425Y1263386D03*
X1277237Y1273498D03*
X1477879Y1056423D03*
X1473691Y1066535D03*
X1477879Y1076647D03*
Y1253274D03*
X1473691Y1263386D03*
X1477879Y1273498D03*
X1498103Y1056423D03*
X1487991Y1052235D03*
X1498103Y1076647D03*
X1487991Y1080835D03*
X1498103Y1253274D03*
X1487991Y1249086D03*
Y1277686D03*
X1498103Y1273498D03*
X1502291Y1066535D03*
Y1263386D03*
X1709912Y1066535D03*
Y1263386D03*
X1724212Y1052235D03*
X1714100Y1056423D03*
Y1076647D03*
X1724212Y1080835D03*
Y1249086D03*
X1714100Y1253274D03*
Y1273498D03*
X1724212Y1277686D03*
X1734324Y1056423D03*
Y1076647D03*
X1738512Y1066535D03*
X1734324Y1253274D03*
X1738512Y1263386D03*
X1734324Y1273498D03*
G54D45*
X710406Y-26826D03*
Y-36826D03*
D03*
Y-26826D03*
X735406D03*
Y-36826D03*
D03*
Y-26826D03*
X830406Y-76006D03*
D03*
Y-66006D03*
D03*
X855406Y-76006D03*
D03*
Y-66006D03*
D03*
X939542Y-36798D03*
Y-26798D03*
D03*
Y-36798D03*
X964386Y-75978D03*
D03*
Y-65978D03*
D03*
X964542Y-36798D03*
Y-26798D03*
D03*
Y-36798D03*
X989386Y-75978D03*
D03*
Y-65978D03*
D03*
X993906Y-46826D03*
Y-36826D03*
D03*
Y-26826D03*
X1018906Y-46826D03*
Y-36826D03*
D03*
Y-26826D03*
X1063906Y-76006D03*
Y-86006D03*
Y-76006D03*
Y-66006D03*
X1088906Y-76006D03*
Y-86006D03*
Y-76006D03*
Y-66006D03*
X1217686Y-85978D03*
Y-75978D03*
D03*
Y-65978D03*
X1223042Y-46928D03*
Y-36928D03*
Y-26928D03*
Y-36928D03*
X1242686Y-85978D03*
Y-75978D03*
D03*
Y-65978D03*
X1248042Y-46928D03*
Y-36928D03*
Y-26928D03*
Y-36928D03*
X1280406Y-46956D03*
Y-36956D03*
D03*
Y-26956D03*
X1305406Y-46956D03*
Y-36956D03*
D03*
Y-26956D03*
X1320406Y-76006D03*
Y-86006D03*
Y-76006D03*
Y-66006D03*
X1345406Y-76006D03*
Y-86006D03*
Y-76006D03*
Y-66006D03*
X1474186Y-85978D03*
Y-75978D03*
D03*
Y-65978D03*
X1499186Y-85978D03*
Y-75978D03*
D03*
Y-65978D03*
X1509542Y-47058D03*
Y-37058D03*
Y-27058D03*
Y-37058D03*
X1534542Y-47058D03*
Y-37058D03*
Y-27058D03*
Y-37058D03*
X1564906Y-47086D03*
Y-37086D03*
D03*
Y-27086D03*
X1574906Y-76006D03*
Y-86006D03*
Y-76006D03*
Y-66006D03*
X1589906Y-47086D03*
Y-37086D03*
D03*
Y-27086D03*
X1599906Y-76006D03*
Y-86006D03*
Y-76006D03*
Y-66006D03*
X1728686Y-85978D03*
Y-75978D03*
D03*
Y-65978D03*
X1753686Y-85978D03*
Y-75978D03*
D03*
Y-65978D03*
X1794042Y-47188D03*
Y-37188D03*
Y-27188D03*
Y-37188D03*
X1819042Y-47188D03*
Y-37188D03*
Y-27188D03*
Y-37188D03*
G54D10*
X3704Y5374D03*
X3017Y24773D03*
Y44773D03*
Y64773D03*
Y84773D03*
Y104773D03*
Y124773D03*
Y144773D03*
Y164773D03*
Y184773D03*
Y204773D03*
Y224773D03*
Y244773D03*
Y264773D03*
Y284773D03*
Y304773D03*
X3221Y324773D03*
X3035Y978036D03*
Y998036D03*
Y1018036D03*
Y1038036D03*
Y1058036D03*
Y1078036D03*
Y1098036D03*
Y1118036D03*
Y1138036D03*
Y1158036D03*
Y1178036D03*
Y1198036D03*
Y1238036D03*
Y1258036D03*
Y1278036D03*
Y1298036D03*
Y1318036D03*
Y1338036D03*
Y1358036D03*
Y1378036D03*
Y1398036D03*
Y1418036D03*
Y1438036D03*
Y1458036D03*
Y1478036D03*
Y1498036D03*
Y1538036D03*
Y1558036D03*
X15972Y3000D03*
X10971Y333342D03*
X17964Y349298D03*
Y369298D03*
Y389298D03*
Y409298D03*
Y429298D03*
Y449298D03*
Y469298D03*
Y489298D03*
Y509298D03*
Y529298D03*
Y549298D03*
Y569298D03*
Y589298D03*
Y609298D03*
Y629298D03*
Y649298D03*
Y669298D03*
Y689298D03*
Y709298D03*
Y729298D03*
Y749298D03*
Y769298D03*
Y789298D03*
Y809298D03*
Y829298D03*
Y849298D03*
Y869298D03*
Y889298D03*
Y909298D03*
Y929298D03*
X9554Y961954D03*
X17964Y949298D03*
X6161Y1075991D03*
X6108Y1070611D03*
Y1065318D03*
X6059Y1091964D03*
X6055Y1086546D03*
X6053Y1081305D03*
X8042Y1522199D03*
X7922Y1532494D03*
X26956Y4469D03*
X28317Y24773D03*
Y44773D03*
X35638Y53597D03*
X36692Y641817D03*
X27934Y1204311D03*
X30934D03*
X27934Y1215511D03*
X30934D03*
X27934Y1212711D03*
Y1209911D03*
Y1207111D03*
X30934Y1212711D03*
Y1209911D03*
Y1207111D03*
X21544Y1479662D03*
X33536Y1467485D03*
X21544Y1489648D03*
X42192Y641817D03*
X51449Y822718D03*
X47949D03*
X44960Y1190619D03*
X49638Y1203884D03*
X40996Y1467703D03*
X40195Y1511279D03*
X55638Y53597D03*
X66371Y482134D03*
Y484634D03*
X60233Y521804D03*
X68202Y522129D03*
X60233Y524304D03*
X56540Y531378D03*
Y528878D03*
X68202Y527129D03*
Y524629D03*
Y529629D03*
X62789Y608311D03*
X66510Y628242D03*
X60849Y826818D03*
X64649D03*
X58949Y821018D03*
X64849Y840418D03*
X60249D03*
X74432Y5374D03*
X73745Y24773D03*
Y44773D03*
X73509Y110445D03*
Y115401D03*
X83911Y117557D03*
X80660Y103783D03*
X73509Y129574D03*
Y124618D03*
X83911Y122513D03*
Y131731D03*
Y136687D03*
X69816Y475946D03*
Y478446D03*
X78033Y478586D03*
Y481086D03*
Y476086D03*
Y483586D03*
X72549Y838818D03*
X93334Y3000D03*
X95943Y377953D03*
X113334Y3000D03*
X129318Y4469D03*
X130679Y24773D03*
Y44773D03*
X138000Y53597D03*
X146196Y390223D03*
X138194Y397335D03*
X146196Y395179D03*
Y404396D03*
Y409352D03*
X138194Y402291D03*
X135794Y416465D03*
Y411509D03*
X146196Y418569D03*
Y423525D03*
X135794Y425682D03*
Y430638D03*
X146196Y432743D03*
Y437699D03*
X135794Y439855D03*
Y444811D03*
Y468609D03*
Y473565D03*
X146196Y489895D03*
X135794Y487738D03*
X146196Y480677D03*
Y475721D03*
X135794Y482782D03*
X146196Y494851D03*
X135794Y512743D03*
Y517699D03*
X146196Y519855D03*
X135794Y526916D03*
Y531872D03*
X146196Y524811D03*
Y538984D03*
Y534028D03*
X158000Y53597D03*
X176794Y5374D03*
X176107Y24773D03*
Y44773D03*
X195697Y3000D03*
X183022Y103783D03*
X215697Y3000D03*
X231681Y4469D03*
X229745Y1446675D03*
X224753D03*
Y1462631D03*
X229745Y1457675D03*
X224753D03*
X229745Y1451631D03*
Y1462631D03*
X224753Y1451631D03*
X233042Y24773D03*
Y44773D03*
X240363Y53597D03*
X260363D03*
X279156Y5374D03*
X278469Y24773D03*
Y44773D03*
X265945Y440098D03*
Y437598D03*
Y435098D03*
Y432598D03*
Y430098D03*
X294959Y11097D03*
X285384Y103783D03*
X298059Y3000D03*
X301943Y332017D03*
X318059Y3000D03*
X318497Y466528D03*
Y471484D03*
X328899Y473640D03*
Y487813D03*
Y478596D03*
X318497Y480701D03*
Y485657D03*
X328899Y492769D03*
Y517774D03*
X318497Y510661D03*
Y515617D03*
X328899Y522730D03*
X318497Y524835D03*
X328899Y536903D03*
Y531947D03*
X318497Y529791D03*
X328899Y572769D03*
X318497Y565657D03*
Y560701D03*
X328899Y567813D03*
X318497Y579830D03*
Y574874D03*
X328899Y581987D03*
X318497Y589047D03*
X328899Y586943D03*
X318497Y594003D03*
X328899Y596160D03*
X318497Y603221D03*
X328899Y601116D03*
Y610333D03*
X318497Y608177D03*
X328899Y615289D03*
X334043Y4469D03*
X335404Y24773D03*
Y44773D03*
X342725Y53597D03*
X348737Y375386D03*
X354486Y377173D03*
X357173Y392183D03*
X357218Y396866D03*
X361234Y402867D03*
X358042Y442518D03*
Y439718D03*
X362725Y53597D03*
X361767Y392228D03*
X376992Y395248D03*
X368587Y409016D03*
X364551Y409032D03*
X361811Y396866D03*
X375919Y449118D03*
Y446318D03*
X367919Y449118D03*
Y446318D03*
X376099Y458309D03*
Y454309D03*
Y462309D03*
X369282Y468088D03*
Y465288D03*
X367816Y1310586D03*
Y1315542D03*
X388059Y3000D03*
X381518Y5374D03*
X388487Y24069D03*
X380831Y24773D03*
X383612Y30618D03*
X380831Y44773D03*
X387746Y103783D03*
X389237Y371070D03*
X385237Y370976D03*
X396373Y407104D03*
X385584Y450041D03*
Y452841D03*
Y455641D03*
X387587Y1296675D03*
X387644Y1302089D03*
X389458Y1365466D03*
X389188Y1369033D03*
X388600Y1395500D03*
X389985Y1405762D03*
X408059Y3000D03*
X396373Y409904D03*
X395577Y455641D03*
Y450041D03*
Y452841D03*
X397315Y479560D03*
X400914Y762675D03*
X408300Y755487D03*
X407965Y770196D03*
X408400Y795200D03*
Y792200D03*
X406600Y789000D03*
X402376Y842677D03*
X399876D03*
X402376Y850677D03*
X399876D03*
X395959Y1352153D03*
X403029Y1379716D03*
X403111Y1384920D03*
X408212Y1379695D03*
X394657Y1377875D03*
X403111Y1390103D03*
X408212Y1390083D03*
X410152Y1410928D03*
X398112Y1403741D03*
X415453Y455039D03*
X419040Y533690D03*
Y528390D03*
Y530990D03*
Y536290D03*
Y538890D03*
X423266Y631438D03*
X420266D03*
X417666D03*
X420266Y637038D03*
Y634238D03*
X417666Y637038D03*
Y634238D03*
X423266Y637038D03*
Y634238D03*
Y642638D03*
X420266D03*
X417666D03*
X423266Y639838D03*
X420266D03*
X417666D03*
X415696Y762466D03*
X424649Y842644D03*
X422149D03*
Y850644D03*
X424649D03*
X422149Y858644D03*
X424649D03*
X414280Y1362561D03*
X413437Y1379736D03*
Y1384899D03*
X413395Y1390062D03*
X428059Y3000D03*
X433724Y433975D03*
X432310Y436164D03*
X428740Y533690D03*
X442704Y533790D03*
X428740Y528390D03*
Y530990D03*
X442704Y528490D03*
Y531090D03*
X428740Y536290D03*
Y538890D03*
X442704Y536390D03*
Y538990D03*
X436369Y622883D03*
X441612Y631011D03*
X435881Y1394934D03*
Y1398800D03*
X448059Y3000D03*
X452404Y533690D03*
Y528390D03*
Y530990D03*
Y536290D03*
Y538890D03*
X468059Y3000D03*
X468850Y537507D03*
X461849Y668016D03*
X459349D03*
X466849D03*
X469349D03*
X464349D03*
X469349Y678016D03*
X466849D03*
X459349D03*
X461849D03*
X464349D03*
X484043Y4469D03*
X485404Y24773D03*
Y44773D03*
X482193Y472784D03*
Y468784D03*
Y476784D03*
X484341Y700528D03*
Y705484D03*
X492725Y53597D03*
X499278Y641817D03*
X493778D03*
X512725Y53597D03*
X523457Y482134D03*
Y484634D03*
X517319Y521804D03*
X513626Y528578D03*
Y531378D03*
X517319Y524304D03*
X519875Y608311D03*
X523596Y628242D03*
X531518Y5374D03*
X530831Y24773D03*
Y44773D03*
X537747Y103783D03*
X535119Y483886D03*
Y481086D03*
Y478586D03*
X526902Y478446D03*
Y475946D03*
X535119Y476086D03*
X525288Y522129D03*
Y524629D03*
Y527129D03*
Y529929D03*
X542275Y760782D03*
X532449Y782389D03*
X534672Y785037D03*
X536641Y838649D03*
X550421Y3000D03*
X542599Y782389D03*
X542546Y784911D03*
X554357Y784889D03*
X551524D03*
X570421Y3000D03*
X562231Y784911D03*
X558294D03*
X560263Y829989D03*
X568503Y936807D03*
X565003D03*
X586405Y4469D03*
X587766Y24773D03*
Y44773D03*
X583501Y800831D03*
X577903Y940907D03*
X581703D03*
X576003Y935107D03*
X581903Y954507D03*
X577303D03*
X595087Y53597D03*
X603282Y390223D03*
Y395179D03*
Y404396D03*
Y409352D03*
X595280Y402291D03*
Y397335D03*
X592880Y416465D03*
Y411509D03*
X603282Y418569D03*
Y423525D03*
X592880Y425682D03*
X603282Y432743D03*
Y437699D03*
X592880Y439855D03*
Y430638D03*
Y444811D03*
Y468609D03*
Y473565D03*
X603282Y489895D03*
X592880Y487738D03*
X603282Y480677D03*
Y475721D03*
X592880Y482782D03*
X603282Y494851D03*
X592880Y517699D03*
X603282Y519855D03*
X592880Y526916D03*
Y531872D03*
X603282Y524811D03*
Y538984D03*
Y534028D03*
X589603Y952907D03*
X615087Y53597D03*
X633248Y44884D03*
X640109Y103783D03*
X690073Y44662D03*
X697387Y53619D03*
X717387D03*
X723031Y440098D03*
Y437598D03*
Y435098D03*
Y432598D03*
Y430098D03*
X736242Y5374D03*
X735555Y24773D03*
Y44773D03*
X742471Y103783D03*
X755145Y3000D03*
X759029Y332017D03*
X775145Y3000D03*
X775584Y466528D03*
X775583Y471484D03*
Y480701D03*
Y485657D03*
Y515617D03*
Y510661D03*
Y524835D03*
Y529791D03*
Y560701D03*
Y565657D03*
Y579830D03*
Y574874D03*
Y589047D03*
Y594003D03*
Y603221D03*
Y608177D03*
X791129Y4469D03*
X792490Y24773D03*
Y44773D03*
X799811Y53597D03*
X785985Y473640D03*
Y487813D03*
Y478596D03*
Y492769D03*
Y517774D03*
Y522730D03*
Y531947D03*
Y536903D03*
Y572769D03*
Y567813D03*
Y581987D03*
Y586943D03*
Y601116D03*
Y596160D03*
Y615289D03*
Y610333D03*
X806318Y1401661D03*
X806874Y1447457D03*
X812474D03*
X806874Y1452587D03*
Y1457717D03*
X812474D03*
X815096Y1464387D03*
X812009Y1473432D03*
Y1470432D03*
X815096Y1467387D03*
X812096Y1479587D03*
Y1476587D03*
X815096Y1473387D03*
Y1479587D03*
Y1476587D03*
Y1470387D03*
X819811Y53597D03*
X829791Y839020D03*
X825721Y836666D03*
X823234Y867680D03*
X825774Y895553D03*
X816648Y1377608D03*
X817974Y1447457D03*
Y1452587D03*
Y1457717D03*
X818096Y1464387D03*
X821096D03*
X818096Y1473387D03*
X821096D03*
X824096D03*
X818096Y1479587D03*
X821096D03*
X824096D03*
X818096Y1476587D03*
X821096D03*
X824096D03*
X818096Y1467387D03*
Y1470387D03*
X821096D03*
Y1467387D03*
X824096D03*
Y1470387D03*
X838606Y5374D03*
X837919Y24773D03*
Y44773D03*
X844833Y103783D03*
X833185Y456309D03*
Y452309D03*
Y448309D03*
X850145Y3000D03*
X857973Y404867D03*
X862522Y400229D03*
X862566Y404867D03*
X857928Y400184D03*
X862020Y410899D03*
X862882Y468791D03*
Y465991D03*
X854882D03*
Y468791D03*
X861468Y491303D03*
X859071Y1447459D03*
X864671D03*
X859071Y1452589D03*
Y1457719D03*
X864671D03*
X864644Y1464759D03*
X861644D03*
X855644D03*
X858644D03*
Y1467759D03*
X855644Y1470759D03*
X858644D03*
X864644Y1467759D03*
Y1470759D03*
X861644Y1467759D03*
Y1470759D03*
X855644Y1467759D03*
Y1473759D03*
X858644D03*
X864644D03*
X861644D03*
X855644Y1476759D03*
X858644D03*
X864644D03*
X861644D03*
X872736Y383125D03*
X872318Y408589D03*
X866128Y417532D03*
X869342Y417399D03*
X880910Y471982D03*
Y469182D03*
Y466382D03*
X870882Y465991D03*
Y468791D03*
X878610Y747171D03*
X871294Y771809D03*
X871624Y1213314D03*
X874624D03*
X871624Y1221714D03*
Y1218914D03*
Y1216114D03*
X874624Y1221714D03*
Y1218914D03*
Y1216114D03*
X871624Y1224514D03*
X874624D03*
X870171Y1447459D03*
Y1452589D03*
Y1457719D03*
X867644Y1464759D03*
X870644D03*
X867644Y1467759D03*
X870644D03*
X867644Y1470759D03*
X870644D03*
X867644Y1473759D03*
X870644D03*
X867644Y1476759D03*
X870644D03*
X884736Y383125D03*
X893736D03*
X888736D03*
X891699Y420445D03*
Y423245D03*
X890903Y469182D03*
Y471982D03*
Y466382D03*
X896431Y534093D03*
X897118Y857891D03*
Y864189D03*
Y854742D03*
X893968Y864189D03*
Y857891D03*
Y854742D03*
X897118Y873638D03*
Y870488D03*
Y867338D03*
X893968Y870488D03*
Y873638D03*
Y867338D03*
X887669Y876787D03*
X888650Y1199622D03*
X893328Y1212887D03*
X912278Y343881D03*
X910779Y471380D03*
X903431Y534093D03*
X912462Y695770D03*
X912864Y848442D03*
Y845293D03*
Y842143D03*
X909714Y845293D03*
Y842143D03*
X900267Y864189D03*
X909714Y854742D03*
X906565Y857891D03*
X909714D03*
X906565Y864189D03*
X909714D03*
X906565Y854742D03*
X900267Y857891D03*
Y854742D03*
X912864Y851592D03*
Y857891D03*
Y854742D03*
X909714Y873638D03*
Y870488D03*
X906565Y873638D03*
Y870488D03*
Y867338D03*
X900267Y873638D03*
Y870488D03*
Y867338D03*
X909714D03*
X912171Y1447459D03*
X906671D03*
X901071D03*
X912171Y1457719D03*
Y1452589D03*
X906671Y1457719D03*
X901071D03*
Y1452589D03*
X908370Y1464583D03*
X905370D03*
X899370D03*
X902370D03*
X911370D03*
X905370Y1476583D03*
X908370D03*
X902370D03*
X899370D03*
X905370Y1473583D03*
X908370D03*
X902370D03*
X899370D03*
X902370Y1467583D03*
X899370Y1470583D03*
X902370D03*
X908370Y1467583D03*
Y1470583D03*
X905370Y1467583D03*
Y1470583D03*
X899370Y1467583D03*
X911370Y1476583D03*
Y1473583D03*
Y1467583D03*
Y1470583D03*
X930145Y3000D03*
X921847Y346622D03*
X927636Y452505D03*
X929050Y450316D03*
X928612Y835844D03*
X922313Y851592D03*
X929611Y858669D03*
X914370Y1464583D03*
Y1476583D03*
Y1473583D03*
Y1467583D03*
Y1470583D03*
X941129Y4469D03*
X942490Y24773D03*
Y44773D03*
X931620Y584417D03*
X931594Y599420D03*
X931647Y593271D03*
X931578Y590669D03*
X933810Y972433D03*
X935601Y1221714D03*
Y1218914D03*
Y1216114D03*
Y1213314D03*
X938601Y1221714D03*
Y1218914D03*
Y1216114D03*
Y1213314D03*
X935601Y1224514D03*
X938601D03*
X949811Y53597D03*
X956365Y641817D03*
X950865D03*
X950567Y927654D03*
X952627Y1199622D03*
X957305Y1212887D03*
X969811Y53597D03*
X976763Y307303D03*
X969623Y405614D03*
X963577Y426391D03*
X974406Y521804D03*
Y524304D03*
X970713Y531378D03*
Y528878D03*
X976962Y608311D03*
X980683Y628242D03*
X972278Y934429D03*
X988606Y5374D03*
X987919Y24773D03*
Y44773D03*
X994833Y103783D03*
X993132Y310942D03*
X993243Y321325D03*
X987055Y320273D03*
X993920Y335454D03*
X993420Y337954D03*
X992206Y478586D03*
Y481086D03*
Y483886D03*
X980544Y482134D03*
Y484634D03*
X992206Y476086D03*
X983989Y475946D03*
Y478446D03*
X982375Y522129D03*
Y527129D03*
Y524629D03*
Y529929D03*
X1007508Y3000D03*
X1004635Y300276D03*
X1008635D03*
X998667Y322239D03*
X1000420Y348954D03*
X1010119Y933822D03*
X1006619D03*
X1013683Y-44304D03*
Y-39348D03*
Y-29348D03*
Y-34304D03*
X1027508Y3000D03*
X1021895Y771974D03*
X1019519Y937922D03*
X1023319D03*
X1017619Y932122D03*
X1023519Y951522D03*
X1018919D03*
X1043492Y4469D03*
X1041496Y300276D03*
X1031354Y322905D03*
X1031219Y949922D03*
X1044853Y24773D03*
Y44773D03*
X1052174Y53597D03*
X1046674Y340031D03*
X1045966Y346808D03*
X1052367Y402291D03*
Y397335D03*
X1049967Y416465D03*
Y411509D03*
Y425682D03*
Y439855D03*
Y430638D03*
Y444811D03*
Y468609D03*
Y473565D03*
Y487738D03*
Y482782D03*
Y512743D03*
Y517699D03*
Y526916D03*
Y531872D03*
X1072174Y53597D03*
X1060369Y390223D03*
Y395179D03*
Y404396D03*
Y409352D03*
Y418569D03*
Y423525D03*
Y432743D03*
Y437699D03*
Y489895D03*
Y480677D03*
Y475721D03*
Y494851D03*
Y519855D03*
Y524811D03*
Y538984D03*
Y534028D03*
X1083683Y-78528D03*
Y-83484D03*
Y-73484D03*
Y-68528D03*
X1090280Y44773D03*
X1083483Y1523433D03*
X1097195Y103783D03*
X1147214Y44773D03*
X1154535Y53597D03*
X1174535D03*
X1176858Y306534D03*
X1180118Y430098D03*
Y440098D03*
Y437598D03*
Y435098D03*
Y432598D03*
X1193330Y5374D03*
X1192643Y24773D03*
Y44773D03*
X1199557Y103783D03*
X1192500Y322400D03*
X1199615Y950670D03*
X1201794Y985289D03*
X1212232Y3000D03*
X1221337Y332017D03*
X1232232Y3000D03*
X1232670Y466528D03*
Y471484D03*
Y480701D03*
Y485657D03*
Y515617D03*
Y510661D03*
Y524835D03*
Y529791D03*
Y565657D03*
Y560701D03*
Y579830D03*
Y589047D03*
Y574874D03*
Y603221D03*
Y594003D03*
Y608177D03*
X1248216Y4469D03*
X1249577Y24773D03*
Y44773D03*
X1243072Y473640D03*
Y487813D03*
Y478596D03*
Y492769D03*
Y522730D03*
Y517774D03*
Y536903D03*
Y531947D03*
Y567813D03*
Y572769D03*
Y586943D03*
Y581987D03*
Y601116D03*
Y596160D03*
Y610333D03*
Y615289D03*
X1256898Y53597D03*
X1266219Y374300D03*
X1268659Y377173D03*
X1276898Y53597D03*
X1275940Y392228D03*
X1271346Y392183D03*
X1275407Y402867D03*
X1271391Y396866D03*
X1275984D03*
X1282760Y409016D03*
X1278724Y409032D03*
X1272215Y442518D03*
Y439718D03*
X1282092Y449118D03*
Y446318D03*
X1283455Y468088D03*
Y465288D03*
X1300183Y-44434D03*
Y-29478D03*
Y-34434D03*
Y-39478D03*
X1302232Y3000D03*
X1295692Y5374D03*
X1303229Y23274D03*
X1295005Y24773D03*
X1297785Y30618D03*
X1295005Y44773D03*
X1301919Y103783D03*
X1303158Y371043D03*
X1299410Y370976D03*
X1291165Y395248D03*
X1290092Y449118D03*
Y446318D03*
X1299757Y450041D03*
Y452841D03*
Y455641D03*
X1290272Y458309D03*
Y454309D03*
Y462309D03*
X1310546Y409904D03*
Y407104D03*
X1309750Y455641D03*
Y450041D03*
Y452841D03*
X1311488Y479560D03*
X1309856Y899161D03*
X1305761D03*
X1313756D03*
X1322232Y3000D03*
X1320903Y370995D03*
X1333331Y370905D03*
X1329064Y370951D03*
X1329626Y455039D03*
X1340183Y-83484D03*
Y-78528D03*
Y-68528D03*
Y-73484D03*
X1342232Y3000D03*
X1338287Y370905D03*
X1347897Y433975D03*
X1346483Y436164D03*
X1362232Y3000D03*
X1382232D03*
X1373748Y397758D03*
X1375375Y428995D03*
X1398216Y4469D03*
X1399577Y24773D03*
Y44773D03*
X1397550Y390484D03*
X1387814Y397136D03*
X1389295Y408443D03*
X1386809Y414173D03*
X1388788Y428348D03*
X1406898Y53597D03*
X1416830Y407134D03*
X1411400Y398032D03*
X1413889Y415642D03*
X1413452Y641817D03*
X1407952D03*
X1426898Y53597D03*
X1431493Y521804D03*
X1427800Y528578D03*
X1431493Y524304D03*
X1427800Y531378D03*
X1422176Y1491198D03*
X1423806Y1524252D03*
X1445692Y5374D03*
X1445005Y24773D03*
Y44773D03*
X1440568Y369566D03*
X1449619Y363290D03*
X1438588Y380589D03*
X1437631Y482134D03*
Y484634D03*
X1449293Y476086D03*
X1441076Y475946D03*
Y478446D03*
X1449293Y478586D03*
Y481086D03*
Y483886D03*
X1439462Y522129D03*
Y529929D03*
Y527129D03*
Y524629D03*
X1434049Y608311D03*
X1437770Y628242D03*
X1464594Y3000D03*
X1462675Y14334D03*
X1451920Y103783D03*
X1455979Y391756D03*
X1458212Y403374D03*
X1473364Y410724D03*
X1472403Y417338D03*
X1469293Y428815D03*
X1484594Y3000D03*
X1498446Y912370D03*
X1497208Y909740D03*
X1500578Y4469D03*
X1501939Y24773D03*
Y44773D03*
X1509260Y53597D03*
X1509454Y402291D03*
Y397335D03*
X1507054Y416465D03*
Y411509D03*
Y425682D03*
Y439855D03*
Y430638D03*
Y444811D03*
Y468609D03*
Y473565D03*
Y487738D03*
Y482782D03*
Y517699D03*
Y512743D03*
Y526916D03*
Y531872D03*
X1507034Y888133D03*
X1507358Y909740D03*
X1507305Y912262D03*
X1501400Y966000D03*
X1529260Y53597D03*
X1517456Y390223D03*
Y395179D03*
Y404396D03*
Y409352D03*
Y418569D03*
Y423525D03*
Y432743D03*
Y437699D03*
Y489895D03*
Y480677D03*
Y475721D03*
Y494851D03*
Y519855D03*
Y538984D03*
Y524811D03*
Y534028D03*
X1516283Y912240D03*
X1519116D03*
X1523053Y912262D03*
X1525022Y957340D03*
X1547367Y44773D03*
X1554282Y103783D03*
X1594683Y-83484D03*
Y-78528D03*
Y-68528D03*
Y-73484D03*
X1584683Y-44564D03*
Y-29608D03*
Y-34564D03*
Y-39608D03*
X1604301Y44773D03*
X1611622Y53597D03*
X1631622D03*
X1637205Y440098D03*
Y437598D03*
Y435098D03*
Y432598D03*
Y430098D03*
X1650417Y5374D03*
X1649730Y24773D03*
Y44773D03*
X1656644Y103783D03*
X1669319Y3001D03*
X1673203Y332017D03*
X1689319Y3001D03*
X1689757Y466528D03*
Y471484D03*
Y480701D03*
Y485657D03*
Y515617D03*
Y510661D03*
Y524835D03*
Y529791D03*
Y565657D03*
Y560701D03*
Y589047D03*
Y574874D03*
Y579830D03*
Y603221D03*
Y594003D03*
Y608177D03*
X1705303Y4470D03*
X1706664Y24774D03*
Y44774D03*
X1700159Y473640D03*
Y487813D03*
Y478596D03*
Y492769D03*
Y517774D03*
Y522730D03*
Y536903D03*
Y531947D03*
Y572769D03*
Y567813D03*
Y586943D03*
Y581987D03*
Y601116D03*
Y596160D03*
Y610333D03*
Y615289D03*
X1713985Y53598D03*
X1725746Y377173D03*
X1723964Y370935D03*
X1733985Y53598D03*
X1733027Y392228D03*
X1728433Y392183D03*
X1739847Y409016D03*
X1735811Y409032D03*
X1732494Y402867D03*
X1728478Y396866D03*
X1733071D03*
X1729302Y439718D03*
Y442518D03*
X1739179Y449118D03*
Y446318D03*
X1740542Y468088D03*
Y465288D03*
X1752778Y5374D03*
X1752091Y24773D03*
Y44773D03*
X1756497Y370976D03*
X1748252Y395248D03*
X1756844Y450041D03*
Y452841D03*
Y455641D03*
X1747179Y449118D03*
Y446318D03*
X1747359Y454309D03*
Y458309D03*
Y462309D03*
X1765559Y3001D03*
X1759006Y103783D03*
X1760497Y371070D03*
X1767633Y409904D03*
Y407104D03*
X1766837Y450041D03*
Y452841D03*
Y455641D03*
X1768575Y479560D03*
X1773600Y888100D03*
X1773614Y895275D03*
X1773600Y902800D03*
X1786713Y455039D03*
X1788400Y888100D03*
X1781000Y888087D03*
X1788396Y895066D03*
X1788300Y902800D03*
X1780665Y902796D03*
X1781263Y964660D03*
X1784763D03*
X1779581Y1222200D03*
Y1219400D03*
Y1216600D03*
Y1213800D03*
X1782581Y1222200D03*
Y1219400D03*
Y1216600D03*
Y1213800D03*
X1779581Y1225000D03*
X1782581D03*
X1804984Y433975D03*
X1803570Y436164D03*
X1794163Y968760D03*
X1797963D03*
X1792263Y962960D03*
X1798163Y982360D03*
X1793563D03*
X1805863Y980760D03*
X1796607Y1200108D03*
X1801285Y1213373D03*
X1822983Y346053D03*
Y366053D03*
Y386053D03*
Y406053D03*
Y426053D03*
Y446053D03*
Y466053D03*
Y486053D03*
Y506053D03*
Y526053D03*
Y546053D03*
Y566053D03*
Y586053D03*
Y606053D03*
Y626053D03*
Y646053D03*
Y666053D03*
Y686053D03*
Y706053D03*
Y726053D03*
Y746053D03*
Y766053D03*
Y786053D03*
Y806053D03*
Y826053D03*
Y846053D03*
Y866053D03*
Y886053D03*
Y906053D03*
Y926053D03*
Y946053D03*
X1825559Y3001D03*
X1836543Y4470D03*
X1837904Y24774D03*
Y44774D03*
Y64774D03*
Y84774D03*
Y104774D03*
Y124774D03*
Y144774D03*
Y164774D03*
Y184774D03*
Y204774D03*
Y224774D03*
Y244774D03*
Y264774D03*
Y284774D03*
Y304774D03*
X1837728Y324733D03*
X1830094Y333210D03*
X1830472Y960970D03*
X1837937Y973244D03*
Y993244D03*
Y1013244D03*
Y1033244D03*
Y1053244D03*
Y1073244D03*
X1824733Y1102830D03*
X1837937Y1093244D03*
X1825832Y1097589D03*
X1837937Y1113244D03*
Y1133244D03*
Y1153244D03*
Y1173244D03*
Y1193244D03*
Y1213244D03*
Y1253244D03*
Y1273244D03*
Y1293244D03*
Y1313244D03*
Y1333244D03*
Y1353244D03*
Y1373244D03*
Y1393244D03*
Y1433244D03*
Y1453244D03*
Y1473244D03*
Y1493244D03*
Y1513244D03*
Y1533244D03*
Y1553244D03*
Y1573244D03*
G54D14*
X20408Y51296D03*
Y55296D03*
X9057Y138939D03*
X19184Y144728D03*
X15184D03*
X15520Y195176D03*
X18320D03*
X13020D03*
X10520D03*
X12880Y203393D03*
X10380D03*
X19068Y206838D03*
X16568D03*
X13606Y1476707D03*
X19365Y1494298D03*
X24316Y67527D03*
Y63527D03*
Y59527D03*
X23184Y144728D03*
X35650Y487982D03*
Y478982D03*
Y483982D03*
Y499982D03*
X25819Y531726D03*
Y536726D03*
Y552726D03*
Y540726D03*
X30410Y1218497D03*
Y1220997D03*
Y1234797D03*
Y1232297D03*
Y1227897D03*
Y1225397D03*
Y1241697D03*
Y1239197D03*
X25674Y1486291D03*
X32195Y1511279D03*
X32079Y1521641D03*
X31237Y1532096D03*
X46240Y109410D03*
X45988Y102323D03*
X46240Y116496D03*
X46931Y130670D03*
X49236Y121658D03*
X46932Y137756D03*
X49839Y546830D03*
X44195Y1511279D03*
X39237Y1532096D03*
X64098Y102323D03*
Y109410D03*
Y116496D03*
Y123583D03*
Y130670D03*
Y137756D03*
X69139Y236611D03*
X68841Y248891D03*
X66224Y473045D03*
X58224D03*
X53643Y472905D03*
X59670Y500086D03*
X64495Y527449D03*
X61695D03*
X60554Y1612002D03*
X66291Y1633801D03*
X74139Y236611D03*
X71639D03*
X71341Y248891D03*
X73841D03*
X74326Y480705D03*
X71995Y532749D03*
X74795D03*
X74291Y1633801D03*
X86291D03*
X119582Y102249D03*
X111582D03*
X115582D03*
X115382Y195176D03*
X112882D03*
X117882D03*
X115242Y203393D03*
X112742D03*
X120682Y195176D03*
X118930Y206838D03*
X121430D03*
X148602Y109410D03*
Y116496D03*
X148350Y102323D03*
X148774Y124576D03*
X149827Y130670D03*
X149822Y137756D03*
X166460Y116496D03*
Y109410D03*
Y102323D03*
Y123583D03*
Y130670D03*
Y137756D03*
X174001Y236611D03*
X176501D03*
X171501D03*
X176203Y248891D03*
X173703D03*
X171203D03*
X185169Y389154D03*
Y396240D03*
X186448Y404911D03*
X186589Y426299D03*
X185402Y412571D03*
X186900Y445847D03*
X185169Y467539D03*
Y474626D03*
X185430Y480828D03*
X187380Y498834D03*
X185169Y518760D03*
Y511673D03*
Y525847D03*
X191125Y602400D03*
Y598400D03*
Y594400D03*
Y606400D03*
Y614400D03*
X203591Y91951D03*
X213944Y102249D03*
X215244Y195176D03*
X215104Y203393D03*
X203280Y389154D03*
Y396240D03*
Y403327D03*
Y410413D03*
Y417500D03*
Y424586D03*
Y431673D03*
Y438760D03*
Y445847D03*
Y467539D03*
Y474626D03*
Y488799D03*
Y481713D03*
Y495886D03*
Y511673D03*
Y518760D03*
Y525847D03*
Y532933D03*
Y540020D03*
Y547106D03*
Y554193D03*
Y602205D03*
Y595118D03*
X221944Y102249D03*
X217944D03*
X220244Y195176D03*
X217744D03*
X223044D03*
X223792Y206838D03*
X221292D03*
X217604Y203393D03*
X228267Y392718D03*
Y408718D03*
Y400718D03*
Y404718D03*
Y412718D03*
X250964Y109410D03*
X250712Y102323D03*
X250964Y116496D03*
X251136Y124576D03*
X252189Y130670D03*
X252184Y137756D03*
X268822Y116496D03*
Y109410D03*
Y102323D03*
Y130670D03*
Y123583D03*
Y137756D03*
X276363Y236611D03*
X278863D03*
X273863D03*
X276065Y248891D03*
X273565D03*
X278565D03*
X274205Y466027D03*
X274347Y475262D03*
Y489435D03*
Y482666D03*
X274163Y495088D03*
X274205Y509626D03*
X274820Y522134D03*
X274898Y514608D03*
X275463Y529136D03*
X275302Y535677D03*
X274586Y565574D03*
X274205Y559665D03*
X274233Y574338D03*
X274332Y616358D03*
X292500Y410394D03*
Y403307D03*
X284295Y430760D03*
X284316Y433570D03*
X284132Y437072D03*
X284173Y439963D03*
X284417Y443180D03*
X284437Y454744D03*
X284379Y452018D03*
X292316Y458406D03*
Y465492D03*
Y472579D03*
Y479665D03*
Y486752D03*
Y493839D03*
Y523799D03*
Y516713D03*
Y509626D03*
Y537973D03*
Y530886D03*
Y559665D03*
Y566752D03*
Y573839D03*
Y588012D03*
Y580925D03*
Y595099D03*
Y602185D03*
Y616358D03*
Y609272D03*
X324306Y102249D03*
X320306D03*
X316306D03*
X322606Y195176D03*
X325406D03*
X320106D03*
X317606D03*
X323654Y206838D03*
X319966Y203393D03*
X317466D03*
X326154Y206838D03*
X319857Y321649D03*
X324291Y556775D03*
X353074Y102323D03*
X353326Y109410D03*
Y116496D03*
X353498Y124576D03*
X354551Y130670D03*
X354546Y137756D03*
X371184Y116496D03*
Y109410D03*
Y102323D03*
Y130670D03*
Y123583D03*
Y137756D03*
X376225Y236611D03*
X375927Y248891D03*
X373101Y779608D03*
X376300Y779800D03*
X370214Y959812D03*
Y967812D03*
X381225Y236611D03*
X378725D03*
X378427Y248891D03*
X380927D03*
X379800Y778000D03*
X387692Y790056D03*
X393547D03*
X386614Y868286D03*
X385512Y955356D03*
X390150Y955312D03*
Y959905D03*
X385467Y959950D03*
X409268Y408240D03*
X409386Y420393D03*
X400900Y755400D03*
Y770100D03*
X407193Y883566D03*
X396182Y955858D03*
X402682Y948536D03*
X402815Y951750D03*
X404004Y1198321D03*
Y1200821D03*
X407469Y1495035D03*
X407854Y1492118D03*
X406377Y1499142D03*
X411768Y408240D03*
X414268D03*
X411847Y424240D03*
X414386Y420393D03*
X411886D03*
X411847Y426740D03*
X415700Y755400D03*
Y770200D03*
X422430Y834800D03*
X422379Y867229D03*
X420661Y1119422D03*
X423141Y1113822D03*
Y1119422D03*
X418181Y1113822D03*
Y1119422D03*
X420661Y1113822D03*
X417469Y1200821D03*
Y1198321D03*
X439804Y536682D03*
Y539182D03*
X430934Y1200821D03*
Y1198321D03*
X430657Y1563562D03*
X446179Y447101D03*
X448726Y653288D03*
Y646480D03*
Y648980D03*
Y655788D03*
X450244Y1090268D03*
Y1093068D03*
X455269Y1119422D03*
X450309Y1113822D03*
Y1119422D03*
X452789Y1113822D03*
Y1119422D03*
X455269Y1113822D03*
X474307Y102249D03*
X470307D03*
X466307D03*
X470107Y195176D03*
X467607D03*
X472607D03*
X475407D03*
X473655Y206838D03*
X467467Y203393D03*
X469967D03*
X463104Y536582D03*
Y539082D03*
X476155Y206838D03*
X492736Y478982D03*
X482905Y531726D03*
X482737Y537215D03*
X482905Y552726D03*
Y540726D03*
X488728Y1119422D03*
X483768Y1113822D03*
X486248D03*
Y1119422D03*
X483768D03*
X488728Y1113822D03*
X477206Y1198321D03*
X490671D03*
Y1200821D03*
X477206D03*
X503075Y102323D03*
X503327Y109410D03*
Y116496D03*
X506653Y121652D03*
X504552Y130670D03*
X504547Y137756D03*
X493485Y439903D03*
X492736Y487982D03*
Y483982D03*
Y499982D03*
X506925Y546830D03*
X504136Y1198321D03*
Y1200821D03*
X521185Y116496D03*
Y109410D03*
Y102323D03*
Y130670D03*
Y123583D03*
Y137756D03*
X508729Y469905D03*
X521310Y470045D03*
X513310D03*
X516756Y500086D03*
X518781Y527449D03*
X521581D03*
X518812Y665867D03*
X515831Y1090568D03*
Y1093068D03*
X518376Y1113822D03*
Y1119422D03*
X520856Y1113822D03*
Y1119422D03*
X515896Y1113822D03*
Y1119422D03*
X526226Y236611D03*
X531226D03*
X528726D03*
X528428Y248891D03*
X530928D03*
X525928D03*
X531412Y480705D03*
X528612D03*
X529481Y532849D03*
X532281D03*
X533486Y664052D03*
X538442D03*
X524941Y661387D03*
X530796D03*
X572669Y102249D03*
X568669D03*
X572469Y195176D03*
X572329Y203393D03*
X567559Y812850D03*
X576669Y102249D03*
X574969Y195176D03*
X577769D03*
X578517Y206838D03*
X576017D03*
X605437Y102323D03*
X605689Y109410D03*
Y116496D03*
X605861Y124576D03*
X606914Y130670D03*
X606909Y137756D03*
X623547Y109410D03*
Y116496D03*
Y102323D03*
Y123583D03*
Y130670D03*
Y137756D03*
X633588Y236611D03*
X631088D03*
X628588D03*
X630790Y248891D03*
X633290D03*
X628290D03*
X642255Y389154D03*
Y396240D03*
X643534Y404911D03*
X642488Y412571D03*
X643675Y426299D03*
X643986Y445847D03*
X642255Y467539D03*
Y474626D03*
X642516Y480828D03*
X644466Y498834D03*
X642255Y518760D03*
Y511673D03*
Y525847D03*
X648211Y602400D03*
Y598400D03*
Y594400D03*
Y606400D03*
Y614400D03*
X660366Y389154D03*
Y403327D03*
Y410413D03*
Y396240D03*
Y417500D03*
Y424586D03*
Y431673D03*
Y438760D03*
Y445847D03*
Y467539D03*
Y474626D03*
Y488799D03*
Y481713D03*
Y495886D03*
Y511673D03*
Y518760D03*
Y525847D03*
Y532933D03*
Y540020D03*
Y554193D03*
Y547106D03*
Y602205D03*
Y595118D03*
X679031Y102249D03*
X672331Y195176D03*
X674831D03*
X680131D03*
X672191Y203393D03*
X674691D03*
X678379Y206838D03*
X680879D03*
X685353Y392718D03*
Y408718D03*
Y400718D03*
Y404718D03*
Y412718D03*
X707799Y102323D03*
X708051Y109410D03*
Y116496D03*
X708223Y124576D03*
X709276Y130670D03*
X709271Y137756D03*
X725909Y102323D03*
Y116496D03*
Y109410D03*
Y130670D03*
Y123583D03*
Y137756D03*
X733450Y236611D03*
X730950D03*
X733152Y248891D03*
X730652D03*
X731291Y466027D03*
X731433Y475262D03*
Y489435D03*
Y482666D03*
X731249Y495088D03*
X731984Y514608D03*
X731906Y522134D03*
X731291Y509626D03*
X732549Y529136D03*
X732388Y535677D03*
X731291Y559665D03*
X731672Y565574D03*
X731319Y574338D03*
X731418Y616358D03*
X735950Y236611D03*
X735652Y248891D03*
X749586Y410394D03*
Y403307D03*
X741259Y439963D03*
X741381Y430760D03*
X741402Y433570D03*
X741218Y437072D03*
X741503Y443180D03*
X741523Y454744D03*
X741465Y452018D03*
X749402Y458406D03*
Y465492D03*
Y472579D03*
Y479665D03*
Y486752D03*
Y493839D03*
Y523799D03*
Y516713D03*
Y509626D03*
Y537973D03*
Y530886D03*
Y559665D03*
Y566752D03*
Y573839D03*
Y588012D03*
Y580925D03*
Y602185D03*
Y595099D03*
Y609272D03*
Y616358D03*
X751140Y1581335D03*
X740640Y1586885D03*
X748924Y1617709D03*
X735878Y1617010D03*
X763040Y91951D03*
X781393Y102249D03*
X777393D03*
X773393D03*
X779693Y195176D03*
X777193D03*
X782493D03*
X774693D03*
X780741Y206838D03*
X783241D03*
X777053Y203393D03*
X774553D03*
X776943Y321649D03*
X778985Y442498D03*
X778881Y446510D03*
X779029Y450510D03*
X777033Y1595215D03*
X781545Y1602835D03*
X774658Y1601012D03*
X792564Y406410D03*
X784586Y421000D03*
Y418500D03*
Y413500D03*
Y416000D03*
X784665Y564843D03*
X787447Y1593586D03*
X791610Y1593708D03*
X810161Y102323D03*
X810413Y109410D03*
Y116496D03*
X810585Y124576D03*
X811638Y130670D03*
X811633Y137756D03*
X828271Y116496D03*
Y109410D03*
Y102323D03*
Y130670D03*
Y123583D03*
Y137756D03*
X835812Y236611D03*
X838312D03*
X833312D03*
X833014Y248891D03*
X838014D03*
X835514D03*
X867093Y570703D03*
Y582828D03*
Y558703D03*
Y562703D03*
Y566703D03*
Y578703D03*
X872440Y1230083D03*
Y1227583D03*
Y1234483D03*
Y1236983D03*
Y1243883D03*
Y1241383D03*
Y1248283D03*
Y1250783D03*
X889436Y715970D03*
X905094Y424581D03*
X902594D03*
X907594D03*
X905212Y436734D03*
X902712D03*
X907712D03*
X907173Y440581D03*
Y443081D03*
X909024Y578394D03*
Y574394D03*
X909714Y838994D03*
X931393Y102249D03*
X923393D03*
X927393D03*
X925359Y180347D03*
X927859D03*
X925219Y188564D03*
X927719D03*
X919606Y231000D03*
X919577Y245669D03*
Y233858D03*
X919682Y236921D03*
X919577Y259843D03*
Y255118D03*
X919729Y274580D03*
X930359Y180347D03*
X933159D03*
X931407Y192009D03*
X933907D03*
X941505Y463442D03*
X939827Y531104D03*
X939992Y536726D03*
Y540726D03*
Y552726D03*
X936417Y1234483D03*
Y1236983D03*
Y1230083D03*
Y1227583D03*
Y1243883D03*
Y1241383D03*
Y1248283D03*
Y1250783D03*
X956460Y-35982D03*
X953207Y-35996D03*
X956445Y-38497D03*
X953192Y-38511D03*
X950167Y-37191D03*
X960161Y102323D03*
X960413Y109410D03*
Y116496D03*
X961638Y130670D03*
X961633Y137756D03*
X950315Y464851D03*
X949823Y487982D03*
X949876Y478486D03*
X949823Y483982D03*
Y499982D03*
X978036Y-77691D03*
X978051Y-75176D03*
X975011Y-76371D03*
X978271Y109410D03*
Y102323D03*
Y116496D03*
Y130670D03*
Y123583D03*
X963360Y121459D03*
X978271Y137756D03*
X977150Y328472D03*
Y335472D03*
X967816Y472905D03*
X972397Y472954D03*
X973843Y500086D03*
X978668Y527449D03*
X975868D03*
X964012Y546830D03*
X978857Y1360945D03*
X981289Y-77677D03*
X981304Y-75162D03*
X985812Y236611D03*
X988312D03*
X983312D03*
X983014Y248891D03*
X988014D03*
X985514D03*
X980397Y473045D03*
X985699Y480705D03*
X988499D03*
X989068Y532949D03*
X986268D03*
X981857Y1360945D03*
X978944Y1413859D03*
X981944D03*
X1007611Y1561247D03*
Y1558247D03*
Y1555247D03*
Y1552247D03*
X1004611Y1561247D03*
Y1558247D03*
Y1555247D03*
Y1552247D03*
X1015402Y91951D03*
X1025755Y102249D03*
X1027055Y195176D03*
X1033755Y102249D03*
X1029755D03*
X1032055Y195176D03*
X1029555D03*
X1034855D03*
X1033103Y206838D03*
X1035603D03*
X1029415Y203393D03*
X1062523Y102323D03*
X1062775Y109410D03*
Y116496D03*
X1062947Y124576D03*
X1064000Y130670D03*
X1063995Y137756D03*
X1080633Y102323D03*
Y116496D03*
Y109410D03*
Y130670D03*
Y123583D03*
Y137756D03*
X1085674Y236611D03*
X1088174D03*
X1090674D03*
X1090376Y248891D03*
X1087876D03*
X1085376D03*
X1077855Y327478D03*
X1077252Y323521D03*
Y318565D03*
X1077855Y332434D03*
X1099342Y389154D03*
Y396240D03*
X1100621Y404911D03*
X1099575Y412571D03*
X1100762Y426299D03*
X1101073Y445847D03*
X1099342Y467539D03*
Y474626D03*
X1099603Y480828D03*
X1101553Y498834D03*
X1099342Y518760D03*
Y511673D03*
Y525847D03*
X1105298Y598400D03*
Y602400D03*
Y594400D03*
Y614400D03*
Y606400D03*
X1117764Y91951D03*
X1117453Y389154D03*
Y396240D03*
Y403327D03*
Y410413D03*
Y417500D03*
Y424586D03*
Y431673D03*
Y438760D03*
Y445847D03*
Y467539D03*
Y474626D03*
Y488799D03*
Y481713D03*
Y495886D03*
Y511673D03*
Y518760D03*
Y525847D03*
Y532933D03*
Y540020D03*
Y554193D03*
Y547106D03*
Y602205D03*
Y595118D03*
X1136117Y102249D03*
X1132117D03*
X1128117D03*
X1134417Y195176D03*
X1131917D03*
X1137217D03*
X1129417D03*
X1137965Y206838D03*
X1131777Y203393D03*
X1135465Y206838D03*
X1142440Y404718D03*
Y412718D03*
X1125287Y592897D03*
X1142440Y392718D03*
Y400718D03*
Y408718D03*
X1164885Y102323D03*
X1165137Y109410D03*
Y116496D03*
X1165309Y124576D03*
X1166362Y130670D03*
X1166357Y137756D03*
X1182995Y116496D03*
Y109410D03*
Y102323D03*
Y130670D03*
Y123583D03*
Y137756D03*
X1188036Y236611D03*
X1187738Y248891D03*
X1188378Y466027D03*
X1188520Y475262D03*
Y489435D03*
Y482666D03*
X1188336Y495088D03*
X1189071Y514608D03*
X1188993Y522134D03*
X1188378Y509626D03*
X1189475Y535677D03*
X1189636Y529136D03*
X1188378Y559665D03*
X1188759Y565574D03*
X1188406Y574338D03*
X1188505Y616358D03*
X1190536Y236611D03*
X1193036D03*
X1192738Y248891D03*
X1190238D03*
X1198468Y430760D03*
X1198489Y433570D03*
X1198305Y437072D03*
X1198346Y439963D03*
X1198552Y452018D03*
X1198590Y443180D03*
X1198610Y454744D03*
X1220126Y91951D03*
X1206673Y410394D03*
Y403307D03*
X1206489Y458406D03*
Y465492D03*
Y472579D03*
Y479665D03*
Y486752D03*
Y493839D03*
Y523799D03*
Y516713D03*
Y509626D03*
Y537973D03*
Y530886D03*
Y566752D03*
Y559665D03*
Y580925D03*
Y588012D03*
Y573839D03*
Y602185D03*
Y595099D03*
Y616358D03*
Y609272D03*
X1231336Y-87691D03*
X1234589Y-87777D03*
X1231351Y-85176D03*
X1234604Y-85262D03*
X1228311Y-86371D03*
X1236692Y-48727D03*
X1236707Y-46212D03*
X1233667Y-47421D03*
X1238479Y102249D03*
X1230479D03*
X1234479D03*
X1236779Y195176D03*
X1234279D03*
X1239579D03*
X1231779D03*
X1234139Y203393D03*
X1231639D03*
X1237827Y206838D03*
X1234100Y322924D03*
X1239945Y-48727D03*
X1239960Y-46212D03*
X1240327Y206838D03*
X1241752Y564843D03*
X1267499Y116496D03*
X1267247Y102323D03*
X1267499Y109410D03*
X1267671Y124576D03*
X1268724Y130670D03*
X1268719Y137756D03*
X1259500Y330000D03*
X1285357Y116496D03*
Y109410D03*
Y102323D03*
Y123583D03*
Y130670D03*
Y137756D03*
X1281834Y374839D03*
X1290398Y236611D03*
X1295398D03*
X1292898D03*
X1290100Y248891D03*
X1292600D03*
X1295100D03*
X1301500Y329000D03*
X1292731Y331820D03*
X1300400Y339619D03*
Y344575D03*
X1290066Y804246D03*
X1319000Y566500D03*
Y582500D03*
Y613000D03*
Y629000D03*
Y657500D03*
Y673500D03*
Y704500D03*
Y720500D03*
X1305412Y799061D03*
X1318178Y1198321D03*
Y1200821D03*
X1325941Y408240D03*
X1328441D03*
X1323441D03*
X1326059Y420393D03*
X1326020Y424240D03*
X1323559Y420393D03*
X1328559D03*
X1326020Y426740D03*
X1335802Y896011D03*
X1332355Y1113822D03*
Y1119422D03*
X1334835Y1113822D03*
Y1119422D03*
X1331643Y1200821D03*
Y1198321D03*
X1344768Y769675D03*
X1337315Y1113822D03*
Y1119422D03*
X1345108Y1200821D03*
Y1198321D03*
X1361039Y327099D03*
Y332055D03*
X1364039Y334973D03*
Y339929D03*
X1361039Y342847D03*
X1364039Y350721D03*
X1361039Y347803D03*
X1364039Y355677D03*
X1360352Y447101D03*
X1364148Y896011D03*
X1364418Y1090568D03*
Y1093068D03*
X1366963Y1119422D03*
Y1113822D03*
X1364483Y1119422D03*
Y1113822D03*
X1380480Y102249D03*
X1384480D03*
X1384280Y195176D03*
X1381780D03*
X1384140Y203393D03*
X1381640D03*
X1384253Y346826D03*
X1384447Y356871D03*
X1384174Y362641D03*
X1379896Y870814D03*
Y883413D03*
X1383046Y899161D03*
X1369443Y1119422D03*
Y1113822D03*
X1388480Y102249D03*
X1389580Y195176D03*
X1386780D03*
X1390328Y206838D03*
X1387828D03*
X1385943Y323222D03*
X1385971Y327688D03*
X1386143Y331982D03*
X1386057Y341200D03*
X1385971Y336791D03*
X1386286Y350218D03*
X1397079Y531726D03*
Y536726D03*
Y552726D03*
Y540726D03*
X1397942Y1119422D03*
X1400422D03*
Y1113822D03*
X1397942D03*
X1391380Y1200821D03*
Y1198321D03*
X1417248Y102323D03*
X1416347Y384373D03*
X1406910Y487982D03*
Y478982D03*
Y483982D03*
Y499982D03*
X1410000Y689000D03*
Y705000D03*
Y733000D03*
Y749000D03*
X1402902Y1119422D03*
Y1113822D03*
X1404845Y1198321D03*
Y1200821D03*
X1404239Y1547755D03*
X1403747Y1570433D03*
X1417500Y109410D03*
Y116496D03*
X1421700Y122900D03*
X1418725Y130670D03*
X1418720Y137756D03*
X1427484Y470045D03*
X1422903Y469905D03*
X1430930Y500086D03*
X1432955Y527449D03*
X1421099Y546830D03*
X1427000Y774500D03*
Y790500D03*
Y818500D03*
Y834500D03*
X1430005Y1090568D03*
Y1093068D03*
X1432550Y1119422D03*
Y1113822D03*
X1430070Y1119422D03*
Y1113822D03*
X1418310Y1198321D03*
Y1200821D03*
X1435358Y116496D03*
Y109410D03*
Y102323D03*
Y130670D03*
Y123583D03*
Y137756D03*
X1440399Y236611D03*
X1442899D03*
X1445399D03*
X1440101Y248891D03*
X1442601D03*
X1445101D03*
X1435484Y470045D03*
X1442786Y480705D03*
X1445586D03*
X1435755Y527449D03*
X1443555Y532949D03*
X1446355D03*
X1435030Y1119422D03*
Y1113822D03*
X1437293Y1546125D03*
X1436801Y1568803D03*
X1451215Y323193D03*
X1451330Y327588D03*
X1451272Y340971D03*
X1451344Y336620D03*
X1451300Y332225D03*
X1451387Y345609D03*
X1451186Y350447D03*
X1472489Y91951D03*
X1479500Y706500D03*
Y750500D03*
X1487836Y-87777D03*
X1491089D03*
X1487851Y-85262D03*
X1491104D03*
X1484811Y-86371D03*
X1490842Y102249D03*
X1486842D03*
X1482842D03*
X1486642Y195176D03*
X1489142D03*
X1484142D03*
X1491942D03*
X1492690Y206838D03*
X1490190D03*
X1484002Y203393D03*
X1486502D03*
X1484796Y320359D03*
X1484968Y325025D03*
X1484876Y329377D03*
X1488255Y342921D03*
X1484682Y338394D03*
X1497760Y336543D03*
X1487926Y347387D03*
X1496500Y792000D03*
Y836000D03*
X1500480Y295727D03*
X1523192Y-48857D03*
X1526445D03*
X1523207Y-46342D03*
X1526460D03*
X1520167Y-47451D03*
X1519610Y102323D03*
X1519862Y109410D03*
Y116496D03*
X1520034Y124576D03*
X1521087Y130670D03*
X1521082Y137756D03*
X1527876Y939439D03*
X1537720Y116496D03*
Y109410D03*
Y102323D03*
Y130670D03*
Y123583D03*
Y137756D03*
X1542761Y236611D03*
X1545261D03*
X1542463Y248891D03*
X1544963D03*
X1541534Y322850D03*
X1547761Y236611D03*
X1547463Y248891D03*
X1547972Y304906D03*
X1556151Y318596D03*
X1556294Y327814D03*
X1556437Y332022D03*
X1556380Y336917D03*
X1556498Y340958D03*
X1556353Y345636D03*
X1556429Y389154D03*
Y396240D03*
X1557708Y404911D03*
X1556662Y412571D03*
X1557849Y426299D03*
X1558160Y445847D03*
X1556429Y467539D03*
Y474626D03*
X1556690Y480828D03*
X1558640Y498834D03*
X1556429Y518760D03*
Y511673D03*
Y525847D03*
X1562385Y598400D03*
Y602400D03*
Y594400D03*
Y614400D03*
Y606400D03*
X1574851Y91951D03*
X1574845Y338843D03*
X1574540Y389154D03*
Y396240D03*
Y403327D03*
Y410413D03*
Y417500D03*
Y424586D03*
Y438760D03*
Y431673D03*
Y445847D03*
Y467539D03*
Y474626D03*
Y488799D03*
Y481713D03*
Y495886D03*
Y511673D03*
Y518760D03*
Y540020D03*
Y525847D03*
Y532933D03*
Y547106D03*
Y554193D03*
Y602205D03*
Y595118D03*
X1593204Y102249D03*
X1585204D03*
X1589204D03*
X1586504Y195176D03*
X1594304D03*
X1589004D03*
X1591504D03*
X1586364Y203393D03*
X1588864D03*
X1595052Y206838D03*
X1592552D03*
X1593290Y339876D03*
X1597006Y290417D03*
X1599527Y392718D03*
Y408718D03*
Y400718D03*
Y404718D03*
Y412718D03*
X1621972Y102323D03*
X1622224Y109410D03*
Y116496D03*
X1622396Y124576D03*
X1623449Y130670D03*
X1623444Y137756D03*
X1640082Y116496D03*
Y109410D03*
Y102323D03*
Y130670D03*
Y123583D03*
Y137756D03*
X1644825Y248891D03*
X1632230Y330400D03*
X1645123Y236611D03*
X1650123D03*
X1647623D03*
X1647325Y248891D03*
X1649825D03*
X1655555Y430760D03*
X1655576Y433570D03*
X1655392Y437072D03*
X1655433Y439963D03*
X1655677Y443180D03*
X1655697Y454744D03*
X1655639Y452018D03*
X1645465Y466027D03*
X1645607Y475262D03*
Y489435D03*
Y482666D03*
X1645423Y495088D03*
X1646158Y514608D03*
X1646080Y522134D03*
X1645465Y509626D03*
X1646562Y535677D03*
X1646723Y529136D03*
X1645465Y559665D03*
X1645846Y565574D03*
X1645493Y574338D03*
X1645592Y616358D03*
X1677213Y91951D03*
X1663760Y410394D03*
Y403307D03*
X1663576Y458406D03*
Y465492D03*
Y472579D03*
Y479665D03*
Y486752D03*
Y493839D03*
Y523799D03*
Y516713D03*
Y509626D03*
Y537973D03*
Y530886D03*
Y559665D03*
Y566752D03*
Y580925D03*
Y588012D03*
Y573839D03*
Y602185D03*
Y595099D03*
Y616358D03*
Y609272D03*
X1695566Y102249D03*
X1687566D03*
X1691566D03*
X1691366Y195176D03*
X1688866D03*
X1691226Y203393D03*
X1688726D03*
X1691117Y321649D03*
X1696666Y195176D03*
X1693866D03*
X1697414Y206838D03*
X1694914D03*
X1698839Y564843D03*
X1724334Y102323D03*
X1724586Y109410D03*
Y116496D03*
X1724758Y124576D03*
X1725811Y130670D03*
X1725806Y137756D03*
X1715705Y328692D03*
X1712734Y340534D03*
X1742336Y-87777D03*
X1739311Y-86371D03*
X1734826Y376499D03*
X1745589Y-87777D03*
X1742351Y-85262D03*
X1745604D03*
X1742444Y102323D03*
Y116496D03*
Y109410D03*
Y130670D03*
Y123583D03*
Y137756D03*
X1752485Y236611D03*
X1749985D03*
X1747485D03*
X1747187Y248891D03*
X1749687D03*
X1752187D03*
X1747561Y385161D03*
X1758583Y1581027D03*
X1750685Y1618504D03*
X1756422Y1640303D03*
X1770680Y926322D03*
X1763818Y926241D03*
X1765294Y1575434D03*
X1759092Y1588137D03*
X1767142Y1588219D03*
X1764422Y1640303D03*
X1779575Y91951D03*
X1790533Y303750D03*
X1783028Y408240D03*
X1785528D03*
X1780528D03*
X1783107Y424240D03*
X1780646Y420393D03*
X1785646D03*
X1783146D03*
X1783107Y426740D03*
X1780397Y1237469D03*
Y1230569D03*
Y1228069D03*
Y1234969D03*
Y1241869D03*
Y1244369D03*
Y1248769D03*
Y1251269D03*
X1776422Y1640303D03*
X1804667Y-47581D03*
X1804993Y297591D03*
X1807692Y-49001D03*
X1810945Y-48987D03*
X1807707Y-46486D03*
X1810960Y-46472D03*
X1817439Y447101D03*
G54D31*
X106586Y1204932D03*
X563673D03*
X1020434Y1205579D03*
X1477846Y1204932D03*
G54D39*
X190325Y368760D03*
Y455492D03*
Y503760D03*
Y583957D03*
Y636752D03*
X647411Y368760D03*
Y455492D03*
Y503760D03*
Y583957D03*
Y636752D03*
X1104498Y368760D03*
Y455492D03*
Y503760D03*
Y583957D03*
Y636752D03*
X1561585Y368760D03*
Y455492D03*
Y503760D03*
Y583957D03*
Y636752D03*
G54D43*
X515573Y692515D03*
X518299Y692384D03*
X520799D03*
X529493Y692443D03*
Y697443D03*
Y699943D03*
X529501Y702622D03*
X526993Y692443D03*
X529493Y694943D03*
X524493Y692443D03*
X1809078Y2165771D03*
X1806706Y2180760D03*
X1812366Y2063809D03*
X1822066Y2054109D03*
X1812366D03*
X1813087Y2087512D03*
X1825427Y2104853D03*
X1817378Y2165771D03*
X1815006Y2180760D03*
X1841295Y2065122D03*
X1832995D03*
X1833649Y2057507D03*
X1830872Y2083503D03*
X1840875Y2083215D03*
X1837649Y2072324D03*
X1829349D03*
X1833727Y2104853D03*
X1835862Y2121040D03*
X1833506Y2185252D03*
X1852032Y2052576D03*
X1854559Y2077931D03*
X1851762Y2121040D03*
X1854796Y2170548D03*
X1846496D03*
X1855978Y2185118D03*
X1847678D03*
X1859032Y2052576D03*
X1870505Y2064156D03*
X1860338Y2071384D03*
X1874505Y2078973D03*
X1860234Y2157701D03*
X1867072Y2174962D03*
X1864547Y2185020D03*
X1890039Y2066092D03*
X1878805Y2064156D03*
X1886128Y2075919D03*
X1882805Y2078973D03*
X1876497Y2070684D03*
X1884535Y2155415D03*
X1882972Y2174962D03*
X1882111Y2179074D03*
X1874932Y2180585D03*
X1881852Y2196600D03*
X1886699Y2183170D03*
X1876697D03*
X1905939Y2066092D03*
X1893118Y2054585D03*
X1905944Y2055424D03*
X1898342Y2062143D03*
X1901295Y2072745D03*
X1892835Y2155415D03*
X1902872Y2178531D03*
X1894572D03*
X1893087Y2168011D03*
X1896403Y2185019D03*
X1917195Y2072745D03*
X1917550Y2158451D03*
X1909250D03*
X1922010Y2151829D03*
X1913710D03*
X1921855Y2172152D03*
X1936295Y2074343D03*
X1935195Y2155918D03*
X1936377Y2163810D03*
X1924735Y2178131D03*
X1936212Y2173508D03*
X1930155Y2172152D03*
X1931738Y2182647D03*
X1923438D03*
X1941040Y2070124D03*
X1951095Y2155918D03*
X1946077Y2163810D03*
X1969128Y2161283D03*
X1959428D03*
X1969128Y2151583D03*
X1959428D03*
G54D51*
X909360Y230906D03*
Y274606D03*
G54D22*
X51043Y144095D03*
X57933Y66811D03*
X160295D03*
X153405Y144095D03*
X183435Y630650D03*
X190325Y374862D03*
X262657Y66811D03*
X255767Y144095D03*
X279360Y630650D03*
X286250Y374862D03*
X358129Y144095D03*
X365019Y66811D03*
X508130Y144095D03*
X515020Y66811D03*
X617382D03*
X610492Y144095D03*
X647411Y374862D03*
X640521Y630650D03*
X719744Y66811D03*
X712854Y144095D03*
X736446Y630650D03*
X743336Y374862D03*
X815216Y144095D03*
X822106Y66811D03*
X972106D03*
X965216Y144095D03*
X1074468Y66811D03*
X1067578Y144095D03*
X1104498Y374862D03*
X1097608Y630650D03*
X1169940Y144095D03*
X1176830Y66811D03*
X1200423Y374862D03*
X1193533Y630650D03*
X1272302Y144095D03*
X1279192Y66811D03*
X1429193D03*
X1422303Y144095D03*
X1531555Y66811D03*
X1524665Y144095D03*
X1561585Y374862D03*
X1554695Y630650D03*
X1627027Y144095D03*
X1633917Y66811D03*
X1657510Y374862D03*
X1650620Y630650D03*
X1736279Y66811D03*
X1729389Y144095D03*
G54D25*
X46248Y1760941D03*
Y1750941D03*
Y1806941D03*
Y1796941D03*
X143208Y1084547D03*
Y1092027D03*
X146948Y1077066D03*
Y1084547D03*
Y1092027D03*
X143208Y1095767D03*
X146948D03*
X143208Y1110728D03*
Y1118208D03*
X146948Y1110728D03*
Y1118208D03*
X146949Y1166830D03*
X154429Y1073326D03*
X161909D03*
X154429Y1092027D03*
X161909Y1077066D03*
X165649Y1080807D03*
Y1088287D03*
X161909D03*
Y1092027D03*
X154429Y1077066D03*
X158169Y1080807D03*
X150689D03*
X158169Y1084547D03*
X150689D03*
X158169Y1088287D03*
X154429D03*
X150689D03*
X165649Y1084547D03*
X158169Y1099507D03*
X150689D03*
X158169Y1103247D03*
X150689D03*
X161909Y1095767D03*
X165649Y1099507D03*
Y1103247D03*
X154429Y1106988D03*
X150689D03*
X154429Y1095767D03*
X158169Y1110728D03*
Y1114468D03*
X154429D03*
X150689D03*
X158169Y1129429D03*
X165649Y1166830D03*
Y1170570D03*
Y1178050D03*
Y1174310D03*
X163779Y1213582D03*
X160039D03*
X214271Y1114468D03*
X238582Y1078936D03*
X242322Y1082677D03*
X238582Y1097637D03*
X246062Y1254724D03*
X238582D03*
Y1250984D03*
X234842Y1247243D03*
X242322Y1243503D03*
Y1247243D03*
X246062Y1250984D03*
X249803Y1082677D03*
X257283D03*
X249803Y1101377D03*
X253543Y1250984D03*
Y1254724D03*
X249803Y1247243D03*
X253543Y1239763D03*
X249803D03*
X257283Y1247243D03*
X261023Y1250984D03*
Y1239763D03*
Y1254724D03*
X279724Y1082677D03*
Y1086417D03*
X275984Y1078936D03*
X264763Y1082677D03*
X275984Y1097637D03*
X274114Y1121948D03*
X277854Y1133169D03*
Y1125688D03*
X274114Y1204232D03*
X279724Y1247243D03*
X272244Y1243503D03*
Y1247243D03*
X264763D03*
X268503Y1250984D03*
X264763Y1243503D03*
X272244Y1239763D03*
X275984Y1250984D03*
X279724Y1243503D03*
X268503Y1254724D03*
X275984D03*
X294684Y1082677D03*
Y1090157D03*
X294685Y1086417D03*
X290944Y1078936D03*
X287204Y1082677D03*
X283464Y1093897D03*
X290944Y1097637D03*
X294685Y1247243D03*
Y1243503D03*
X283464Y1250984D03*
X287204Y1247243D03*
Y1243503D03*
Y1239763D03*
X290944Y1250984D03*
X283464Y1254724D03*
X290944D03*
X302164Y1082677D03*
X302165Y1086417D03*
X309644Y1082677D03*
X309645Y1086417D03*
X298425Y1097637D03*
X305905D03*
X300295Y1155610D03*
X309645Y1247243D03*
Y1243503D03*
X298425Y1250984D03*
X302165Y1247243D03*
Y1243503D03*
Y1239763D03*
X305905Y1250984D03*
X298425Y1254724D03*
X305905D03*
X320866Y1086417D03*
X317126D03*
X317125Y1082677D03*
X324606Y1086417D03*
X320866Y1093897D03*
X324606D03*
Y1105117D03*
Y1097637D03*
X320866Y1105117D03*
Y1097637D03*
X313385D03*
X324606Y1112598D03*
Y1120078D03*
X320866Y1112598D03*
Y1120078D03*
X317125Y1108858D03*
X320866Y1127558D03*
Y1135039D03*
X322736Y1140649D03*
X324606Y1127558D03*
Y1135039D03*
X326476Y1140649D03*
X322736Y1155610D03*
X326476Y1148129D03*
Y1155610D03*
X322736Y1148129D03*
X326476Y1170570D03*
Y1178051D03*
Y1185531D03*
X320866Y1250984D03*
X313385D03*
X317125Y1247243D03*
Y1243503D03*
X313385Y1254724D03*
X317125Y1239763D03*
X320866Y1254724D03*
X333286Y1728583D03*
Y1738583D03*
X333212Y1774624D03*
Y1784624D03*
X438162Y1348187D03*
Y1360099D03*
Y1384297D03*
Y1372385D03*
X450402Y1348187D03*
Y1360099D03*
Y1384297D03*
Y1372385D03*
Y1396583D03*
Y1408495D03*
X462642Y1348187D03*
X474882D03*
X462642Y1360099D03*
X474882D03*
X462642Y1384297D03*
X474882D03*
X462642Y1372385D03*
X474882D03*
Y1396583D03*
X462642D03*
X474882Y1408495D03*
X462642D03*
X487122Y1348187D03*
Y1360099D03*
Y1372385D03*
Y1384297D03*
Y1396583D03*
Y1408495D03*
X499362Y1348187D03*
Y1360099D03*
Y1372385D03*
Y1384297D03*
Y1396583D03*
Y1408495D03*
X511602Y1348187D03*
Y1360099D03*
Y1372385D03*
Y1384297D03*
Y1396583D03*
Y1408495D03*
X536082Y1348187D03*
X523842D03*
X536082Y1360099D03*
X523842D03*
Y1384297D03*
Y1372385D03*
X536082Y1384297D03*
Y1372385D03*
Y1396583D03*
X523842D03*
X536082Y1408495D03*
X523842D03*
X548322Y1348187D03*
Y1360099D03*
Y1384297D03*
Y1372385D03*
Y1396583D03*
Y1408495D03*
X560562Y1348187D03*
Y1360099D03*
Y1384297D03*
Y1372385D03*
Y1396583D03*
Y1408495D03*
X600295Y1084547D03*
Y1092027D03*
X604035Y1077066D03*
Y1084547D03*
Y1092027D03*
X600295Y1095767D03*
X604035D03*
X600295Y1110728D03*
Y1118208D03*
X604035Y1110728D03*
Y1118208D03*
X604036Y1166830D03*
X611516Y1073326D03*
X618996D03*
Y1088287D03*
Y1092027D03*
X611516Y1077066D03*
X615256Y1080807D03*
X607776D03*
X615256Y1084547D03*
X607776D03*
X615256Y1088287D03*
X611516D03*
X607776D03*
X611516Y1092027D03*
X618996Y1077066D03*
X611516Y1106988D03*
X607776D03*
X611516Y1095767D03*
X615256Y1099507D03*
X607776D03*
X615256Y1103247D03*
X607776D03*
X618996Y1095767D03*
X615256Y1110728D03*
Y1114468D03*
X611516D03*
X607776D03*
X615256Y1129429D03*
X617126Y1213582D03*
X620866D03*
X620083Y1728286D03*
Y1738286D03*
X619711Y1775438D03*
Y1785438D03*
X626476Y1088287D03*
X622736Y1080807D03*
Y1084547D03*
Y1088287D03*
Y1099507D03*
Y1103247D03*
Y1166830D03*
Y1170570D03*
Y1174310D03*
Y1178050D03*
X636288Y1372385D03*
Y1384297D03*
Y1396583D03*
X624048D03*
X636288Y1408495D03*
X624048D03*
X648528Y1348187D03*
Y1360099D03*
Y1372385D03*
Y1384297D03*
Y1396583D03*
Y1408495D03*
X660768Y1348187D03*
Y1360099D03*
Y1372385D03*
Y1384297D03*
Y1396583D03*
Y1408495D03*
X671358Y1114468D03*
X673008Y1348187D03*
X685248D03*
X673008Y1360099D03*
X685248D03*
Y1372385D03*
Y1384297D03*
X673008Y1372385D03*
Y1384297D03*
X685248Y1396583D03*
X673008D03*
X685248Y1408495D03*
X673008D03*
X695669Y1078936D03*
X699409Y1082677D03*
X695669Y1097637D03*
X699409Y1247243D03*
Y1243503D03*
X691929Y1247243D03*
X695669Y1250984D03*
Y1254724D03*
X697488Y1348187D03*
Y1360099D03*
Y1384297D03*
Y1372385D03*
Y1396583D03*
Y1408495D03*
X706890Y1082677D03*
X714370D03*
X706890Y1101377D03*
X703149Y1254724D03*
Y1250984D03*
X718110D03*
Y1239763D03*
X714370Y1247243D03*
X710630Y1254724D03*
Y1250984D03*
Y1239763D03*
X706890Y1247243D03*
Y1239763D03*
X718110Y1254724D03*
X709728Y1348187D03*
Y1360099D03*
Y1384297D03*
Y1372385D03*
Y1396583D03*
Y1408495D03*
X721850Y1082677D03*
X733071Y1078936D03*
Y1097637D03*
X731201Y1121948D03*
X734941Y1125688D03*
Y1133169D03*
X731201Y1204232D03*
X729331Y1243503D03*
X721850D03*
X729331Y1239763D03*
Y1247243D03*
X733071Y1250984D03*
Y1254724D03*
X725590D03*
Y1250984D03*
X721850Y1247243D03*
X734208Y1348187D03*
X721968D03*
X734208Y1360099D03*
X721968D03*
Y1384297D03*
Y1372385D03*
X734208D03*
Y1384297D03*
X721968Y1396489D03*
X734208D03*
X721968Y1408401D03*
X734208D03*
X744291Y1082677D03*
X748031Y1078936D03*
X736811Y1086417D03*
Y1082677D03*
X748031Y1097637D03*
X740551Y1093897D03*
X736811Y1243503D03*
Y1247243D03*
X744291Y1243503D03*
Y1239763D03*
X748031Y1254724D03*
Y1250984D03*
X744291Y1247243D03*
X740551Y1254724D03*
Y1250984D03*
X746448Y1348187D03*
Y1360099D03*
Y1372385D03*
Y1384297D03*
X759251Y1082677D03*
X751772Y1086417D03*
X751771Y1090157D03*
Y1082677D03*
X759252Y1086417D03*
X766732D03*
X766731Y1082677D03*
X762992Y1097637D03*
X755512D03*
X757382Y1155610D03*
X755512Y1250984D03*
Y1254724D03*
X759252Y1247243D03*
Y1243503D03*
X762992Y1250984D03*
Y1254724D03*
X766732Y1247243D03*
Y1243503D03*
X759252Y1239763D03*
X751772Y1247243D03*
Y1243503D03*
X758688Y1348187D03*
Y1360099D03*
Y1372385D03*
Y1384297D03*
X774213Y1086417D03*
X774212Y1082677D03*
X781693Y1086417D03*
X777953D03*
X770472Y1097637D03*
X777953Y1093897D03*
Y1105117D03*
X781693Y1093897D03*
Y1097637D03*
X777953D03*
X781693Y1105117D03*
Y1112598D03*
X777953Y1120078D03*
X781693D03*
X774212Y1108858D03*
X777953Y1112598D03*
X783563Y1140649D03*
X779823D03*
X781693Y1127558D03*
X777953D03*
Y1135039D03*
X781693D03*
X783563Y1155610D03*
Y1148129D03*
X779823Y1155610D03*
Y1148129D03*
X783563Y1170570D03*
Y1185531D03*
Y1178051D03*
X770472Y1250984D03*
Y1254724D03*
X777953Y1250984D03*
X774212Y1247243D03*
Y1243503D03*
Y1239763D03*
X777953Y1254724D03*
X770928Y1348187D03*
Y1360099D03*
X907279Y1738990D03*
Y1728990D03*
X907073Y1776014D03*
Y1786014D03*
X1057381Y1092027D03*
Y1084547D03*
Y1095767D03*
Y1118208D03*
Y1110728D03*
X1068602Y1073326D03*
X1072342Y1088287D03*
Y1084547D03*
Y1080807D03*
X1061121Y1092027D03*
X1068602D03*
X1064862Y1088287D03*
X1068602D03*
X1061121Y1084547D03*
X1064862D03*
Y1080807D03*
X1061121Y1077066D03*
X1068602D03*
X1072342Y1099507D03*
Y1103247D03*
X1061121Y1095767D03*
X1068602D03*
X1064862Y1106988D03*
X1068602D03*
X1064862Y1103247D03*
Y1099507D03*
X1072342Y1114468D03*
Y1110728D03*
X1061121Y1118208D03*
X1064862Y1114468D03*
X1068602D03*
X1061121Y1110728D03*
X1072342Y1129429D03*
X1061122Y1166830D03*
X1074212Y1213582D03*
X1076082Y1073326D03*
X1083562Y1088287D03*
X1079822D03*
Y1084547D03*
Y1080807D03*
X1076082Y1092027D03*
Y1088287D03*
Y1077066D03*
X1079822Y1103247D03*
Y1099507D03*
X1076082Y1095767D03*
X1079822Y1170570D03*
Y1166830D03*
Y1174310D03*
Y1178050D03*
X1077952Y1213582D03*
X1128444Y1114468D03*
X1152755Y1078936D03*
X1156495Y1082677D03*
X1152755Y1097637D03*
Y1254724D03*
Y1250984D03*
X1149015Y1247243D03*
X1156495Y1243503D03*
Y1247243D03*
X1163976Y1082677D03*
X1171456D03*
X1163976Y1101377D03*
Y1239763D03*
Y1247243D03*
X1167716Y1239763D03*
Y1250984D03*
Y1254724D03*
X1171456Y1247243D03*
X1160235Y1250984D03*
Y1254724D03*
X1178936Y1082677D03*
X1188287Y1121948D03*
Y1204232D03*
X1175196Y1254724D03*
Y1239763D03*
Y1250984D03*
X1178936Y1247243D03*
X1182676Y1250984D03*
Y1254724D03*
X1186417Y1247243D03*
Y1239763D03*
X1178936Y1243503D03*
X1186417D03*
X1190157Y1078936D03*
X1201377Y1082677D03*
X1205117Y1078936D03*
X1193897Y1082677D03*
Y1086417D03*
X1190157Y1097637D03*
X1197637Y1093897D03*
X1205117Y1097637D03*
X1192027Y1133169D03*
Y1125688D03*
X1190157Y1254724D03*
Y1250984D03*
X1197637D03*
Y1254724D03*
X1201377Y1247243D03*
X1205117Y1250984D03*
Y1254724D03*
X1201377Y1239763D03*
Y1243503D03*
X1193897Y1247243D03*
Y1243503D03*
X1216337Y1082677D03*
X1216338Y1086417D03*
X1208857Y1082677D03*
X1208858Y1086417D03*
X1208857Y1090157D03*
X1212598Y1097637D03*
X1220078D03*
X1214468Y1155610D03*
X1212598Y1250984D03*
Y1254724D03*
X1216338Y1247243D03*
Y1243503D03*
X1220078Y1250984D03*
Y1254724D03*
X1216338Y1239763D03*
X1208858Y1247243D03*
Y1243503D03*
X1223817Y1082677D03*
X1223818Y1086417D03*
X1231298Y1082677D03*
X1235039Y1086417D03*
X1231299D03*
X1227558Y1097637D03*
X1235039Y1093897D03*
Y1097637D03*
Y1105117D03*
X1231298Y1108858D03*
X1235039Y1112598D03*
Y1120078D03*
X1236909Y1140649D03*
X1235039Y1127558D03*
Y1135039D03*
X1236909Y1148129D03*
Y1155610D03*
X1223818Y1247243D03*
Y1243503D03*
X1227558Y1250984D03*
Y1254724D03*
X1235039Y1250984D03*
X1231298Y1247243D03*
Y1243503D03*
Y1239763D03*
X1235039Y1254724D03*
X1238779Y1086417D03*
Y1093897D03*
Y1097637D03*
Y1105117D03*
Y1112598D03*
Y1120078D03*
X1240649Y1140649D03*
X1238779Y1127558D03*
Y1135039D03*
X1240649Y1148129D03*
Y1155610D03*
Y1170570D03*
Y1178051D03*
Y1185531D03*
X1514468Y1084547D03*
Y1092027D03*
Y1095767D03*
Y1110728D03*
Y1118208D03*
X1525689Y1073326D03*
Y1077066D03*
X1518208D03*
X1529429Y1080807D03*
X1521949D03*
X1529429Y1084547D03*
X1521949D03*
X1518208D03*
X1529429Y1088287D03*
X1525689D03*
X1521949D03*
X1525689Y1092027D03*
X1518208D03*
X1521949Y1103247D03*
X1525689Y1106988D03*
X1521949D03*
X1525689Y1095767D03*
X1518208D03*
X1529429Y1099507D03*
X1521949D03*
X1529429Y1103247D03*
Y1110728D03*
X1518208D03*
X1529429Y1114468D03*
X1525689D03*
X1521949D03*
X1518208Y1118208D03*
X1529429Y1129429D03*
X1518209Y1166830D03*
X1533169Y1073326D03*
X1540649Y1088287D03*
X1533169Y1077066D03*
X1536909Y1080807D03*
Y1084547D03*
Y1088287D03*
X1533169D03*
Y1092027D03*
Y1095767D03*
X1536909Y1099507D03*
Y1103247D03*
Y1166830D03*
Y1170570D03*
Y1174310D03*
X1535039Y1176180D03*
Y1213582D03*
X1531299D03*
X1585531Y1114468D03*
X1609842Y1078936D03*
Y1097637D03*
Y1254724D03*
Y1250984D03*
X1606102Y1247243D03*
X1613582Y1082677D03*
X1621063D03*
Y1101377D03*
X1613582Y1243503D03*
Y1247243D03*
X1621063Y1239763D03*
Y1247243D03*
X1624803Y1239763D03*
Y1250984D03*
Y1254724D03*
X1617322Y1250984D03*
Y1254724D03*
X1636023Y1082677D03*
X1628543D03*
X1632283Y1254724D03*
X1628543Y1247243D03*
X1632283Y1239763D03*
Y1250984D03*
X1636023Y1247243D03*
X1639763Y1250984D03*
Y1254724D03*
X1643504Y1247243D03*
Y1239763D03*
X1636023Y1243503D03*
X1643504D03*
X1658464Y1082677D03*
X1650984D03*
Y1086417D03*
X1647244Y1078936D03*
Y1097637D03*
X1654724Y1093897D03*
X1645374Y1121948D03*
X1649114Y1133169D03*
Y1125688D03*
X1645374Y1204232D03*
X1647244Y1254724D03*
Y1250984D03*
X1654724D03*
Y1254724D03*
X1658464Y1247243D03*
Y1239763D03*
Y1243503D03*
X1650984Y1247243D03*
Y1243503D03*
X1662204Y1078936D03*
X1673424Y1082677D03*
X1673425Y1086417D03*
X1665944Y1082677D03*
X1665945Y1086417D03*
X1665944Y1090157D03*
X1662204Y1097637D03*
X1669685D03*
X1671555Y1155610D03*
X1665945Y1247243D03*
Y1243503D03*
X1662204Y1250984D03*
Y1254724D03*
X1669685Y1250984D03*
Y1254724D03*
X1673425Y1247243D03*
Y1243503D03*
Y1239763D03*
X1680904Y1082677D03*
X1680905Y1086417D03*
X1688385Y1082677D03*
X1692126Y1086417D03*
X1688386D03*
X1677165Y1097637D03*
X1684645D03*
X1692126Y1093897D03*
Y1097637D03*
Y1105117D03*
X1688385Y1108858D03*
X1692126Y1112598D03*
Y1120078D03*
Y1127558D03*
Y1135039D03*
X1684645Y1250984D03*
Y1254724D03*
X1692126Y1250984D03*
X1688385Y1247243D03*
Y1243503D03*
Y1239763D03*
X1692126Y1254724D03*
X1677165Y1250984D03*
Y1254724D03*
X1680905Y1247243D03*
Y1243503D03*
X1695866Y1086417D03*
Y1093897D03*
Y1097637D03*
Y1105117D03*
Y1112598D03*
Y1120078D03*
X1697736Y1140649D03*
X1693996D03*
X1695866Y1127558D03*
Y1135039D03*
X1697736Y1148129D03*
X1693996D03*
X1697736Y1155610D03*
X1693996D03*
X1697736Y1170570D03*
Y1178051D03*
Y1185531D03*
G54D37*
X145078Y1250984D03*
X148818Y1243503D03*
Y1250984D03*
X145078Y1243503D03*
X161909Y1125688D03*
X158169Y1151869D03*
X154429D03*
Y1166830D03*
X160039Y1194881D03*
Y1202362D03*
Y1209842D03*
Y1217322D03*
X156299Y1250984D03*
X160039Y1247243D03*
X152559D03*
X156299Y1239763D03*
X163779Y1250984D03*
X156299Y1254724D03*
X163779D03*
X178740Y1075196D03*
X171259D03*
X178740Y1078936D03*
X174999Y1086417D03*
Y1082677D03*
X171259Y1078936D03*
X182480Y1086417D03*
Y1082677D03*
X174999Y1093897D03*
X182480D03*
X171259Y1097637D03*
X182480D03*
X174999D03*
X178740Y1101376D03*
Y1105117D03*
X173129Y1129428D03*
X169389D03*
X180610Y1170570D03*
X174999Y1209842D03*
X167519Y1221062D03*
X182480Y1236023D03*
Y1232283D03*
X174999D03*
Y1236023D03*
X182480Y1239763D03*
Y1247243D03*
X178740Y1250984D03*
Y1239763D03*
X174999Y1243503D03*
X178740Y1254724D03*
X171259D03*
X167519Y1247243D03*
X186220Y1075196D03*
X193700D03*
X189960Y1086417D03*
Y1082677D03*
X193700Y1078936D03*
X186220D03*
X197440Y1086417D03*
Y1082677D03*
X193700Y1105117D03*
X197440Y1093897D03*
X189960Y1097637D03*
X186220Y1105117D03*
X197440Y1097637D03*
X193700Y1101376D03*
X186220D03*
X188090Y1178051D03*
Y1193011D03*
X197440Y1236023D03*
Y1232283D03*
X189960Y1236023D03*
Y1232283D03*
X197440Y1247243D03*
X193700Y1254724D03*
X186220D03*
X189960Y1239763D03*
X186220Y1250984D03*
X189960Y1247243D03*
X193700Y1250984D03*
X201181Y1075196D03*
X208661D03*
Y1078936D03*
X212401Y1086417D03*
Y1082677D03*
X204921Y1086417D03*
Y1082677D03*
X201181Y1078936D03*
X204921Y1097637D03*
X208661Y1101376D03*
X212401Y1097637D03*
X208661Y1105117D03*
X212401Y1093897D03*
X201181Y1101376D03*
X204921Y1093897D03*
X201181Y1105117D03*
X204921Y1232283D03*
X212401D03*
Y1236023D03*
X204921D03*
X208661Y1250984D03*
X201181Y1239763D03*
X212401D03*
Y1247243D03*
X201181Y1254724D03*
X204921Y1239763D03*
X201181Y1250984D03*
X204921Y1247243D03*
X208661Y1254724D03*
X213969Y1445013D03*
Y1456013D03*
X223622Y1075196D03*
X231102D03*
X216141D03*
X227362Y1086417D03*
Y1082677D03*
X219881Y1086417D03*
Y1082677D03*
X223622Y1078936D03*
X231102D03*
X216141D03*
Y1101376D03*
X231102D03*
X227362Y1093897D03*
X219881Y1097637D03*
X223621Y1101376D03*
Y1105117D03*
X216141D03*
X219881Y1093897D03*
X227362Y1097637D03*
X231102Y1105117D03*
X219881Y1232283D03*
Y1236023D03*
X227362Y1232283D03*
Y1236023D03*
X223622Y1254724D03*
X231102D03*
X227362Y1247243D03*
X219881Y1239763D03*
X223622Y1250984D03*
X219881Y1247243D03*
X231102Y1250984D03*
X227362Y1239763D03*
X216141Y1250984D03*
Y1254724D03*
X227249Y1445013D03*
Y1456013D03*
X246062Y1221062D03*
X234842Y1239763D03*
Y1243503D03*
X242322Y1239763D03*
X257283Y1101377D03*
X249803Y1221062D03*
X253543D03*
X261023D03*
X257283D03*
X249803Y1243503D03*
X257283D03*
X272244Y1101377D03*
X279724D03*
X264763D03*
X277854Y1121948D03*
Y1129429D03*
X264763Y1221062D03*
X279724Y1239763D03*
X275984D03*
X264763D03*
X287204Y1086417D03*
X283464Y1097637D03*
X294684Y1101377D03*
X289074Y1144389D03*
X294685Y1198621D03*
Y1213582D03*
Y1206102D03*
Y1236023D03*
X290944Y1224803D03*
X294685Y1232283D03*
X290944Y1228543D03*
X294685Y1239763D03*
X302164Y1090157D03*
X305904D03*
X309644D03*
X302165Y1101377D03*
X309645D03*
Y1123818D03*
X309644Y1108858D03*
X309645Y1116338D03*
Y1131299D03*
X307775Y1140649D03*
X298425Y1135039D03*
Y1127558D03*
X300295Y1151869D03*
Y1144389D03*
X307775Y1148129D03*
Y1155610D03*
Y1159350D03*
X298425Y1198621D03*
X305905Y1202362D03*
X302165D03*
X298425Y1213582D03*
X305905Y1209842D03*
Y1217322D03*
X302165Y1209842D03*
X298425Y1206102D03*
X302165Y1217322D03*
Y1232283D03*
X309645D03*
X298425Y1224803D03*
Y1228543D03*
X309645Y1236023D03*
X305905Y1228543D03*
Y1224803D03*
X302165Y1236023D03*
X305905Y1239763D03*
X317125Y1090157D03*
X317126Y1105117D03*
X317125Y1101377D03*
X318996Y1136909D03*
X317125Y1131299D03*
X318996Y1144389D03*
Y1151869D03*
X322736Y1166830D03*
X318996Y1159350D03*
Y1166830D03*
X326476D03*
X318996Y1189271D03*
Y1181791D03*
Y1174310D03*
X317125Y1198621D03*
X320866D03*
X313385Y1202362D03*
X324606Y1198621D03*
X317125Y1202362D03*
Y1206102D03*
Y1213582D03*
Y1217322D03*
Y1209842D03*
X324606Y1213582D03*
X313385Y1209842D03*
X320866Y1213582D03*
X324606Y1206102D03*
X313385Y1217322D03*
X317125Y1236023D03*
X313385Y1224803D03*
X324606Y1228543D03*
X317125Y1232283D03*
X313385Y1228543D03*
X320866D03*
Y1243503D03*
X313385Y1239763D03*
X320866Y1247243D03*
X324606D03*
X602165Y1228543D03*
Y1243503D03*
Y1250984D03*
X618996Y1125688D03*
Y1133169D03*
X615256Y1151869D03*
X611516D03*
Y1166830D03*
X617126Y1202362D03*
Y1194881D03*
Y1209842D03*
Y1217322D03*
X605905Y1228543D03*
X609646Y1232283D03*
X617126Y1236023D03*
Y1232283D03*
X609646Y1236023D03*
X613386Y1239763D03*
X620866Y1254724D03*
Y1250984D03*
X617126Y1247243D03*
X609646D03*
X613386Y1254724D03*
Y1250984D03*
X605905Y1243503D03*
Y1254724D03*
Y1250984D03*
X626476Y1073326D03*
X635827Y1075196D03*
X628346D03*
X626476Y1077066D03*
X628346Y1078936D03*
X635827D03*
X632086Y1082677D03*
Y1086417D03*
Y1097637D03*
X626476Y1099507D03*
X628346Y1097637D03*
X635827Y1105117D03*
X632086Y1093897D03*
X635827Y1101376D03*
X630216Y1129428D03*
X626476D03*
X630216Y1136909D03*
X626476D03*
X632086Y1209842D03*
X624606Y1221062D03*
X632086Y1232283D03*
Y1236023D03*
X624606Y1232283D03*
Y1236023D03*
X632086Y1243503D03*
X635827Y1239763D03*
Y1254724D03*
Y1250984D03*
X628346Y1254724D03*
X624606Y1247243D03*
X643307Y1075196D03*
X650787D03*
Y1078936D03*
X647047Y1082677D03*
Y1086417D03*
X643307Y1078936D03*
X639567Y1086417D03*
Y1082677D03*
X650787Y1105117D03*
X639567Y1097637D03*
X643307Y1105117D03*
X647047Y1097637D03*
X639567Y1093897D03*
X643307Y1101376D03*
X650787D03*
X637697Y1170570D03*
X645177Y1178051D03*
Y1193011D03*
X639567Y1236023D03*
X647047D03*
X639567Y1232283D03*
X647047D03*
X639567Y1239763D03*
Y1247243D03*
X647047Y1239763D03*
X650787Y1254724D03*
Y1250984D03*
X647047Y1247243D03*
X643307Y1254724D03*
Y1250984D03*
X658268Y1075196D03*
X665748D03*
X669488Y1086417D03*
X665748Y1078936D03*
X669488Y1082677D03*
X654527D03*
Y1086417D03*
X662008Y1082677D03*
Y1086417D03*
X658268Y1078936D03*
X662008Y1097637D03*
X654527Y1093897D03*
X669488D03*
X665748Y1105117D03*
X654527Y1097637D03*
X662008Y1093897D03*
X669488Y1097637D03*
X665748Y1101376D03*
X658268Y1105117D03*
Y1101376D03*
X654527Y1236023D03*
Y1232283D03*
Y1247243D03*
X662008Y1239763D03*
X658268D03*
X669488D03*
X665748Y1250984D03*
Y1254724D03*
X669488Y1247243D03*
X662008D03*
X658268Y1254724D03*
Y1250984D03*
X680709Y1075196D03*
X673228D03*
X684449Y1082677D03*
Y1086417D03*
X673228Y1078936D03*
X680709D03*
X676968Y1082677D03*
Y1086417D03*
X673228Y1105117D03*
X684449Y1093897D03*
X676968D03*
X684449Y1097637D03*
X676968D03*
X680708Y1105117D03*
X673228Y1101376D03*
X680708D03*
X676968Y1239763D03*
X680709Y1254724D03*
Y1250984D03*
X676968Y1247243D03*
X673228Y1254724D03*
Y1250984D03*
X684449Y1247243D03*
Y1239763D03*
X688189Y1075196D03*
Y1078936D03*
Y1105117D03*
Y1101376D03*
Y1254724D03*
Y1250984D03*
X699409Y1239763D03*
X691929D03*
Y1243503D03*
X714370Y1101377D03*
X718110Y1228543D03*
Y1224803D03*
X714370Y1243503D03*
X706890D03*
X729331Y1101377D03*
X721850D03*
X734941Y1121948D03*
Y1129429D03*
X725590Y1228543D03*
X733071D03*
X721850Y1236023D03*
X733071Y1224803D03*
X721850Y1232283D03*
X725590Y1224803D03*
X729331Y1236023D03*
Y1232283D03*
X733071Y1239763D03*
X721850D03*
X744291Y1086417D03*
X740551Y1097637D03*
X736811Y1101377D03*
X746161Y1144389D03*
X744291Y1236023D03*
X736811Y1232283D03*
X744291D03*
X736811Y1236023D03*
X740551Y1224803D03*
Y1228543D03*
X736811Y1239763D03*
X766731Y1090157D03*
X759251D03*
X762991D03*
X751771Y1101377D03*
X759252D03*
X766732D03*
X766731Y1108858D03*
X766732Y1116338D03*
Y1123818D03*
X764862Y1140649D03*
X766732Y1131299D03*
X755512Y1127558D03*
Y1135039D03*
X764862Y1155610D03*
Y1148129D03*
X757382Y1144389D03*
Y1151869D03*
X764862Y1159350D03*
X762992Y1239763D03*
X751772D03*
X774212Y1090157D03*
Y1101377D03*
X774213Y1105117D03*
X774212Y1131299D03*
X776083Y1151869D03*
Y1144389D03*
X783563Y1166830D03*
X776083D03*
Y1159350D03*
X779823Y1166830D03*
X776083Y1174310D03*
Y1181791D03*
Y1196751D03*
X774212Y1198621D03*
Y1213582D03*
Y1206102D03*
X777953Y1243503D03*
X770472Y1239763D03*
X1059251Y1243503D03*
Y1250984D03*
X1072342Y1151869D03*
X1068602D03*
Y1166830D03*
X1074212Y1194881D03*
Y1202362D03*
Y1217322D03*
Y1209842D03*
X1070472Y1250984D03*
Y1254724D03*
X1066732Y1247243D03*
X1074212D03*
X1070472Y1239763D03*
X1062991Y1250984D03*
Y1254724D03*
Y1243503D03*
X1083562Y1073326D03*
Y1077066D03*
X1089172Y1082677D03*
Y1086417D03*
Y1097637D03*
Y1093897D03*
X1083562Y1099507D03*
Y1136909D03*
X1087302D03*
X1083562Y1129428D03*
X1087302D03*
X1076082Y1133169D03*
Y1125688D03*
X1089172Y1209842D03*
X1081692Y1221062D03*
X1089172Y1232283D03*
Y1236023D03*
X1077952Y1250984D03*
Y1254724D03*
X1081692Y1247243D03*
X1085432Y1254724D03*
X1089172Y1243503D03*
X1092913Y1075196D03*
X1107873D03*
X1100393D03*
X1092913Y1078936D03*
X1104133Y1086417D03*
Y1082677D03*
X1107873Y1078936D03*
X1100393D03*
X1096653Y1082677D03*
Y1086417D03*
X1092913Y1105117D03*
X1104133Y1097637D03*
X1096653D03*
X1100393Y1105117D03*
Y1101376D03*
X1096653Y1093897D03*
X1092913Y1101376D03*
X1107873Y1105117D03*
Y1101376D03*
X1094783Y1170570D03*
X1102263Y1178051D03*
Y1193011D03*
X1104133Y1236023D03*
Y1232283D03*
X1096653Y1236023D03*
Y1232283D03*
X1092913Y1250984D03*
Y1254724D03*
Y1239763D03*
X1100393Y1250984D03*
Y1254724D03*
X1104133Y1247243D03*
X1107873Y1250984D03*
Y1254724D03*
X1104133Y1239763D03*
X1096653Y1247243D03*
Y1239763D03*
X1115354Y1075196D03*
X1122834D03*
X1115354Y1078936D03*
X1119094Y1082677D03*
Y1086417D03*
X1122834Y1078936D03*
X1111613Y1082677D03*
Y1086417D03*
X1119094Y1097637D03*
X1115354Y1101376D03*
X1111613Y1093897D03*
Y1097637D03*
X1122834Y1105117D03*
X1119094Y1093897D03*
X1122834Y1101376D03*
X1115354Y1105117D03*
X1119094Y1232283D03*
X1111613D03*
X1119094Y1236023D03*
X1111613D03*
X1115354Y1250984D03*
Y1254724D03*
X1119094Y1247243D03*
X1122834Y1254724D03*
Y1250984D03*
X1115354Y1239763D03*
X1119094D03*
X1111613Y1247243D03*
X1130314Y1075196D03*
X1137795D03*
X1126574Y1086417D03*
Y1082677D03*
X1130314Y1078936D03*
X1134054Y1082677D03*
Y1086417D03*
X1137795Y1078936D03*
X1126574Y1093897D03*
X1130314Y1105117D03*
X1134054Y1093897D03*
X1130314Y1101376D03*
X1134054Y1097637D03*
X1137794Y1105117D03*
X1126574Y1097637D03*
X1137794Y1101376D03*
X1134054Y1236023D03*
Y1232283D03*
X1126574D03*
Y1236023D03*
Y1247243D03*
Y1239763D03*
X1130314Y1250984D03*
Y1254724D03*
X1134054Y1247243D03*
X1137795Y1250984D03*
Y1254724D03*
X1134054Y1239763D03*
X1145275Y1075196D03*
X1141535Y1082677D03*
Y1086417D03*
X1145275Y1078936D03*
Y1105117D03*
X1141535Y1093897D03*
X1145275Y1101376D03*
X1141535Y1097637D03*
Y1236023D03*
Y1232283D03*
Y1239763D03*
Y1247243D03*
X1149015Y1243503D03*
Y1239763D03*
X1156495D03*
X1145275Y1250984D03*
Y1254724D03*
X1171456Y1101377D03*
X1163976Y1243503D03*
X1171456D03*
X1178936Y1101377D03*
X1186417D03*
X1178936Y1239763D03*
X1201377Y1086417D03*
X1197637Y1097637D03*
X1193897Y1101377D03*
X1192027Y1121948D03*
Y1129429D03*
X1203247Y1144389D03*
X1205117Y1228543D03*
Y1224803D03*
X1190157Y1239763D03*
X1193897D03*
X1216337Y1090157D03*
X1220077D03*
X1216338Y1101377D03*
X1208857D03*
X1221948Y1140649D03*
X1212598Y1127558D03*
Y1135039D03*
X1221948Y1155610D03*
X1214468Y1151869D03*
Y1144389D03*
X1221948Y1148129D03*
Y1159350D03*
X1212598Y1198621D03*
X1208858D03*
X1216338Y1202362D03*
X1220078D03*
Y1217322D03*
Y1209842D03*
X1212598Y1206102D03*
X1216338Y1217322D03*
X1212598Y1213582D03*
X1208858Y1206102D03*
Y1213582D03*
X1216338Y1209842D03*
X1220078Y1224803D03*
X1212598Y1228543D03*
X1208858Y1232283D03*
X1216338Y1236023D03*
Y1232283D03*
X1212598Y1224803D03*
X1220078Y1228543D03*
X1208858Y1236023D03*
X1220078Y1239763D03*
X1208858D03*
X1223817Y1090157D03*
X1231298D03*
X1223818Y1101377D03*
X1231298D03*
X1231299Y1105117D03*
X1223817Y1108858D03*
X1223818Y1116338D03*
Y1123818D03*
X1233169Y1136909D03*
X1223818Y1131299D03*
X1231298D03*
X1233169Y1144389D03*
Y1151869D03*
X1236909Y1166830D03*
X1233169Y1159350D03*
Y1166830D03*
Y1189271D03*
Y1181791D03*
Y1174310D03*
Y1196751D03*
X1231298Y1198621D03*
Y1202362D03*
X1235039Y1198621D03*
X1227558Y1202362D03*
X1231298Y1206102D03*
Y1213582D03*
X1235039D03*
X1231298Y1209842D03*
X1227558D03*
X1231298Y1217322D03*
X1227558D03*
X1231298Y1232283D03*
X1227558Y1228543D03*
Y1224803D03*
X1223818Y1236023D03*
X1231298D03*
X1235039Y1228543D03*
X1223818Y1232283D03*
X1235039Y1243503D03*
X1227558Y1239763D03*
X1235039Y1247243D03*
X1243149Y1136909D03*
X1240649Y1166830D03*
X1238779Y1198621D03*
Y1206102D03*
Y1213582D03*
Y1228543D03*
Y1247243D03*
X1511968Y1170570D03*
Y1178050D03*
X1529429Y1151869D03*
X1525689D03*
Y1166830D03*
X1516338Y1228543D03*
X1523819Y1232283D03*
X1520078Y1228543D03*
X1523819Y1236023D03*
X1516338Y1243503D03*
Y1250984D03*
X1527559D03*
Y1254724D03*
X1523819Y1247243D03*
X1527559Y1239763D03*
X1520078Y1250984D03*
Y1254724D03*
Y1243503D03*
X1540649Y1073326D03*
Y1077066D03*
X1546259Y1082677D03*
Y1086417D03*
X1540649Y1099507D03*
X1546259Y1097637D03*
Y1093897D03*
X1533169Y1125688D03*
X1544389Y1129428D03*
X1540649D03*
X1544389Y1136909D03*
X1533169Y1133169D03*
X1540649Y1136909D03*
X1531299Y1194881D03*
Y1202362D03*
Y1217322D03*
Y1209842D03*
X1546259D03*
X1538779Y1221062D03*
X1546259Y1232283D03*
X1538779Y1236023D03*
X1531299Y1232283D03*
X1546259Y1236023D03*
X1531299D03*
X1538779Y1232283D03*
X1531299Y1247243D03*
X1535039Y1250984D03*
Y1254724D03*
X1538779Y1247243D03*
X1542519Y1254724D03*
X1546259Y1243503D03*
X1557480Y1075196D03*
X1550000D03*
X1561220Y1086417D03*
Y1082677D03*
X1557480Y1078936D03*
X1553740Y1082677D03*
Y1086417D03*
X1550000Y1078936D03*
X1557480Y1101376D03*
Y1105117D03*
X1561220Y1097637D03*
X1550000Y1101376D03*
Y1105117D03*
X1553740Y1093897D03*
Y1097637D03*
X1551870Y1170570D03*
X1559350Y1178051D03*
Y1193011D03*
X1553740Y1232283D03*
Y1236023D03*
X1561220D03*
Y1232283D03*
X1550000Y1250984D03*
Y1254724D03*
Y1239763D03*
X1557480Y1250984D03*
Y1254724D03*
X1561220Y1247243D03*
Y1239763D03*
X1553740Y1247243D03*
Y1239763D03*
X1572441Y1075196D03*
X1564960D03*
Y1078936D03*
X1572441D03*
X1576181Y1082677D03*
Y1086417D03*
X1568700Y1082677D03*
Y1086417D03*
X1564960Y1105117D03*
X1576181Y1097637D03*
X1568700D03*
X1576181Y1093897D03*
X1568700D03*
X1572441Y1101376D03*
Y1105117D03*
X1564960Y1101376D03*
X1568700Y1236023D03*
Y1232283D03*
X1564960Y1250984D03*
Y1254724D03*
X1572441Y1250984D03*
Y1254724D03*
X1576181Y1247243D03*
X1572441Y1239763D03*
X1576181D03*
X1568700Y1247243D03*
X1579921Y1075196D03*
X1587401D03*
X1594882D03*
X1583661Y1086417D03*
Y1082677D03*
X1579921Y1078936D03*
X1587401D03*
X1591141Y1082677D03*
Y1086417D03*
X1594882Y1078936D03*
X1594881Y1105117D03*
X1591141Y1097637D03*
X1583661Y1093897D03*
X1594881Y1101376D03*
X1583661Y1097637D03*
X1587401Y1105117D03*
X1579921Y1101376D03*
X1591141Y1093897D03*
X1587401Y1101376D03*
X1579921Y1105117D03*
X1583661Y1247243D03*
X1579921Y1254724D03*
Y1250984D03*
X1583661Y1239763D03*
X1587401Y1250984D03*
Y1254724D03*
X1591141Y1247243D03*
X1594882Y1250984D03*
Y1254724D03*
X1591141Y1239763D03*
X1602362Y1075196D03*
X1598622Y1082677D03*
Y1086417D03*
X1602362Y1078936D03*
Y1101376D03*
X1598622Y1097637D03*
Y1093897D03*
X1602362Y1105117D03*
X1598622Y1239763D03*
Y1247243D03*
X1606102Y1243503D03*
Y1239763D03*
X1602362Y1250984D03*
Y1254724D03*
X1613582Y1239763D03*
X1621063Y1243503D03*
X1636023Y1101377D03*
X1643504D03*
X1628543D03*
X1632283Y1228543D03*
X1639763Y1224803D03*
X1636023Y1236023D03*
X1643504Y1232283D03*
X1632283Y1224803D03*
X1643504Y1236023D03*
X1636023Y1232283D03*
X1639763Y1228543D03*
X1628543Y1243503D03*
X1636023Y1239763D03*
X1658464Y1086417D03*
X1654724Y1097637D03*
X1650984Y1101377D03*
X1649114Y1121948D03*
Y1129429D03*
X1660334Y1144389D03*
X1654724Y1228543D03*
X1647244D03*
X1658464Y1232283D03*
X1654724Y1224803D03*
X1658464Y1236023D03*
X1650984D03*
X1647244Y1224803D03*
X1650984Y1232283D03*
X1647244Y1239763D03*
X1650984D03*
X1673424Y1090157D03*
X1673425Y1101377D03*
X1665944D03*
X1671555Y1136909D03*
X1669685Y1127558D03*
Y1135039D03*
X1671555Y1151869D03*
Y1144389D03*
X1665945Y1239763D03*
X1677164Y1090157D03*
X1680904D03*
X1688385D03*
X1680905Y1101377D03*
X1688385D03*
X1688386Y1105117D03*
X1680904Y1108858D03*
X1680905Y1116338D03*
Y1123818D03*
X1690256Y1136909D03*
X1679035Y1140649D03*
X1680905Y1131299D03*
X1688385D03*
X1690256Y1144389D03*
X1679035Y1148129D03*
Y1155610D03*
X1690256Y1151869D03*
Y1159350D03*
X1679035D03*
X1690256Y1166830D03*
Y1174310D03*
Y1189271D03*
Y1181791D03*
X1688385Y1198621D03*
Y1213582D03*
Y1206102D03*
X1692126Y1243503D03*
X1684645Y1239763D03*
X1677165D03*
X1700236Y1136909D03*
X1693996Y1166830D03*
X1697736D03*
G54D46*
X718503Y-38525D03*
X718500Y-33320D03*
Y-30420D03*
X718488Y-36010D03*
X721756Y-38539D03*
X724781Y-37219D03*
X721741Y-36024D03*
X838503Y-77705D03*
X841756Y-77719D03*
X838500Y-72500D03*
X838488Y-75190D03*
X841741Y-75204D03*
X844781Y-76399D03*
X838500Y-69600D03*
X1005256Y-48539D03*
X1002003D03*
X1005241Y-46024D03*
X1001988D03*
X1008281Y-47219D03*
X1002000Y-40834D03*
X1005256Y-38239D03*
X1002003Y-38225D03*
X1002000Y-43334D03*
X1005241Y-35724D03*
X1002000Y-32720D03*
X1001988Y-35710D03*
X1002000Y-30120D03*
X1008281Y-36919D03*
X1075256Y-77419D03*
X1072003Y-77405D03*
X1071988Y-85290D03*
X1075241D03*
X1072000Y-82600D03*
X1072003Y-87805D03*
X1075256D03*
X1072000Y-80100D03*
Y-72000D03*
Y-69400D03*
X1075241Y-74904D03*
X1071988Y-74890D03*
X1078281Y-86399D03*
Y-76099D03*
X1291756Y-48669D03*
X1288503D03*
X1291741Y-46154D03*
X1288488D03*
X1294781Y-47349D03*
X1288500Y-40964D03*
X1291756Y-38369D03*
X1288503Y-38355D03*
X1288500Y-43464D03*
X1291741Y-35854D03*
X1288500Y-32950D03*
X1288488Y-35840D03*
X1288500Y-30350D03*
X1294781Y-37049D03*
X1328500Y-80100D03*
X1331756Y-77419D03*
X1328503Y-77405D03*
X1331756Y-87805D03*
X1328503D03*
X1328500Y-82600D03*
X1331741Y-85290D03*
X1328488D03*
X1334781Y-86499D03*
X1331741Y-74904D03*
X1328500Y-72000D03*
X1328488Y-74890D03*
X1328500Y-69400D03*
X1334781Y-76099D03*
X1576256Y-48799D03*
X1573003D03*
X1576241Y-46284D03*
X1572988D03*
X1579281Y-47479D03*
X1573000Y-41094D03*
X1576256Y-38499D03*
X1573003Y-38485D03*
X1573000Y-43594D03*
X1576241Y-35984D03*
X1573000Y-33080D03*
X1572988Y-35970D03*
X1573000Y-30480D03*
X1579281Y-37179D03*
X1583000Y-80014D03*
X1586256Y-77419D03*
X1583003Y-77405D03*
X1586256Y-87719D03*
X1583003D03*
X1583000Y-82514D03*
X1586241Y-85204D03*
X1582988D03*
X1589281Y-86399D03*
X1586241Y-74904D03*
X1583000Y-72000D03*
X1582988Y-74890D03*
X1583000Y-69400D03*
X1589281Y-76099D03*
G54D26*
X56348Y1727941D03*
Y1737941D03*
X56248Y1750941D03*
X56348Y1773941D03*
X56248Y1760941D03*
X56348Y1783941D03*
X56248Y1806941D03*
Y1796941D03*
X308448Y1737941D03*
Y1727941D03*
Y1750941D03*
Y1760941D03*
Y1773941D03*
Y1783941D03*
X308348Y1796941D03*
Y1806941D03*
X343286Y1738583D03*
Y1728583D03*
X343112Y1751624D03*
X343212Y1774624D03*
X343112Y1761624D03*
X343212Y1784624D03*
Y1797624D03*
Y1807624D03*
X595386Y1728583D03*
Y1738583D03*
X595312Y1751624D03*
Y1774624D03*
Y1761624D03*
Y1784624D03*
Y1807624D03*
Y1797624D03*
X630083Y1738286D03*
Y1728286D03*
X629861Y1751765D03*
X629711Y1775438D03*
X629861Y1761765D03*
X629711Y1785438D03*
X629475Y1798845D03*
Y1808845D03*
X882183Y1728286D03*
Y1738286D03*
X881911Y1751765D03*
X881761Y1775438D03*
X881911Y1761765D03*
X881761Y1785438D03*
X881525Y1798845D03*
Y1808845D03*
X917279Y1738990D03*
Y1728990D03*
X917163Y1752566D03*
Y1762566D03*
X917073Y1786014D03*
Y1776014D03*
X917166Y1800435D03*
Y1810435D03*
X1169329Y1728990D03*
Y1738990D03*
X1169263Y1752566D03*
Y1762566D03*
X1169123Y1776014D03*
Y1786014D03*
X1169216Y1800435D03*
Y1810435D03*
G54D42*
X318448Y1727941D03*
Y1737941D03*
Y1773941D03*
Y1783941D03*
X605312Y1751624D03*
Y1761624D03*
Y1807624D03*
Y1797624D03*
X891911Y1751765D03*
Y1761765D03*
X891525Y1808845D03*
Y1798845D03*
X1179263Y1752566D03*
Y1762566D03*
X1179216Y1800435D03*
Y1810435D03*
G54D35*
X145078Y1198621D03*
Y1191141D03*
X148818D03*
Y1198621D03*
X145078Y1221062D03*
X148818D03*
Y1213582D03*
X145078D03*
Y1206102D03*
X148818D03*
X145078Y1228543D03*
X148818D03*
Y1247243D03*
X145078D03*
X148818Y1239763D03*
X145078D03*
X156299Y1187401D03*
X163779D03*
X152559D03*
X156299Y1202362D03*
Y1194881D03*
X152559Y1202362D03*
Y1194881D03*
X163779D03*
Y1202362D03*
X156299Y1217322D03*
Y1209842D03*
X152559D03*
X163779D03*
Y1217322D03*
X152559D03*
X160039Y1236023D03*
X163779Y1224803D03*
X156299D03*
Y1228543D03*
X163779D03*
X160039Y1232283D03*
X152559Y1236023D03*
Y1232283D03*
Y1250984D03*
Y1254724D03*
X160039D03*
X156299Y1243503D03*
Y1247243D03*
X163779Y1243503D03*
X160039Y1250984D03*
X163779Y1247243D03*
X174999Y1075196D03*
X182480D03*
X174999Y1078936D03*
X182480D03*
X178740Y1082677D03*
Y1086417D03*
X167519Y1187401D03*
X174999Y1198621D03*
Y1191141D03*
X167519Y1194881D03*
X171259Y1198621D03*
Y1191141D03*
X167519Y1202362D03*
Y1209842D03*
X171259Y1213582D03*
Y1206102D03*
X174999D03*
X167519Y1217322D03*
X174999Y1213582D03*
X167519Y1232283D03*
Y1236023D03*
Y1254724D03*
Y1250984D03*
X178740Y1247243D03*
X182480Y1254724D03*
Y1250984D03*
X171259Y1247243D03*
X174999Y1250984D03*
X171259Y1243503D03*
X174999Y1254724D03*
X178740Y1243503D03*
X189960Y1075196D03*
X197440D03*
X186220Y1082677D03*
Y1086417D03*
X189960Y1078936D03*
X193700Y1086417D03*
Y1082677D03*
X197440Y1078936D03*
Y1254724D03*
Y1250984D03*
X193700Y1247243D03*
Y1243503D03*
X189960Y1254724D03*
Y1250984D03*
X186220Y1247243D03*
Y1243503D03*
X204921Y1075196D03*
X212401D03*
Y1078936D03*
X208661Y1082677D03*
X201181D03*
Y1086417D03*
X208661D03*
X204921Y1078936D03*
X208661Y1243503D03*
X204921Y1250984D03*
X208661Y1247243D03*
X212401Y1254724D03*
X201181Y1243503D03*
X212401Y1250984D03*
X201181Y1247243D03*
X204921Y1254724D03*
X227362Y1075196D03*
X219881D03*
Y1078936D03*
X216141Y1086417D03*
X231102Y1082677D03*
Y1086417D03*
X223622Y1082677D03*
X227362Y1078936D03*
X216141Y1082677D03*
X223622Y1086417D03*
X231102Y1228543D03*
Y1224803D03*
Y1243503D03*
Y1247243D03*
X223622Y1243503D03*
X216141Y1247243D03*
X223622D03*
X216141Y1243503D03*
X219881Y1250984D03*
Y1254724D03*
X227362D03*
Y1250984D03*
X234841Y1075195D03*
X242321Y1075196D03*
Y1078936D03*
X246061Y1082677D03*
X238581Y1082676D03*
X234841Y1078935D03*
X246061Y1086417D03*
X238581Y1086416D03*
X234841Y1093897D03*
X246062Y1105117D03*
X242321Y1097637D03*
X234841D03*
X238582Y1101376D03*
X246062D03*
X238582Y1105117D03*
X242321Y1093897D03*
X238582Y1224803D03*
Y1228543D03*
X242322Y1236023D03*
Y1232283D03*
X246062Y1228543D03*
X234842Y1232283D03*
X246062Y1224803D03*
X234842Y1236023D03*
X238582Y1247243D03*
X246062Y1243503D03*
X242322Y1250984D03*
X234842D03*
X246062Y1247243D03*
X234842Y1254724D03*
X238582Y1243503D03*
X242322Y1254724D03*
X249802Y1075196D03*
X257282D03*
X249802Y1078936D03*
X261022Y1086417D03*
X253542Y1082676D03*
X257282Y1078936D03*
X253542Y1086416D03*
X261022Y1082677D03*
X249802Y1097637D03*
X257282D03*
X249802Y1093897D03*
X253543Y1105117D03*
Y1101376D03*
X257282Y1093897D03*
X261023Y1105117D03*
Y1101376D03*
Y1224803D03*
X253543Y1228543D03*
X249803Y1232283D03*
X257283D03*
Y1236023D03*
X261023Y1228543D03*
X253543Y1224803D03*
X249803Y1236023D03*
X261023Y1243503D03*
X249803Y1250984D03*
X261023Y1247243D03*
X257283Y1250984D03*
X253543Y1247243D03*
X257283Y1254724D03*
X249803D03*
X253543Y1243503D03*
X279723Y1075196D03*
X264762D03*
X272243D03*
X275982Y1082677D03*
Y1086417D03*
X268502Y1082676D03*
X272243Y1078936D03*
X268502Y1086416D03*
X279723Y1078936D03*
X264762D03*
Y1097637D03*
X268503Y1105117D03*
X272243Y1097637D03*
X275984Y1105117D03*
X279723Y1093897D03*
X272243D03*
X279723Y1097637D03*
X268503Y1101376D03*
X275984D03*
X264762Y1093897D03*
X264763Y1232283D03*
X268503Y1224803D03*
X275984D03*
X272244Y1236023D03*
X279724Y1232283D03*
Y1236023D03*
X275984Y1228543D03*
X272244Y1232283D03*
X268503Y1228543D03*
X264763Y1236023D03*
Y1254724D03*
Y1250984D03*
X268503Y1243503D03*
Y1247243D03*
X272244Y1254724D03*
Y1250984D03*
X275984Y1243503D03*
Y1247243D03*
X279724Y1250984D03*
Y1254724D03*
X287203Y1075196D03*
X294684D03*
X290943Y1086417D03*
X287203Y1078936D03*
X290943Y1082677D03*
X283463Y1082676D03*
Y1086416D03*
X294684Y1078936D03*
X283464Y1101376D03*
X294684Y1093897D03*
X287203D03*
X294684Y1097637D03*
X283464Y1105117D03*
X290944Y1101376D03*
Y1105117D03*
X287203Y1097637D03*
X294684Y1123818D03*
Y1116338D03*
Y1131299D03*
X287204Y1232283D03*
X283464Y1224803D03*
Y1228543D03*
X287204Y1236023D03*
Y1254724D03*
X283464Y1243503D03*
Y1247243D03*
X287204Y1250984D03*
X302164Y1075196D03*
X309644D03*
X305904Y1082677D03*
X302164Y1078936D03*
X305904Y1086417D03*
X309644Y1078936D03*
X298424Y1086416D03*
Y1082676D03*
X298425Y1105117D03*
Y1101376D03*
X309644Y1097637D03*
X302164D03*
X305905Y1105117D03*
X309644Y1093897D03*
X305905Y1101376D03*
X302164Y1093897D03*
X302165Y1120078D03*
X305905Y1112598D03*
X298425Y1116338D03*
X305905Y1120078D03*
X302165Y1112598D03*
X298425Y1123818D03*
X305905Y1127559D03*
Y1135039D03*
X302165D03*
Y1127559D03*
X298425Y1131299D03*
X317124Y1075196D03*
X320866Y1090157D03*
X324606D03*
Y1082676D03*
X317124Y1078936D03*
X313384Y1082677D03*
Y1086417D03*
X320866Y1082676D03*
X313385Y1101377D03*
X317125Y1093897D03*
X320866Y1101377D03*
X313385Y1105117D03*
X324606Y1101377D03*
X317125Y1097637D03*
X313385Y1120078D03*
X324606Y1123818D03*
Y1108858D03*
X320866D03*
X317125Y1112598D03*
X324606Y1116338D03*
X313385Y1112598D03*
X317125Y1120078D03*
X320866Y1116338D03*
Y1123818D03*
X313385Y1127558D03*
X317125Y1135039D03*
X313385D03*
X324606Y1131299D03*
X317125Y1127558D03*
X320866Y1131299D03*
X602165Y1191141D03*
Y1198621D03*
Y1221062D03*
Y1206102D03*
Y1213582D03*
Y1247243D03*
X613386Y1187401D03*
X609646D03*
X605905Y1191141D03*
X613386Y1194881D03*
X605905Y1198621D03*
X609646Y1194881D03*
Y1202362D03*
X613386D03*
Y1217322D03*
X605905Y1221062D03*
X609646Y1217322D03*
Y1209842D03*
X605905Y1206102D03*
Y1213582D03*
X613386Y1209842D03*
X605905Y1247243D03*
X617126Y1250984D03*
X620866Y1243503D03*
Y1247243D03*
X609646Y1254724D03*
X613386Y1247243D03*
X617126Y1254724D03*
X613386Y1243503D03*
X609646Y1250984D03*
X632086Y1075196D03*
Y1078936D03*
X635827Y1086417D03*
Y1082677D03*
X624606Y1254724D03*
Y1250984D03*
X639567Y1075196D03*
X647047D03*
X643307Y1086417D03*
Y1082677D03*
X647047Y1078936D03*
X639567D03*
X650787Y1082677D03*
Y1086417D03*
X662008Y1075196D03*
X654527D03*
X669488D03*
X662008Y1078936D03*
X665748Y1082677D03*
X658268D03*
X654527Y1078936D03*
X665748Y1086417D03*
X658268D03*
X669488Y1078936D03*
Y1232283D03*
X662008D03*
X665748Y1224803D03*
X662008Y1236023D03*
X658268Y1224803D03*
X665748Y1228543D03*
X658268D03*
X669488Y1236023D03*
X662008Y1254724D03*
X665748Y1247243D03*
X669488Y1250984D03*
X658268Y1247243D03*
X662008Y1250984D03*
X665748Y1243503D03*
X669488Y1254724D03*
X658268Y1243503D03*
X676968Y1075196D03*
X684449D03*
X676968Y1078936D03*
X680709Y1086417D03*
X684449Y1078936D03*
X673228Y1086417D03*
Y1082677D03*
X680709D03*
X676968Y1236023D03*
X684449Y1232283D03*
X673228Y1228543D03*
X680709Y1224803D03*
X684449Y1236023D03*
X676968Y1232283D03*
X673228Y1224803D03*
X680709Y1228543D03*
X673228Y1243503D03*
X680709Y1247243D03*
X673228D03*
X684449Y1254724D03*
Y1250984D03*
X676968Y1254724D03*
Y1250984D03*
X680709Y1243503D03*
X699408Y1075196D03*
X691928Y1075195D03*
X688189Y1086417D03*
Y1082677D03*
X691928Y1078935D03*
X699408Y1078936D03*
X695668Y1086416D03*
Y1082676D03*
X695669Y1101376D03*
X699408Y1097637D03*
X695669Y1105117D03*
X691928Y1093897D03*
Y1097637D03*
X699408Y1093897D03*
X688189Y1228543D03*
X691929Y1236023D03*
X699409Y1232283D03*
X688189Y1224803D03*
X699409Y1236023D03*
X691929Y1232283D03*
X695669Y1228543D03*
Y1224803D03*
X699409Y1254724D03*
X691929Y1250984D03*
X688189Y1247243D03*
Y1243503D03*
X691929Y1254724D03*
X695669Y1247243D03*
X699409Y1250984D03*
X695669Y1243503D03*
X706889Y1075196D03*
X714369D03*
X706889Y1078936D03*
X718109Y1086417D03*
X714369Y1078936D03*
X703148Y1082677D03*
X710629Y1086416D03*
X703148Y1086417D03*
X718109Y1082677D03*
X710629Y1082676D03*
X714369Y1097637D03*
X706889Y1093897D03*
X703149Y1105117D03*
X718110D03*
Y1101376D03*
X710630Y1105117D03*
X714369Y1093897D03*
X706889Y1097637D03*
X703149Y1101376D03*
X710630D03*
X706890Y1236023D03*
X714370D03*
X710630Y1228543D03*
X703149D03*
X714370Y1232283D03*
X703149Y1224803D03*
X710630D03*
X706890Y1232283D03*
Y1250984D03*
X703149Y1243503D03*
X714370Y1254724D03*
Y1250984D03*
X710630Y1247243D03*
X706890Y1254724D03*
X710630Y1243503D03*
X703149Y1247243D03*
X721849Y1075196D03*
X729330D03*
X725589Y1086416D03*
X733069Y1086417D03*
X721849Y1078936D03*
X729330D03*
X733069Y1082677D03*
X725589Y1082676D03*
X725590Y1101376D03*
X733071Y1105117D03*
X725590D03*
X721849Y1097637D03*
Y1093897D03*
X729330Y1097637D03*
X733071Y1101376D03*
X729330Y1093897D03*
X736810Y1075196D03*
X744290D03*
Y1078936D03*
X748030Y1086417D03*
X740550Y1086416D03*
Y1082676D03*
X736810Y1078936D03*
X748030Y1082677D03*
X736810Y1097637D03*
X748031Y1105117D03*
X744290Y1093897D03*
X740551Y1105117D03*
X744290Y1097637D03*
X736810Y1093897D03*
X740551Y1101376D03*
X748031D03*
Y1224803D03*
Y1228543D03*
Y1247243D03*
Y1243503D03*
X751771Y1075196D03*
X766731D03*
X759251D03*
X762991Y1086417D03*
X766731Y1078936D03*
X755511Y1086416D03*
X759251Y1078936D03*
X755511Y1082676D03*
X762991Y1082677D03*
X751771Y1078936D03*
Y1097637D03*
X762992Y1101376D03*
Y1105117D03*
X755512D03*
X759251Y1097637D03*
Y1093897D03*
X766731Y1097637D03*
X755512Y1101376D03*
X766731Y1093897D03*
X751771D03*
X755512Y1123818D03*
X759252Y1112598D03*
X751771Y1123818D03*
X762992Y1112598D03*
X755512Y1116338D03*
X751771D03*
X759252Y1120078D03*
X762992D03*
X751771Y1131299D03*
X762992Y1135039D03*
X755512Y1131299D03*
X762992Y1127559D03*
X759252Y1135039D03*
Y1127559D03*
X762992Y1202362D03*
X755512Y1198621D03*
X759252Y1202362D03*
X751772Y1198621D03*
X762992Y1217322D03*
X751772Y1213582D03*
X762992Y1209842D03*
X755512Y1213582D03*
X751772Y1206102D03*
X759252Y1217322D03*
Y1209842D03*
X755512Y1206102D03*
Y1228543D03*
X751772Y1236023D03*
X762992Y1228543D03*
X751772Y1232283D03*
X766732D03*
Y1236023D03*
X759252Y1232283D03*
X762992Y1224803D03*
X759252Y1236023D03*
X755512Y1224803D03*
X766732Y1250984D03*
X755512Y1243503D03*
X762992D03*
Y1247243D03*
X751772Y1250984D03*
Y1254724D03*
X759252D03*
X766732D03*
X759252Y1250984D03*
X755512Y1247243D03*
X774211Y1075196D03*
X781693Y1090157D03*
X777953D03*
X781693Y1082676D03*
X774211Y1078936D03*
X770471Y1086417D03*
Y1082677D03*
X777953Y1082676D03*
X770472Y1101377D03*
X781693D03*
X777953D03*
X774212Y1097637D03*
X770472Y1105117D03*
X774212Y1093897D03*
Y1112598D03*
X770472D03*
X781693Y1123818D03*
X777953D03*
X781693Y1116338D03*
X777953Y1108858D03*
X770472Y1120078D03*
X781693Y1108858D03*
X777953Y1116338D03*
X774212Y1120078D03*
X770472Y1127558D03*
Y1135039D03*
X781693Y1131299D03*
X774212Y1127558D03*
Y1135039D03*
X777953Y1131299D03*
X781693Y1198621D03*
X774212Y1202362D03*
X770472D03*
X777953Y1198621D03*
Y1206102D03*
X770472Y1209842D03*
X781693Y1213582D03*
X774212Y1209842D03*
X777953Y1221062D03*
X781693D03*
Y1206102D03*
X770472Y1217322D03*
X774212D03*
X777953Y1213582D03*
X770472Y1228543D03*
X781693D03*
X770472Y1224803D03*
X777953Y1228543D03*
X774212Y1232283D03*
Y1236023D03*
X777953Y1239763D03*
X781693D03*
X777953Y1247243D03*
X770472Y1243503D03*
X781693Y1247243D03*
X770472D03*
X774212Y1250984D03*
Y1254724D03*
X1059251Y1198621D03*
Y1191141D03*
Y1221062D03*
Y1206102D03*
Y1213582D03*
Y1228543D03*
Y1247243D03*
Y1239763D03*
X1070472Y1187401D03*
X1066732D03*
X1062991Y1198621D03*
X1066732Y1194881D03*
X1062991Y1191141D03*
X1070472Y1194881D03*
Y1202362D03*
X1066732D03*
X1070472Y1217322D03*
X1066732D03*
X1062991Y1221062D03*
Y1206102D03*
X1070472Y1209842D03*
X1062991Y1213582D03*
X1066732Y1209842D03*
X1070472Y1228543D03*
X1066732Y1236023D03*
Y1232283D03*
X1074212Y1236023D03*
Y1232283D03*
X1070472Y1224803D03*
X1062991Y1228543D03*
X1074212Y1250984D03*
X1066732Y1254724D03*
X1070472Y1247243D03*
X1074212Y1254724D03*
X1062991Y1247243D03*
X1070472Y1243503D03*
X1062991Y1239763D03*
X1066732Y1250984D03*
X1089172Y1075196D03*
Y1078936D03*
X1077952Y1187401D03*
X1081692D03*
X1077952Y1194881D03*
Y1202362D03*
X1089172Y1191141D03*
Y1198621D03*
X1081692Y1202362D03*
X1085432Y1198621D03*
X1081692Y1194881D03*
X1085432Y1191141D03*
X1089172Y1206102D03*
X1077952Y1209842D03*
X1081692D03*
Y1217322D03*
X1089172Y1213582D03*
X1077952Y1217322D03*
X1085432Y1206102D03*
Y1213582D03*
X1081692Y1232283D03*
Y1236023D03*
X1077952Y1224803D03*
Y1228543D03*
Y1243503D03*
X1081692Y1250984D03*
X1077952Y1247243D03*
X1081692Y1254724D03*
X1085432Y1243503D03*
X1089172Y1254724D03*
Y1250984D03*
X1085432Y1247243D03*
X1096653Y1075196D03*
X1104133D03*
X1100393Y1082677D03*
X1104133Y1078936D03*
X1107873Y1082677D03*
Y1086417D03*
X1092913Y1082677D03*
X1100393Y1086417D03*
X1092913D03*
X1096653Y1078936D03*
Y1254724D03*
X1104133D03*
X1092913Y1247243D03*
X1096653Y1250984D03*
X1092913Y1243503D03*
X1107873D03*
X1100393D03*
X1107873Y1247243D03*
X1100393D03*
X1104133Y1250984D03*
X1111613Y1075196D03*
X1119094D03*
X1122834Y1086417D03*
X1119094Y1078936D03*
X1115354Y1082677D03*
X1111613Y1078936D03*
X1115354Y1086417D03*
X1122834Y1082677D03*
Y1243503D03*
X1119094Y1250984D03*
X1111613Y1254724D03*
X1119094D03*
X1122834Y1247243D03*
X1115354Y1243503D03*
Y1247243D03*
X1111613Y1250984D03*
X1126574Y1075196D03*
X1134054D03*
Y1078936D03*
X1126574D03*
X1130314Y1086417D03*
Y1082677D03*
X1137795Y1086417D03*
Y1082677D03*
X1126574Y1254724D03*
X1137795Y1243503D03*
X1130314Y1247243D03*
X1126574Y1250984D03*
X1137795Y1247243D03*
X1130314Y1243503D03*
X1134054Y1250984D03*
Y1254724D03*
X1141535Y1075196D03*
X1156494D03*
X1149014Y1075195D03*
X1145275Y1086417D03*
Y1082677D03*
X1141535Y1078936D03*
X1149014Y1078935D03*
X1156494Y1078936D03*
X1152754Y1086416D03*
Y1082676D03*
X1149014Y1097637D03*
X1156494Y1093897D03*
X1152755Y1101376D03*
X1156494Y1097637D03*
X1149014Y1093897D03*
X1152755Y1105117D03*
X1149015Y1236023D03*
Y1232283D03*
X1152755Y1228543D03*
X1145275Y1224803D03*
X1156495Y1232283D03*
Y1236023D03*
X1145275Y1228543D03*
X1152755Y1224803D03*
X1141535Y1254724D03*
Y1250984D03*
X1149015Y1254724D03*
X1145275Y1247243D03*
X1152755Y1243503D03*
X1156495Y1254724D03*
X1145275Y1243503D03*
X1152755Y1247243D03*
X1149015Y1250984D03*
X1156495D03*
X1163975Y1075196D03*
X1171455D03*
X1160234Y1086417D03*
X1167715Y1086416D03*
X1163975Y1078936D03*
X1160234Y1082677D03*
X1171455Y1078936D03*
X1167715Y1082676D03*
X1160235Y1105117D03*
Y1101376D03*
X1171455Y1093897D03*
X1167716Y1105117D03*
X1171455Y1097637D03*
X1163975Y1093897D03*
Y1097637D03*
X1167716Y1101376D03*
X1160235Y1224803D03*
X1163976Y1232283D03*
X1167716Y1224803D03*
X1160235Y1228543D03*
X1171456Y1232283D03*
X1163976Y1236023D03*
X1171456D03*
X1167716Y1228543D03*
X1171456Y1250984D03*
X1167716Y1247243D03*
X1163976Y1250984D03*
X1160235Y1247243D03*
Y1243503D03*
X1167716D03*
X1171456Y1254724D03*
X1163976D03*
X1178935Y1075196D03*
X1186416D03*
X1175195Y1086417D03*
X1182675Y1086416D03*
X1175195Y1082677D03*
X1178935Y1078936D03*
X1182675Y1082676D03*
X1186416Y1078936D03*
X1178935Y1097637D03*
X1186416Y1093897D03*
X1182676Y1105117D03*
X1175196D03*
X1178935Y1093897D03*
X1182676Y1101376D03*
X1175196D03*
X1186416Y1097637D03*
X1182676Y1228543D03*
X1186417Y1236023D03*
X1178936D03*
X1186417Y1232283D03*
X1175196Y1228543D03*
X1178936Y1232283D03*
X1182676Y1224803D03*
X1175196D03*
X1178936Y1254724D03*
X1175196Y1243503D03*
X1182676Y1247243D03*
X1178936Y1250984D03*
X1186417D03*
X1182676Y1243503D03*
X1186417Y1254724D03*
X1175196Y1247243D03*
X1193896Y1075196D03*
X1201376D03*
X1190155Y1086417D03*
X1205116Y1082677D03*
X1190155D03*
X1197636Y1082676D03*
X1193896Y1078936D03*
X1205116Y1086417D03*
X1201376Y1078936D03*
X1197636Y1086416D03*
X1201376Y1093897D03*
X1193896Y1097637D03*
X1197637Y1105117D03*
X1205117D03*
X1197637Y1101376D03*
X1205117D03*
X1190157D03*
X1193896Y1093897D03*
X1201376Y1097637D03*
X1190157Y1105117D03*
X1197637Y1224803D03*
X1193897Y1236023D03*
X1190157Y1228543D03*
X1201377Y1236023D03*
X1190157Y1224803D03*
X1193897Y1232283D03*
X1197637Y1228543D03*
X1201377Y1232283D03*
X1190157Y1243503D03*
X1201377Y1250984D03*
X1197637Y1247243D03*
X1193897Y1250984D03*
X1201377Y1254724D03*
X1197637Y1243503D03*
X1193897Y1254724D03*
X1190157Y1247243D03*
X1216337Y1075196D03*
X1208857D03*
X1212597Y1082676D03*
Y1086416D03*
X1220077Y1086417D03*
X1208857Y1078936D03*
X1216337D03*
X1220077Y1082677D03*
X1220078Y1105117D03*
X1216337Y1093897D03*
X1212598Y1101376D03*
Y1105117D03*
X1208857Y1093897D03*
X1216337Y1097637D03*
X1220078Y1101376D03*
X1208857Y1097637D03*
X1212598Y1123818D03*
X1208857Y1116338D03*
X1212598D03*
X1216338Y1120078D03*
Y1112598D03*
X1208857Y1123818D03*
X1220078Y1112598D03*
Y1120078D03*
X1216338Y1127559D03*
Y1135039D03*
X1212598Y1131299D03*
X1208857D03*
X1220078Y1135039D03*
Y1127559D03*
X1231297Y1075196D03*
X1223817D03*
X1235039Y1090157D03*
X1231297Y1078936D03*
X1235039Y1082676D03*
X1227557Y1086417D03*
X1223817Y1078936D03*
X1227557Y1082677D03*
X1227558Y1101377D03*
X1231298Y1093897D03*
X1235039Y1101377D03*
X1227558Y1105117D03*
X1223817Y1093897D03*
Y1097637D03*
X1231298D03*
X1227558Y1112598D03*
X1235039Y1123818D03*
X1231298Y1120078D03*
Y1112598D03*
X1235039Y1108858D03*
Y1116338D03*
X1227558Y1120078D03*
X1231298Y1135039D03*
X1227558Y1127558D03*
X1235039Y1131299D03*
X1231298Y1127558D03*
X1227558Y1135039D03*
X1238779Y1090157D03*
Y1082676D03*
Y1101377D03*
Y1108858D03*
Y1116338D03*
Y1123818D03*
Y1131299D03*
X1523819Y1187401D03*
X1527559D03*
X1516338Y1198621D03*
X1523819Y1194881D03*
X1520078Y1198621D03*
X1523819Y1202362D03*
X1516338Y1191141D03*
X1527559Y1202362D03*
Y1194881D03*
X1520078Y1191141D03*
Y1221062D03*
X1516338Y1213582D03*
Y1206102D03*
X1520078D03*
X1527559Y1217322D03*
X1523819Y1209842D03*
X1516338Y1221062D03*
X1527559Y1209842D03*
X1523819Y1217322D03*
X1520078Y1213582D03*
Y1247243D03*
X1516338D03*
X1527559Y1243503D03*
Y1247243D03*
X1523819Y1250984D03*
Y1254724D03*
X1546259Y1075196D03*
Y1078936D03*
X1538779Y1250984D03*
Y1254724D03*
X1535039Y1243503D03*
X1531299Y1250984D03*
X1535039Y1247243D03*
X1531299Y1254724D03*
X1553740Y1075196D03*
X1561220D03*
X1557480Y1082677D03*
X1553740Y1078936D03*
X1561220D03*
X1550000Y1086417D03*
Y1082677D03*
X1557480Y1086417D03*
X1576181Y1075196D03*
X1568700D03*
Y1078936D03*
X1572441Y1086417D03*
X1564960Y1082677D03*
Y1086417D03*
X1572441Y1082677D03*
X1576181Y1078936D03*
X1572441Y1228543D03*
X1576181Y1236023D03*
X1572441Y1224803D03*
X1576181Y1232283D03*
X1572441Y1247243D03*
X1576181Y1254724D03*
Y1250984D03*
X1572441Y1243503D03*
X1583661Y1075196D03*
X1591141D03*
X1594882Y1082677D03*
X1579921D03*
X1583661Y1078936D03*
X1594882Y1086417D03*
X1587401Y1082677D03*
X1579921Y1086417D03*
X1587401D03*
X1591141Y1078936D03*
X1594882Y1224803D03*
X1591141Y1232283D03*
X1583661Y1236023D03*
X1579921Y1228543D03*
X1583661Y1232283D03*
X1594882Y1228543D03*
X1579921Y1224803D03*
X1587401Y1228543D03*
Y1224803D03*
X1591141Y1236023D03*
X1583661Y1254724D03*
X1579921Y1247243D03*
X1591141Y1254724D03*
X1587401Y1247243D03*
Y1243503D03*
X1594882D03*
X1579921D03*
X1594882Y1247243D03*
X1583661Y1250984D03*
X1591141D03*
X1606101Y1075195D03*
X1598622Y1075196D03*
X1609841Y1086416D03*
X1606101Y1078935D03*
X1609841Y1082676D03*
X1602362Y1082677D03*
Y1086417D03*
X1598622Y1078936D03*
X1606101Y1093897D03*
X1609842Y1101376D03*
Y1105117D03*
X1606101Y1097637D03*
X1598622Y1236023D03*
X1606102D03*
X1609842Y1228543D03*
X1606102Y1232283D03*
X1602362Y1224803D03*
X1609842D03*
X1602362Y1228543D03*
X1598622Y1232283D03*
Y1254724D03*
Y1250984D03*
X1609842Y1247243D03*
X1606102Y1250984D03*
Y1254724D03*
X1609842Y1243503D03*
X1602362Y1247243D03*
Y1243503D03*
X1613581Y1075196D03*
X1621062D03*
X1613581Y1078936D03*
X1624802Y1082676D03*
X1617321Y1082677D03*
X1621062Y1078936D03*
X1617321Y1086417D03*
X1624802Y1086416D03*
X1621062Y1093897D03*
X1617322Y1105117D03*
Y1101376D03*
X1613581Y1093897D03*
Y1097637D03*
X1624803Y1101376D03*
Y1105117D03*
X1621062Y1097637D03*
X1617322Y1228543D03*
X1624803Y1224803D03*
X1617322D03*
X1621063Y1236023D03*
X1613582D03*
X1621063Y1232283D03*
X1624803Y1228543D03*
X1613582Y1232283D03*
X1624803Y1247243D03*
Y1243503D03*
X1621063Y1254724D03*
X1613582Y1250984D03*
X1617322Y1243503D03*
Y1247243D03*
X1613582Y1254724D03*
X1621063Y1250984D03*
X1636022Y1075196D03*
X1643503D03*
X1628542D03*
X1632282Y1082677D03*
X1643503Y1078936D03*
X1628542D03*
X1639762Y1086416D03*
X1632282Y1086417D03*
X1636022Y1078936D03*
X1639762Y1082676D03*
X1639763Y1101376D03*
X1628542Y1093897D03*
X1636022D03*
X1639763Y1105117D03*
X1632283D03*
Y1101376D03*
X1636022Y1097637D03*
X1643503D03*
Y1093897D03*
X1628542Y1097637D03*
X1628543Y1236023D03*
Y1232283D03*
Y1250984D03*
Y1254724D03*
X1650983Y1075196D03*
X1658463D03*
X1654723Y1086416D03*
Y1082676D03*
X1650983Y1078936D03*
X1647242Y1082677D03*
Y1086417D03*
X1658463Y1078936D03*
Y1097637D03*
X1647244Y1101376D03*
X1658463Y1093897D03*
X1654724Y1105117D03*
X1650983Y1093897D03*
X1647244Y1105117D03*
X1654724Y1101376D03*
X1650983Y1097637D03*
X1673424Y1075196D03*
X1665944D03*
X1662203Y1086417D03*
Y1082677D03*
X1669684Y1086416D03*
X1665944Y1078936D03*
X1673424D03*
X1669684Y1082676D03*
X1665944Y1093897D03*
X1662204Y1105117D03*
X1669685D03*
X1673424Y1097637D03*
X1669685Y1101376D03*
X1673424Y1093897D03*
X1665944Y1097637D03*
X1662204Y1101376D03*
X1673425Y1112598D03*
X1665944Y1123818D03*
X1673425Y1120078D03*
X1669685Y1123818D03*
X1665944Y1116338D03*
X1669685D03*
X1665944Y1131299D03*
X1669685D03*
X1673425Y1127559D03*
Y1135039D03*
Y1202362D03*
X1665945Y1198621D03*
X1669685D03*
X1665945Y1206102D03*
X1669685Y1213582D03*
X1673425Y1209842D03*
X1669685Y1206102D03*
X1665945Y1213582D03*
X1673425Y1217322D03*
Y1236023D03*
X1662204Y1228543D03*
X1669685D03*
X1673425Y1232283D03*
X1665945D03*
Y1236023D03*
X1662204Y1224803D03*
X1669685D03*
X1673425Y1250984D03*
X1662204Y1247243D03*
X1665945Y1254724D03*
X1673425D03*
X1662204Y1243503D03*
X1665945Y1250984D03*
X1669685Y1247243D03*
Y1243503D03*
X1680904Y1075196D03*
X1688384D03*
X1692126Y1090157D03*
Y1082676D03*
X1684644Y1082677D03*
Y1086417D03*
X1680904Y1078936D03*
X1688384D03*
X1677164Y1086417D03*
Y1082677D03*
X1692126Y1101377D03*
X1684645D03*
X1677165Y1105117D03*
X1680904Y1097637D03*
X1677165Y1101376D03*
X1688385Y1097637D03*
X1684645Y1105117D03*
X1680904Y1093897D03*
X1688385D03*
X1677165Y1120078D03*
Y1112598D03*
X1692126Y1116338D03*
Y1108858D03*
X1684645Y1120078D03*
X1688385D03*
X1684645Y1112598D03*
X1692126Y1123818D03*
X1688385Y1112598D03*
X1677165Y1135039D03*
Y1127559D03*
X1684645Y1135039D03*
Y1127558D03*
X1692126Y1131299D03*
X1688385Y1127558D03*
Y1135039D03*
X1684645Y1202362D03*
X1692126Y1198621D03*
X1688385Y1202362D03*
X1677165D03*
X1692126Y1213582D03*
X1684645Y1217322D03*
Y1209842D03*
X1692126Y1206102D03*
X1677165Y1209842D03*
X1692126Y1221062D03*
X1688385Y1209842D03*
X1677165Y1217322D03*
X1688385D03*
X1677165Y1228543D03*
X1680905Y1236023D03*
Y1232283D03*
X1692126Y1228543D03*
X1684645Y1224803D03*
Y1228543D03*
X1677165Y1224803D03*
X1688385Y1232283D03*
Y1236023D03*
X1684645Y1243503D03*
X1677165D03*
X1692126Y1247243D03*
X1684645D03*
X1677165D03*
X1688385Y1254724D03*
Y1250984D03*
X1692126Y1239763D03*
X1680905Y1254724D03*
Y1250984D03*
X1695866Y1090157D03*
Y1082676D03*
Y1101377D03*
Y1123818D03*
Y1116338D03*
Y1108858D03*
Y1131299D03*
Y1198621D03*
Y1221062D03*
Y1213582D03*
Y1206102D03*
Y1228543D03*
Y1239763D03*
Y1247243D03*
G54D58*
X1250055Y1710189D03*
Y1720189D03*
Y1739208D03*
Y1749208D03*
X1250048Y1768377D03*
Y1778377D03*
X1248555Y1797909D03*
Y1807909D03*
X1734069Y1710189D03*
Y1720189D03*
Y1739208D03*
Y1749208D03*
X1734062Y1768377D03*
Y1778377D03*
X1734069Y1797909D03*
Y1807909D03*
G54D18*
X7983Y1529035D03*
Y1525635D03*
X35688Y111255D03*
Y114655D03*
X28388Y121742D03*
X35688Y125428D03*
X28388Y132515D03*
Y118342D03*
X35688Y128828D03*
X28388Y135915D03*
X35825Y1464845D03*
X39225D03*
X79512Y1372385D03*
X76112D03*
Y1384297D03*
X79512D03*
X88352Y1348187D03*
X91752D03*
Y1360099D03*
X88352D03*
X100592Y1384297D03*
Y1372385D03*
X91752Y1396583D03*
X88352D03*
X91752Y1408495D03*
X88352D03*
X116232Y1348187D03*
X112832D03*
Y1360099D03*
X116232D03*
X103992Y1372385D03*
Y1384297D03*
X116232Y1396583D03*
X112832D03*
Y1408495D03*
X116232D03*
X130750Y132515D03*
Y121742D03*
Y118342D03*
Y135915D03*
X125072Y1384297D03*
X128472D03*
X125072Y1372385D03*
X128472D03*
X138050Y111255D03*
Y114655D03*
Y128828D03*
Y125428D03*
X148692Y391001D03*
Y394401D03*
Y405174D03*
X140690Y401513D03*
Y398113D03*
X148692Y408574D03*
X138290Y412287D03*
X148692Y419347D03*
Y422747D03*
X138290Y415687D03*
Y426460D03*
X148692Y433521D03*
X138290Y429860D03*
X148692Y436921D03*
X138290Y440633D03*
Y444033D03*
Y469387D03*
Y472787D03*
X148692Y476499D03*
X138290Y483560D03*
X148692Y490673D03*
X138290Y486960D03*
X148692Y479899D03*
Y494073D03*
Y524033D03*
Y520633D03*
X138290Y516921D03*
Y513521D03*
Y531094D03*
X148692Y538206D03*
Y534806D03*
X138290Y527694D03*
X140712Y1348187D03*
X137312D03*
Y1360099D03*
X140712D03*
X149552Y1384297D03*
Y1372385D03*
X140712Y1396583D03*
X137312D03*
X140712Y1408495D03*
X137312D03*
X165192Y1348187D03*
X161792D03*
X165192Y1360099D03*
X161792D03*
X152952Y1384297D03*
Y1372385D03*
X165192Y1396583D03*
X161792D03*
X165192Y1408495D03*
X161792D03*
X177432Y1384297D03*
X174032D03*
Y1372385D03*
X177432D03*
X189672Y1348187D03*
X186272D03*
X189672Y1360099D03*
X186272D03*
X198512Y1384297D03*
Y1372385D03*
X186272Y1396583D03*
X189672D03*
Y1408495D03*
X186272D03*
X212980Y390995D03*
Y405168D03*
Y394395D03*
X205680Y401482D03*
Y398082D03*
X212980Y408568D03*
Y419341D03*
Y422741D03*
X205680Y415655D03*
Y412255D03*
Y426428D03*
Y440602D03*
Y429828D03*
X212980Y433515D03*
Y436915D03*
X205680Y444002D03*
X212980Y469381D03*
Y472781D03*
X205680Y490641D03*
Y479868D03*
X212980Y483554D03*
X205680Y476468D03*
X212980Y486954D03*
X205680Y494041D03*
Y524002D03*
X212980Y516915D03*
Y513515D03*
X205680Y520602D03*
Y534775D03*
X212980Y527688D03*
X205680Y538175D03*
X212980Y531088D03*
X201912Y1384297D03*
Y1372385D03*
X240412Y114655D03*
Y111255D03*
X233112Y132515D03*
Y121742D03*
X240412Y125428D03*
X233112Y118342D03*
X240412Y128828D03*
X233112Y135915D03*
X245023Y1372385D03*
X241623D03*
Y1384297D03*
X245023D03*
X264005Y467337D03*
Y470737D03*
X256705Y474424D03*
X264005Y484910D03*
X256705Y488597D03*
X264005Y481510D03*
X256705Y477824D03*
Y491997D03*
X264005Y514871D03*
X256705Y518558D03*
X264005Y511471D03*
X256705Y521958D03*
Y532731D03*
Y536131D03*
X264005Y525644D03*
Y529044D03*
Y561510D03*
X256705Y571997D03*
Y568597D03*
X264005Y564910D03*
X256705Y586171D03*
X264005Y575684D03*
Y579084D03*
X256705Y582771D03*
X264005Y589857D03*
X256705Y600344D03*
X264005Y593257D03*
Y604030D03*
X256705Y596944D03*
Y611117D03*
Y614517D03*
X264005Y607430D03*
X253863Y1348187D03*
X257263D03*
X253863Y1360099D03*
X257263D03*
X253863Y1396583D03*
X257263D03*
Y1408495D03*
X253863D03*
X278343Y1348187D03*
Y1360099D03*
X269503Y1372385D03*
X266103D03*
Y1384297D03*
X269503D03*
X278343Y1396583D03*
Y1408495D03*
X281743Y1348187D03*
Y1360099D03*
X293983Y1372385D03*
X290583Y1384297D03*
X293983D03*
X290583Y1372385D03*
X281743Y1396583D03*
Y1408495D03*
X302823Y1348187D03*
X306223D03*
Y1360099D03*
X302823D03*
Y1396583D03*
X306223D03*
X302823Y1408495D03*
X306223D03*
X320993Y467306D03*
Y470706D03*
Y481479D03*
Y484879D03*
Y514839D03*
Y511439D03*
Y525613D03*
Y529013D03*
Y564879D03*
Y561479D03*
Y575652D03*
Y579052D03*
Y603999D03*
Y593225D03*
Y589825D03*
Y607399D03*
X327303Y1348187D03*
Y1360099D03*
X315063Y1372385D03*
X318463Y1384297D03*
X315063D03*
X318463Y1372385D03*
X327303Y1396583D03*
Y1408495D03*
X342774Y111255D03*
Y114655D03*
X335474Y118342D03*
Y132515D03*
X342774Y125428D03*
X335474Y121742D03*
X342774Y128828D03*
X335474Y135915D03*
X331395Y474418D03*
Y488591D03*
Y477818D03*
Y491991D03*
Y518552D03*
Y521952D03*
Y536125D03*
Y532725D03*
Y568591D03*
Y571991D03*
Y586165D03*
Y582765D03*
Y600338D03*
Y596938D03*
Y611111D03*
Y614511D03*
X330703Y1348187D03*
Y1360099D03*
X339543Y1372385D03*
X342943D03*
Y1384297D03*
X339543D03*
X330703Y1396583D03*
Y1408495D03*
X351783Y1348187D03*
X355183D03*
Y1360099D03*
X351783D03*
Y1396583D03*
X355183D03*
X351783Y1408495D03*
X355183D03*
X364023Y1372385D03*
X367423Y1384297D03*
X364023D03*
X367423Y1372385D03*
X392415Y792725D03*
X389015D03*
X440402Y1372385D03*
Y1384297D03*
X452642Y1348187D03*
X456042D03*
Y1360099D03*
X452642D03*
X443802Y1372385D03*
Y1384297D03*
X452642Y1396583D03*
X456042D03*
X452642Y1408495D03*
X456042D03*
X464882Y1372385D03*
X468282D03*
X464882Y1384297D03*
X468282D03*
X485475Y118342D03*
Y121742D03*
Y132515D03*
Y135915D03*
X480522Y1348187D03*
X477122D03*
X480522Y1360099D03*
X477122D03*
X489362Y1372385D03*
Y1384297D03*
X480522Y1396583D03*
X477122D03*
Y1408495D03*
X480522D03*
X492775Y114655D03*
Y111255D03*
Y128828D03*
Y125428D03*
X501602Y1348187D03*
X505002D03*
X501602Y1360099D03*
X505002D03*
X492762Y1372385D03*
Y1384297D03*
X505002Y1396583D03*
X501602D03*
X505002Y1408495D03*
X501602D03*
X517242Y1372385D03*
X513842D03*
X517242Y1384297D03*
X513842D03*
X529482Y1348187D03*
X526082D03*
X529482Y1360099D03*
X526082D03*
X538322Y1384297D03*
Y1372385D03*
X526082Y1396583D03*
X529482D03*
Y1408495D03*
X526082D03*
X549168Y781600D03*
X545768D03*
X553962Y1348187D03*
X550562D03*
X553962Y1360099D03*
X550562D03*
X541722Y1372385D03*
Y1384297D03*
X553962Y1396583D03*
X550562D03*
X553962Y1408495D03*
X550562D03*
X566202Y1372385D03*
Y1384297D03*
X562802D03*
Y1372385D03*
X587837Y118342D03*
Y121742D03*
Y132515D03*
Y135915D03*
X595137Y111255D03*
Y114655D03*
Y125428D03*
Y128828D03*
X597776Y401513D03*
Y398113D03*
X595376Y412287D03*
Y426460D03*
Y415687D03*
Y440633D03*
Y429860D03*
Y444033D03*
Y469387D03*
Y472787D03*
Y483560D03*
Y486960D03*
Y513521D03*
Y516921D03*
Y531094D03*
Y527694D03*
X605778Y391001D03*
Y405174D03*
Y394401D03*
Y408574D03*
Y422747D03*
Y419347D03*
Y433521D03*
Y436921D03*
Y479899D03*
Y490673D03*
Y476499D03*
Y494073D03*
Y520633D03*
Y524033D03*
Y534806D03*
Y538206D03*
X650768Y1348187D03*
Y1360099D03*
X638528Y1372385D03*
X641928D03*
X638528Y1384297D03*
X641928D03*
X650768Y1396583D03*
Y1408495D03*
X670066Y390995D03*
Y405168D03*
X662766Y398082D03*
X670066Y408568D03*
Y394395D03*
X662766Y401482D03*
X670066Y422741D03*
Y419341D03*
X662766Y415655D03*
Y426428D03*
Y412255D03*
Y440602D03*
X670066Y433515D03*
X662766Y429828D03*
X670066Y436915D03*
X662766Y444002D03*
X670066Y469381D03*
Y472781D03*
X662766Y476468D03*
Y490641D03*
X670066Y483554D03*
Y486954D03*
X662766Y479868D03*
Y494041D03*
X670066Y516915D03*
X662766Y520602D03*
Y524002D03*
X670066Y513515D03*
Y527688D03*
X662766Y534775D03*
X670066Y531088D03*
X662766Y538175D03*
X654168Y1348187D03*
Y1360099D03*
X663008Y1372385D03*
X666408D03*
X663008Y1384297D03*
X666408D03*
X654168Y1396583D03*
Y1408495D03*
X678648Y1348187D03*
X675248D03*
X678648Y1360099D03*
X675248D03*
Y1396583D03*
X678648D03*
Y1408495D03*
X675248D03*
X697499Y114655D03*
Y111255D03*
X690199Y132515D03*
X697499Y125428D03*
Y128828D03*
X690199Y121742D03*
Y118342D03*
Y135915D03*
X699728Y1348187D03*
Y1360099D03*
X690888Y1372385D03*
X687488D03*
Y1384297D03*
X690888D03*
X699728Y1396583D03*
Y1408495D03*
X713791Y474424D03*
Y488597D03*
Y477824D03*
Y491997D03*
Y518558D03*
Y521958D03*
Y536131D03*
Y532731D03*
Y571997D03*
Y568597D03*
Y582771D03*
Y586171D03*
Y596944D03*
Y600344D03*
Y611117D03*
Y614517D03*
X703128Y1348187D03*
Y1360099D03*
X715368Y1372385D03*
X711968D03*
X715368Y1384297D03*
X711968D03*
X703128Y1396583D03*
Y1408495D03*
X721091Y470737D03*
Y467337D03*
Y484910D03*
Y481510D03*
Y514871D03*
Y511471D03*
Y525644D03*
Y529044D03*
Y561510D03*
Y564910D03*
Y579084D03*
Y575684D03*
Y593257D03*
Y604030D03*
Y589857D03*
Y607430D03*
X727608Y1348187D03*
X724208D03*
Y1360099D03*
X727608D03*
X724208Y1396489D03*
X727608D03*
X724208Y1408401D03*
X727608D03*
X748688Y1348187D03*
Y1360099D03*
X739848Y1372385D03*
X736448D03*
X739848Y1384297D03*
X736448D03*
X752088Y1348187D03*
Y1360099D03*
X764328Y1372385D03*
X760928D03*
X764328Y1384297D03*
X760928D03*
X778079Y467306D03*
Y470706D03*
Y481479D03*
Y484879D03*
Y514839D03*
Y511439D03*
Y529013D03*
Y525613D03*
Y561479D03*
Y564879D03*
Y575652D03*
Y579052D03*
Y589825D03*
Y593225D03*
Y603999D03*
Y607399D03*
X776568Y1348187D03*
X773168D03*
Y1360099D03*
X776568D03*
X799861Y114655D03*
Y111255D03*
X792561Y132515D03*
Y118342D03*
X799861Y128828D03*
X792561Y121742D03*
X799861Y125428D03*
X792561Y135915D03*
X788481Y474418D03*
Y477818D03*
Y488591D03*
Y491991D03*
Y518552D03*
Y521952D03*
Y532725D03*
Y536125D03*
Y571991D03*
Y568591D03*
Y586165D03*
Y582765D03*
Y600338D03*
Y596938D03*
Y614511D03*
Y611111D03*
X919163Y848442D03*
Y851592D03*
X942561Y118342D03*
Y132515D03*
Y121742D03*
Y135915D03*
X942731Y324044D03*
X939331D03*
X942700Y346363D03*
X939300D03*
X945982Y886737D03*
X949861Y111255D03*
Y114655D03*
Y125428D03*
Y128828D03*
X949382Y886737D03*
X1011187Y-33526D03*
Y-30126D03*
Y-43526D03*
Y-40126D03*
X1052223Y111255D03*
Y114655D03*
X1044923Y118342D03*
X1052223Y125428D03*
Y128828D03*
X1044923Y132515D03*
Y121742D03*
Y135915D03*
X1054863Y401513D03*
Y398113D03*
X1052463Y412287D03*
Y415687D03*
Y426460D03*
Y440633D03*
Y429860D03*
Y444033D03*
Y469387D03*
Y472787D03*
Y486960D03*
Y483560D03*
Y513521D03*
Y516921D03*
Y531094D03*
Y527694D03*
X1058113Y1372385D03*
X1054713D03*
Y1384297D03*
X1058113D03*
X1062865Y391001D03*
Y408574D03*
Y405174D03*
Y394401D03*
Y422747D03*
Y419347D03*
Y436921D03*
Y433521D03*
Y476499D03*
Y479899D03*
Y490673D03*
Y494073D03*
Y520633D03*
Y524033D03*
Y534806D03*
Y538206D03*
X1066953Y1348187D03*
X1070353D03*
X1066953Y1360099D03*
X1070353D03*
Y1396583D03*
X1066953D03*
Y1408495D03*
X1070353D03*
X1081187Y-79306D03*
Y-82706D03*
Y-72706D03*
Y-69306D03*
X1091433Y1348187D03*
Y1360099D03*
X1079193Y1372385D03*
X1082593D03*
Y1384297D03*
X1079193D03*
X1091433Y1396583D03*
Y1408495D03*
X1094833Y1348187D03*
Y1360099D03*
X1107073Y1372385D03*
X1103673D03*
X1107073Y1384297D03*
X1103673D03*
X1094833Y1396583D03*
Y1408495D03*
X1119853Y398082D03*
Y401482D03*
Y412255D03*
Y426428D03*
Y415655D03*
Y440602D03*
Y429828D03*
Y444002D03*
Y490641D03*
Y476468D03*
Y479868D03*
Y494041D03*
Y524002D03*
Y520602D03*
Y538175D03*
Y534775D03*
X1115913Y1348187D03*
X1119313D03*
X1115913Y1360099D03*
X1119313D03*
X1115913Y1396583D03*
X1119313D03*
X1115913Y1408495D03*
X1119313D03*
X1127153Y390995D03*
Y408568D03*
Y405168D03*
Y394395D03*
Y422741D03*
Y419341D03*
Y436915D03*
Y433515D03*
Y472781D03*
Y469381D03*
Y486954D03*
Y483554D03*
Y516915D03*
Y513515D03*
Y527688D03*
Y531088D03*
X1140393Y1348187D03*
Y1360099D03*
X1128153Y1384297D03*
X1131553D03*
X1128153Y1372385D03*
X1131553D03*
X1140393Y1396583D03*
Y1408495D03*
X1154585Y114655D03*
Y111255D03*
Y128828D03*
X1147285Y118342D03*
Y121742D03*
Y132515D03*
X1154585Y125428D03*
X1147285Y135915D03*
X1143793Y1348187D03*
Y1360099D03*
X1156033Y1384297D03*
X1152633D03*
X1156033Y1372385D03*
X1152633D03*
X1143793Y1396583D03*
Y1408495D03*
X1170878Y474424D03*
Y477824D03*
Y488597D03*
Y491997D03*
Y518558D03*
Y521958D03*
Y532731D03*
Y536131D03*
Y571997D03*
Y568597D03*
Y586171D03*
Y582771D03*
Y596944D03*
Y600344D03*
Y614517D03*
Y611117D03*
X1168273Y1348187D03*
X1164873D03*
Y1360099D03*
X1168273D03*
X1164873Y1396583D03*
X1168273D03*
Y1408495D03*
X1164873D03*
X1178178Y467337D03*
Y470737D03*
Y484910D03*
Y481510D03*
Y511471D03*
Y514871D03*
Y529044D03*
Y525644D03*
Y564910D03*
Y561510D03*
Y579084D03*
Y575684D03*
Y604030D03*
Y593257D03*
Y589857D03*
Y607430D03*
X1177113Y1384297D03*
X1180513D03*
X1177113Y1372385D03*
X1180513D03*
X1225405Y-79278D03*
Y-82678D03*
Y-72678D03*
Y-69278D03*
X1230761Y-33628D03*
Y-30228D03*
Y-43628D03*
Y-40228D03*
X1235166Y470706D03*
Y467306D03*
Y484879D03*
Y481479D03*
Y514839D03*
Y511439D03*
Y529013D03*
Y525613D03*
Y564879D03*
Y561479D03*
Y575652D03*
Y579052D03*
Y593225D03*
Y603999D03*
Y589825D03*
Y607399D03*
X1230326Y1372385D03*
X1233726D03*
X1230326Y1384297D03*
X1233726D03*
X1249647Y118342D03*
Y132515D03*
Y121742D03*
Y135915D03*
X1245568Y474418D03*
Y488591D03*
Y477818D03*
Y491991D03*
Y521952D03*
Y518552D03*
Y536125D03*
Y532725D03*
Y568591D03*
Y571991D03*
Y582765D03*
Y586165D03*
Y596938D03*
Y600338D03*
Y611111D03*
Y614511D03*
X1245966Y1348187D03*
X1242566D03*
Y1360099D03*
X1245966D03*
X1254806Y1372385D03*
Y1384297D03*
X1245966Y1396583D03*
X1242566D03*
Y1408495D03*
X1245966D03*
X1256947Y114655D03*
Y111255D03*
Y128828D03*
Y125428D03*
X1267046Y1348187D03*
X1270446D03*
Y1360099D03*
X1267046D03*
X1258206Y1372385D03*
Y1384297D03*
X1267046Y1396583D03*
X1270446D03*
Y1408495D03*
X1267046D03*
X1279286Y1372385D03*
X1282686D03*
Y1384297D03*
X1279286D03*
X1297687Y-33656D03*
Y-40256D03*
Y-30256D03*
Y-43656D03*
X1291526Y1348187D03*
X1294926D03*
X1291526Y1360099D03*
X1294926D03*
Y1396583D03*
X1291526D03*
Y1408495D03*
X1294926D03*
X1319406Y1348187D03*
X1316006D03*
X1319406Y1360099D03*
X1316006D03*
X1307166Y1372385D03*
X1303766D03*
Y1384297D03*
X1307166D03*
X1319406Y1396583D03*
X1316006D03*
Y1408495D03*
X1319406D03*
X1331646Y1384297D03*
Y1372385D03*
X1328246D03*
Y1384297D03*
X1337687Y-79306D03*
Y-82706D03*
Y-69306D03*
Y-72706D03*
X1343886Y1348187D03*
X1340486D03*
X1343886Y1360099D03*
X1340486D03*
Y1396583D03*
X1343886D03*
Y1408495D03*
X1340486D03*
X1352726Y1384297D03*
X1356126Y1372385D03*
Y1384297D03*
X1352726Y1372385D03*
X1399648Y132515D03*
Y121742D03*
Y118342D03*
Y135915D03*
X1406948Y111255D03*
Y114655D03*
Y128828D03*
Y125428D03*
X1464770Y1372385D03*
X1461370D03*
X1464770Y1384297D03*
X1461370D03*
X1481905Y-79278D03*
Y-82678D03*
Y-69278D03*
Y-72678D03*
X1477010Y1348187D03*
X1473610D03*
Y1360099D03*
X1477010D03*
Y1396583D03*
X1473610D03*
Y1408495D03*
X1477010D03*
X1498090Y1348187D03*
Y1360099D03*
X1489250Y1372385D03*
X1485850D03*
Y1384297D03*
X1489250D03*
X1498090Y1396583D03*
Y1408495D03*
X1509310Y114655D03*
Y111255D03*
X1502010Y121742D03*
X1509310Y125428D03*
Y128828D03*
X1502010Y118342D03*
Y132515D03*
Y135915D03*
X1511950Y401513D03*
Y398113D03*
X1509550Y412287D03*
Y415687D03*
Y426460D03*
Y440633D03*
Y429860D03*
Y444033D03*
Y472787D03*
Y469387D03*
Y483560D03*
Y486960D03*
Y516921D03*
Y513521D03*
Y527694D03*
Y531094D03*
X1501490Y1348187D03*
Y1360099D03*
X1510330Y1372385D03*
X1513730D03*
Y1384297D03*
X1510330D03*
X1501490Y1396583D03*
Y1408495D03*
X1517261Y-33758D03*
Y-40358D03*
Y-30358D03*
Y-43758D03*
X1519952Y391001D03*
Y394401D03*
Y408574D03*
Y405174D03*
Y422747D03*
Y419347D03*
Y436921D03*
Y433521D03*
Y479899D03*
Y476499D03*
Y490673D03*
Y494073D03*
Y520633D03*
Y524033D03*
Y534806D03*
Y538206D03*
X1525970Y1348187D03*
X1522570D03*
Y1360099D03*
X1525970D03*
X1522570Y1396583D03*
X1525970D03*
Y1408495D03*
X1522570D03*
X1547050Y1348187D03*
Y1360099D03*
X1538210Y1372385D03*
X1534810D03*
Y1384297D03*
X1538210D03*
X1547050Y1396583D03*
Y1408495D03*
X1550450Y1348187D03*
Y1360099D03*
X1562690Y1372385D03*
X1559290D03*
X1562690Y1384297D03*
X1559290D03*
X1550450Y1396583D03*
Y1408495D03*
X1576940Y398082D03*
Y401482D03*
Y415655D03*
Y412255D03*
Y426428D03*
Y440602D03*
Y429828D03*
Y444002D03*
Y476468D03*
Y490641D03*
Y479868D03*
Y494041D03*
Y520602D03*
Y524002D03*
Y534775D03*
Y538175D03*
X1574930Y1348187D03*
X1571530D03*
X1574930Y1360099D03*
X1571530D03*
Y1396583D03*
X1574930D03*
X1571530Y1408495D03*
X1574930D03*
X1592187Y-79306D03*
Y-82706D03*
Y-69306D03*
Y-72706D03*
X1582187Y-33786D03*
Y-43786D03*
Y-30386D03*
Y-40386D03*
X1584240Y390995D03*
Y408568D03*
Y405168D03*
Y394395D03*
Y419341D03*
Y422741D03*
Y433515D03*
Y436915D03*
Y472781D03*
Y469381D03*
Y483554D03*
Y486954D03*
Y516915D03*
Y513515D03*
Y531088D03*
Y527688D03*
X1587170Y1372385D03*
X1583770D03*
Y1384297D03*
X1587170D03*
X1611672Y111255D03*
Y114655D03*
X1604372Y118342D03*
X1611672Y125428D03*
X1604372Y121742D03*
X1611672Y128828D03*
X1604372Y132515D03*
Y135915D03*
X1611398Y1384297D03*
Y1372385D03*
X1627965Y474424D03*
Y488597D03*
Y477824D03*
Y491997D03*
Y521958D03*
Y518558D03*
Y536131D03*
Y532731D03*
Y571997D03*
Y568597D03*
Y582771D03*
Y586171D03*
Y596944D03*
Y600344D03*
Y614517D03*
Y611117D03*
X1623638Y1348187D03*
X1627038D03*
X1623638Y1360099D03*
X1627038D03*
X1614798Y1372385D03*
Y1384297D03*
X1627038Y1396583D03*
X1623638D03*
X1627038Y1408495D03*
X1623638D03*
X1635265Y470737D03*
Y467337D03*
Y484910D03*
Y481510D03*
Y514871D03*
Y511471D03*
Y529044D03*
Y525644D03*
Y564910D03*
Y561510D03*
Y575684D03*
Y579084D03*
Y593257D03*
Y604030D03*
Y589857D03*
Y607430D03*
X1635878Y1384297D03*
X1639278D03*
Y1372385D03*
X1635878D03*
X1651518Y1348187D03*
X1648118D03*
X1651518Y1360099D03*
X1648118D03*
X1660358Y1384297D03*
Y1372385D03*
X1651518Y1396583D03*
X1648118D03*
Y1408495D03*
X1651518D03*
X1672598Y1348187D03*
X1675998D03*
Y1360099D03*
X1672598D03*
X1663758Y1384297D03*
Y1372385D03*
X1675998Y1396583D03*
X1672598D03*
X1675998Y1408495D03*
X1672598D03*
X1692253Y467306D03*
Y470706D03*
Y484879D03*
Y481479D03*
Y511439D03*
Y514839D03*
Y529013D03*
Y525613D03*
Y561479D03*
Y564879D03*
Y575652D03*
Y579052D03*
Y593225D03*
Y603999D03*
Y589825D03*
Y607399D03*
X1684838Y1384297D03*
X1688238D03*
X1684838Y1372385D03*
X1688238D03*
X1706734Y118342D03*
Y132515D03*
Y121742D03*
Y135915D03*
X1702655Y474418D03*
Y477818D03*
Y488591D03*
Y491991D03*
Y521952D03*
Y518552D03*
Y536125D03*
Y532725D03*
Y571991D03*
Y568591D03*
Y586165D03*
Y582765D03*
Y600338D03*
Y596938D03*
Y611111D03*
Y614511D03*
X1700478Y1348187D03*
X1697078D03*
Y1360099D03*
X1700478D03*
X1709318Y1384297D03*
Y1372385D03*
X1700478Y1396583D03*
X1697078D03*
Y1408495D03*
X1700478D03*
X1714034Y111255D03*
Y114655D03*
Y125428D03*
Y128828D03*
X1721558Y1348187D03*
X1724958D03*
Y1360099D03*
X1721558D03*
X1712718Y1372385D03*
Y1384297D03*
X1721558Y1396583D03*
X1724958D03*
X1721558Y1408495D03*
X1724958D03*
X1736405Y-79278D03*
Y-82678D03*
Y-69278D03*
Y-72678D03*
X1737198Y1384297D03*
X1733798D03*
Y1372385D03*
X1737198D03*
X1801761Y-33888D03*
Y-43888D03*
Y-30488D03*
Y-40488D03*
G54D11*
X13780Y1226024D03*
X79331Y1186654D03*
X390354Y1141024D03*
X536418Y1086654D03*
X854291Y1225118D03*
X993504Y1170748D03*
X1304528Y1141024D03*
X1450591Y1086654D03*
X1761614Y1215000D03*
X1827165Y1235630D03*
G54D44*
X661674Y23622D03*
G54D19*
X23622Y1604724D03*
X62205Y765197D03*
X74016Y333464D03*
X102224Y70866D03*
X409488Y1604724D03*
X433130Y70866D03*
X463387Y286221D03*
X463386Y765197D03*
X785039Y1547638D03*
X890217Y23622D03*
X920473Y765196D03*
X1055905Y1547637D03*
X1118760Y23622D03*
X1347303Y70866D03*
X1377559Y286220D03*
Y765197D03*
X1431457Y1604724D03*
X1575846Y23622D03*
X1766929Y333464D03*
X1778740Y765197D03*
X1795010Y23622D03*
X1817323Y1604724D03*
G54D20*
X28819Y81575D03*
X73307Y61614D03*
X131181Y81575D03*
X175669Y61614D03*
X233543Y81575D03*
X278032Y61614D03*
X335906Y81575D03*
X380394Y61614D03*
X485886Y81595D03*
X530394Y61614D03*
X588248Y81594D03*
X632756Y61614D03*
X690611Y81595D03*
X735118Y61614D03*
X792973Y81595D03*
X837480Y61614D03*
X942973Y81595D03*
X987480Y61614D03*
X1045335Y81595D03*
X1089843Y61614D03*
X1147697Y81595D03*
X1192205Y61614D03*
X1250060Y81595D03*
X1294567Y61614D03*
X1400060Y81595D03*
X1444567Y61614D03*
X1502441Y81575D03*
X1546929Y61614D03*
X1604784Y81595D03*
X1649291Y61614D03*
X1707146Y81595D03*
X1751654Y61614D03*
G54D34*
X109882Y1473977D03*
Y1479095D03*
Y1504685D03*
Y1509804D03*
Y1576339D03*
Y1581457D03*
Y1607048D03*
Y1612166D03*
X127205Y1473977D03*
Y1479095D03*
X118543Y1478308D03*
Y1483426D03*
X127205Y1504685D03*
Y1509804D03*
X118543Y1509016D03*
Y1514134D03*
X127205Y1576339D03*
Y1581457D03*
X118543Y1580670D03*
Y1585788D03*
X127205Y1607048D03*
Y1612166D03*
X118543Y1611378D03*
Y1616496D03*
X144528Y1473977D03*
Y1479095D03*
X135866Y1478308D03*
Y1483426D03*
X144528Y1504685D03*
Y1509804D03*
X135866Y1509016D03*
Y1514134D03*
X144528Y1576339D03*
Y1581457D03*
X135866Y1580670D03*
Y1585788D03*
X144528Y1607048D03*
Y1612166D03*
X135866Y1611378D03*
Y1616496D03*
X161850Y1473977D03*
Y1479095D03*
X153189Y1478308D03*
Y1483426D03*
X161850Y1504685D03*
Y1509804D03*
X153189Y1509016D03*
Y1514134D03*
X161850Y1576339D03*
Y1581457D03*
X153189Y1580670D03*
Y1585788D03*
X161850Y1607048D03*
Y1612166D03*
X153189Y1611378D03*
Y1616496D03*
X170512Y1478308D03*
Y1483426D03*
Y1509016D03*
Y1514134D03*
Y1580670D03*
Y1585788D03*
Y1611378D03*
Y1616496D03*
X283110Y1458622D03*
X291771Y1462953D03*
X283110Y1463741D03*
X291771Y1468071D03*
X283110Y1473977D03*
X291771Y1478308D03*
X283110Y1479095D03*
X291771Y1483426D03*
X283110Y1489331D03*
X291771Y1493662D03*
X283110Y1494449D03*
X291771Y1498780D03*
X283110Y1560985D03*
X291771Y1565315D03*
X283110Y1566103D03*
X291771Y1570434D03*
X283110Y1576339D03*
X291771Y1580670D03*
X283110Y1581457D03*
X291771Y1585788D03*
X283110Y1591693D03*
X291771Y1596024D03*
X283110Y1596811D03*
X291771Y1601142D03*
X300433Y1458622D03*
X309094Y1462953D03*
X300433Y1463741D03*
X309094Y1468071D03*
X300433Y1473977D03*
X309094Y1478308D03*
X300433Y1479095D03*
X309094Y1483426D03*
X300433Y1489331D03*
X309094Y1493662D03*
X300433Y1494449D03*
X309094Y1498780D03*
X300433Y1560985D03*
X309094Y1565315D03*
X300433Y1566103D03*
X309094Y1570434D03*
X300433Y1576339D03*
X309094Y1580670D03*
X300433Y1581457D03*
X309094Y1585788D03*
X300433Y1591693D03*
X309094Y1596024D03*
X300433Y1596811D03*
X309094Y1601142D03*
X317756Y1458622D03*
X326417Y1462953D03*
X317756Y1463741D03*
X326417Y1468071D03*
X317756Y1473977D03*
X326417Y1478308D03*
X317756Y1479095D03*
X326417Y1483426D03*
X317756Y1489331D03*
X326417Y1493662D03*
X317756Y1494449D03*
X326417Y1498780D03*
X317756Y1560985D03*
X326417Y1565315D03*
X317756Y1566103D03*
X326417Y1570434D03*
X317756Y1576339D03*
X326417Y1580670D03*
X317756Y1581457D03*
X326417Y1585788D03*
X317756Y1591693D03*
X326417Y1596024D03*
X317756Y1596811D03*
X326417Y1601142D03*
X335078Y1458622D03*
X343740Y1462953D03*
X335078Y1463741D03*
X343740Y1468071D03*
X335078Y1473977D03*
X343740Y1478308D03*
X335078Y1479095D03*
X343740Y1483426D03*
X335078Y1489331D03*
X343740Y1493662D03*
X335078Y1494449D03*
X343740Y1498780D03*
X335078Y1560985D03*
X343740Y1565315D03*
X335078Y1566103D03*
X343740Y1570434D03*
X335078Y1576339D03*
X343740Y1580670D03*
X335078Y1581457D03*
X343740Y1585788D03*
X335078Y1591693D03*
X343740Y1596024D03*
X335078Y1596811D03*
X343740Y1601142D03*
X456339Y1473977D03*
Y1479095D03*
Y1504685D03*
Y1509804D03*
Y1560985D03*
Y1566103D03*
Y1591693D03*
Y1596811D03*
X473662Y1473977D03*
Y1479095D03*
X465000Y1478308D03*
Y1483426D03*
X473662Y1504685D03*
Y1509804D03*
X465000Y1509016D03*
Y1514134D03*
X473662Y1560985D03*
Y1566103D03*
X465000Y1565315D03*
Y1570434D03*
X473662Y1591693D03*
X465000Y1596024D03*
X473662Y1596811D03*
X465000Y1601142D03*
X490985Y1473977D03*
Y1479095D03*
X482323Y1478308D03*
Y1483426D03*
X490985Y1504685D03*
Y1509804D03*
X482323Y1509016D03*
Y1514134D03*
X490985Y1560985D03*
Y1566103D03*
X482323Y1565315D03*
Y1570434D03*
X490985Y1591693D03*
X482323Y1596024D03*
X490985Y1596811D03*
X482323Y1601142D03*
X499646Y1478308D03*
Y1483426D03*
Y1509016D03*
Y1514134D03*
Y1565315D03*
Y1570434D03*
Y1596024D03*
Y1601142D03*
X508307Y1473977D03*
X516969Y1478308D03*
X508307Y1479095D03*
X516969Y1483426D03*
X508307Y1504685D03*
X516969Y1509016D03*
X508307Y1509804D03*
X516969Y1514134D03*
X508307Y1560985D03*
X516969Y1565315D03*
X508307Y1566103D03*
X516969Y1570434D03*
X508307Y1591693D03*
X516969Y1596024D03*
X508307Y1596811D03*
X516969Y1601142D03*
X629567Y1458622D03*
Y1463741D03*
Y1489331D03*
Y1494449D03*
Y1504685D03*
Y1509804D03*
Y1560985D03*
Y1566103D03*
Y1591693D03*
Y1596811D03*
Y1607048D03*
Y1612166D03*
X646890Y1458622D03*
Y1463741D03*
X638228Y1462953D03*
Y1468071D03*
X646890Y1489331D03*
Y1494449D03*
X638228Y1493662D03*
Y1498780D03*
X646890Y1504685D03*
Y1509804D03*
X638228Y1509016D03*
Y1514134D03*
X646890Y1560985D03*
Y1566103D03*
X638228Y1565315D03*
Y1570434D03*
X646890Y1591693D03*
X638228Y1596024D03*
X646890Y1596811D03*
Y1607048D03*
Y1612166D03*
X638228Y1601142D03*
Y1611378D03*
Y1616496D03*
X664213Y1458622D03*
Y1463741D03*
X655551Y1462953D03*
Y1468071D03*
X664213Y1489331D03*
Y1494449D03*
X655551Y1493662D03*
Y1498780D03*
X664213Y1504685D03*
Y1509804D03*
X655551Y1509016D03*
Y1514134D03*
X664213Y1560985D03*
Y1566103D03*
X655551Y1565315D03*
Y1570434D03*
X664213Y1591693D03*
X655551Y1596024D03*
X664213Y1596811D03*
Y1607048D03*
Y1612166D03*
X655551Y1601142D03*
Y1611378D03*
Y1616496D03*
X681535Y1458622D03*
Y1463741D03*
X672874Y1462953D03*
Y1468071D03*
X681535Y1489331D03*
Y1494449D03*
X672874Y1493662D03*
Y1498780D03*
X681535Y1504685D03*
Y1509804D03*
X672874Y1509016D03*
Y1514134D03*
X681535Y1560985D03*
Y1566103D03*
X672874Y1565315D03*
Y1570434D03*
X681535Y1591693D03*
X672874Y1596024D03*
X681535Y1596811D03*
Y1607048D03*
Y1612166D03*
X672874Y1601142D03*
Y1611378D03*
Y1616496D03*
X690197Y1462953D03*
Y1468071D03*
Y1493662D03*
Y1498780D03*
Y1509016D03*
Y1514134D03*
Y1565315D03*
Y1570434D03*
Y1596024D03*
Y1601142D03*
Y1611378D03*
Y1616496D03*
X1131850Y1473977D03*
X1140511Y1478308D03*
X1131850Y1479095D03*
X1140511Y1483426D03*
X1131850Y1504685D03*
X1140511Y1509016D03*
X1131850Y1509804D03*
X1140511Y1514134D03*
X1131850Y1576339D03*
X1140511Y1580670D03*
X1131850Y1581457D03*
X1140511Y1585788D03*
X1131850Y1607048D03*
X1140511Y1611378D03*
X1131850Y1612166D03*
X1140511Y1616496D03*
X1149173Y1473977D03*
Y1479095D03*
Y1504685D03*
Y1509804D03*
Y1576339D03*
Y1581457D03*
Y1607048D03*
Y1612166D03*
X1166496Y1473977D03*
Y1479095D03*
X1157834Y1478308D03*
Y1483426D03*
X1166496Y1504685D03*
Y1509804D03*
X1157834Y1509016D03*
Y1514134D03*
X1166496Y1576339D03*
Y1581457D03*
X1157834Y1580670D03*
Y1585788D03*
X1166496Y1607048D03*
Y1612166D03*
X1157834Y1611378D03*
Y1616496D03*
X1183818Y1473977D03*
Y1479095D03*
X1175157Y1478308D03*
Y1483426D03*
X1183818Y1504685D03*
Y1509804D03*
X1175157Y1509016D03*
Y1514134D03*
X1183818Y1576339D03*
Y1581457D03*
X1175157Y1580670D03*
Y1585788D03*
X1183818Y1607048D03*
Y1612166D03*
X1175157Y1611378D03*
Y1616496D03*
X1192480Y1478308D03*
Y1483426D03*
Y1509016D03*
Y1514134D03*
Y1580670D03*
Y1585788D03*
Y1611378D03*
Y1616496D03*
X1305079Y1458622D03*
X1313740Y1462953D03*
X1305079Y1463741D03*
X1313740Y1468071D03*
X1305079Y1473977D03*
X1313740Y1478308D03*
X1305079Y1479095D03*
X1313740Y1483426D03*
X1305079Y1489331D03*
X1313740Y1493662D03*
X1305079Y1494449D03*
X1313740Y1498780D03*
X1305079Y1560985D03*
X1313740Y1565315D03*
X1305079Y1566103D03*
X1313740Y1570434D03*
X1305079Y1576339D03*
X1313740Y1580670D03*
X1305079Y1581457D03*
X1313740Y1585788D03*
X1305079Y1591693D03*
X1313740Y1596024D03*
X1305079Y1596811D03*
X1313740Y1601142D03*
X1322402Y1458622D03*
X1331063Y1462953D03*
X1322402Y1463741D03*
X1331063Y1468071D03*
X1322402Y1473977D03*
X1331063Y1478308D03*
X1322402Y1479095D03*
X1331063Y1483426D03*
X1322402Y1489331D03*
X1331063Y1493662D03*
X1322402Y1494449D03*
X1331063Y1498780D03*
X1322402Y1560985D03*
X1331063Y1565315D03*
X1322402Y1566103D03*
X1331063Y1570434D03*
X1322402Y1576339D03*
X1331063Y1580670D03*
X1322402Y1581457D03*
X1331063Y1585788D03*
X1322402Y1591693D03*
X1331063Y1596024D03*
X1322402Y1596811D03*
X1331063Y1601142D03*
X1339725Y1458622D03*
X1348386Y1462953D03*
X1339725Y1463741D03*
X1348386Y1468071D03*
X1339725Y1473977D03*
X1348386Y1478308D03*
X1339725Y1479095D03*
X1348386Y1483426D03*
X1339725Y1489331D03*
X1348386Y1493662D03*
X1339725Y1494449D03*
X1348386Y1498780D03*
X1339725Y1560985D03*
X1348386Y1565315D03*
X1339725Y1566103D03*
X1348386Y1570434D03*
X1339725Y1576339D03*
X1348386Y1580670D03*
X1339725Y1581457D03*
X1348386Y1585788D03*
X1339725Y1591693D03*
X1348386Y1596024D03*
X1339725Y1596811D03*
X1348386Y1601142D03*
X1357047Y1458622D03*
X1365709Y1462953D03*
X1357047Y1463741D03*
X1365709Y1468071D03*
X1357047Y1473977D03*
X1365709Y1478308D03*
X1357047Y1479095D03*
X1365709Y1483426D03*
X1357047Y1489331D03*
X1365709Y1493662D03*
X1357047Y1494449D03*
X1365709Y1498780D03*
X1357047Y1560985D03*
X1365709Y1565315D03*
X1357047Y1566103D03*
X1365709Y1570434D03*
X1357047Y1576339D03*
X1365709Y1580670D03*
X1357047Y1581457D03*
X1365709Y1585788D03*
X1357047Y1591693D03*
X1365709Y1596024D03*
X1357047Y1596811D03*
X1365709Y1601142D03*
X1478307Y1473977D03*
Y1479095D03*
Y1504685D03*
Y1509804D03*
Y1560985D03*
Y1566103D03*
Y1591693D03*
Y1596811D03*
X1495630Y1473977D03*
Y1479095D03*
X1486968Y1478308D03*
Y1483426D03*
X1495630Y1504685D03*
Y1509804D03*
X1486968Y1509016D03*
Y1514134D03*
X1495630Y1560985D03*
Y1566103D03*
X1486968Y1565315D03*
Y1570434D03*
X1495630Y1591693D03*
X1486968Y1596024D03*
X1495630Y1596811D03*
X1486968Y1601142D03*
X1512953Y1473977D03*
Y1479095D03*
X1504291Y1478308D03*
Y1483426D03*
X1512953Y1504685D03*
Y1509804D03*
X1504291Y1509016D03*
Y1514134D03*
X1512953Y1560985D03*
Y1566103D03*
X1504291Y1565315D03*
Y1570434D03*
X1512953Y1591693D03*
X1504291Y1596024D03*
X1512953Y1596811D03*
X1504291Y1601142D03*
X1530275Y1473977D03*
Y1479095D03*
X1521614Y1478308D03*
Y1483426D03*
X1530275Y1504685D03*
Y1509804D03*
X1521614Y1509016D03*
Y1514134D03*
X1530275Y1560985D03*
Y1566103D03*
X1521614Y1565315D03*
Y1570434D03*
X1530275Y1591693D03*
X1521614Y1596024D03*
X1530275Y1596811D03*
X1521614Y1601142D03*
X1538937Y1478308D03*
Y1483426D03*
Y1509016D03*
Y1514134D03*
Y1565315D03*
Y1570434D03*
Y1596024D03*
Y1601142D03*
X1651535Y1458622D03*
X1660196Y1462953D03*
X1651535Y1463741D03*
X1660196Y1468071D03*
X1651535Y1489331D03*
X1660196Y1493662D03*
X1651535Y1494449D03*
X1660196Y1498780D03*
X1651535Y1504685D03*
X1660196Y1509016D03*
X1651535Y1509804D03*
X1660196Y1514134D03*
X1651535Y1560985D03*
X1660196Y1565315D03*
X1651535Y1566103D03*
X1660196Y1570434D03*
X1651535Y1591693D03*
X1660196Y1596024D03*
X1651535Y1596811D03*
X1660196Y1601142D03*
X1651535Y1607048D03*
X1660196Y1611378D03*
X1651535Y1612166D03*
X1660196Y1616496D03*
X1668858Y1458622D03*
Y1463741D03*
Y1489331D03*
Y1494449D03*
Y1504685D03*
Y1509804D03*
Y1560985D03*
Y1566103D03*
Y1591693D03*
Y1596811D03*
Y1607048D03*
Y1612166D03*
X1686181Y1458622D03*
Y1463741D03*
X1677519Y1462953D03*
Y1468071D03*
X1686181Y1489331D03*
Y1494449D03*
X1677519Y1493662D03*
Y1498780D03*
X1686181Y1504685D03*
Y1509804D03*
X1677519Y1509016D03*
Y1514134D03*
X1686181Y1560985D03*
Y1566103D03*
X1677519Y1565315D03*
Y1570434D03*
X1686181Y1591693D03*
X1677519Y1596024D03*
X1686181Y1596811D03*
Y1607048D03*
Y1612166D03*
X1677519Y1601142D03*
Y1611378D03*
Y1616496D03*
X1703503Y1458622D03*
Y1463741D03*
X1694842Y1462953D03*
Y1468071D03*
X1703503Y1489331D03*
Y1494449D03*
X1694842Y1493662D03*
Y1498780D03*
X1703503Y1504685D03*
Y1509804D03*
X1694842Y1509016D03*
Y1514134D03*
X1703503Y1560985D03*
Y1566103D03*
X1694842Y1565315D03*
Y1570434D03*
X1703503Y1591693D03*
X1694842Y1596024D03*
X1703503Y1596811D03*
Y1607048D03*
Y1612166D03*
X1694842Y1601142D03*
Y1611378D03*
Y1616496D03*
X1712165Y1462953D03*
Y1468071D03*
Y1493662D03*
Y1498780D03*
Y1509016D03*
Y1514134D03*
Y1565315D03*
Y1570434D03*
Y1596024D03*
Y1601142D03*
Y1611378D03*
Y1616496D03*
G54D38*
X173829Y455492D03*
Y583957D03*
X202844Y455492D03*
Y583957D03*
X630915Y455492D03*
Y583957D03*
X659930Y455492D03*
Y583957D03*
X1088002Y455492D03*
Y583957D03*
X1117017Y455492D03*
Y583957D03*
X1545089Y455492D03*
Y583957D03*
X1574104Y455492D03*
Y583957D03*
G54D61*
X1795453Y812874D03*
Y834922D03*
G54D48*
X849441Y1367717D03*
G54D50*
X895384Y228740D03*
Y276772D03*
X923336Y226772D03*
Y278740D03*
G54D55*
X1030635Y764546D03*
G54D62*
X1803917Y823898D03*
G54D59*
X1747253Y1715189D03*
Y1744208D03*
X1747246Y1773377D03*
G54D60*
X1747253Y1802909D03*
G54D63*
X1817323Y1567323D03*
G54D13*
X19685Y-83298D03*
Y1801195D03*
X1821260Y-83298D03*
Y1801195D03*
G54D30*
X116731Y1066535D03*
Y1263386D03*
X352952Y1066535D03*
Y1263386D03*
X573818Y1066535D03*
Y1263386D03*
X810038Y1066535D03*
Y1263386D03*
X1030905Y1066535D03*
Y1263386D03*
X1267125Y1066535D03*
Y1263386D03*
X1487991Y1066535D03*
Y1263386D03*
X1724212Y1066535D03*
Y1263386D03*
G54D17*
X26789Y1373669D03*
X184851Y334492D03*
X235433Y1580079D03*
Y1626339D03*
X581890Y1580079D03*
Y1626339D03*
X1259055Y1580079D03*
Y1626339D03*
X1605512Y1580079D03*
Y1626339D03*
X1796847Y1517889D03*
X1809883Y120792D03*
G54D47*
X770472Y1490945D03*
X820079Y388583D03*
X1020866D03*
X1070472Y1490945D03*
G54D32*
X109882Y1453504D03*
Y1468859D03*
Y1484213D03*
Y1499567D03*
Y1514922D03*
Y1555867D03*
Y1571221D03*
Y1586575D03*
Y1601930D03*
Y1617284D03*
X127205Y1453504D03*
X118543Y1457835D03*
X127205Y1468859D03*
X118543Y1473189D03*
X127205Y1484213D03*
X118543Y1488544D03*
X127205Y1499567D03*
Y1514922D03*
X118543Y1503898D03*
Y1519252D03*
X127205Y1555867D03*
X118543Y1560197D03*
X127205Y1571221D03*
X118543Y1575552D03*
X127205Y1586575D03*
X118543Y1590906D03*
X127205Y1601930D03*
X118543Y1606260D03*
X127205Y1617284D03*
X118543Y1621615D03*
X144528Y1453504D03*
X135866Y1457835D03*
X144528Y1468859D03*
X135866Y1473189D03*
X144528Y1484213D03*
X135866Y1488544D03*
X144528Y1499567D03*
Y1514922D03*
X135866Y1503898D03*
Y1519252D03*
X144528Y1555867D03*
X135866Y1560197D03*
X144528Y1571221D03*
X135866Y1575552D03*
X144528Y1586575D03*
X135866Y1590906D03*
X144528Y1601930D03*
X135866Y1606260D03*
X144528Y1617284D03*
X135866Y1621615D03*
X161850Y1453504D03*
X153189Y1457835D03*
X161850Y1468859D03*
X153189Y1473189D03*
X161850Y1484213D03*
X153189Y1488544D03*
X161850Y1499567D03*
Y1514922D03*
X153189Y1503898D03*
Y1519252D03*
X161850Y1555867D03*
X153189Y1560197D03*
X161850Y1571221D03*
X153189Y1575552D03*
X161850Y1586575D03*
X153189Y1590906D03*
X161850Y1601930D03*
X153189Y1606260D03*
X161850Y1617284D03*
X153189Y1621615D03*
X179173Y1453504D03*
X170512Y1457835D03*
X179173Y1468859D03*
X170512Y1473189D03*
X179173Y1484213D03*
X170512Y1488544D03*
X179173Y1499567D03*
Y1514922D03*
X170512Y1503898D03*
Y1519252D03*
X179173Y1555867D03*
X170512Y1560197D03*
X179173Y1571221D03*
X170512Y1575552D03*
X179173Y1586575D03*
X170512Y1590906D03*
X179173Y1601930D03*
X170512Y1606260D03*
X179173Y1617284D03*
X170512Y1621615D03*
X187835Y1457835D03*
Y1473189D03*
Y1488544D03*
Y1503898D03*
Y1519252D03*
Y1560197D03*
Y1575552D03*
Y1590906D03*
Y1606260D03*
Y1621615D03*
X283110Y1453504D03*
X291771Y1457835D03*
X283110Y1468859D03*
X291771Y1473189D03*
X283110Y1484213D03*
X291771Y1488544D03*
X283110Y1499567D03*
X291771Y1503898D03*
X283110Y1514922D03*
X291771Y1519252D03*
X283110Y1555867D03*
X291771Y1560197D03*
X283110Y1571221D03*
X291771Y1575552D03*
X283110Y1586575D03*
X291771Y1590906D03*
X283110Y1601930D03*
X291771Y1606260D03*
X283110Y1617284D03*
X291771Y1621615D03*
X300433Y1453504D03*
X309094Y1457835D03*
X300433Y1468859D03*
X309094Y1473189D03*
X300433Y1484213D03*
X309094Y1488544D03*
X300433Y1499567D03*
X309094Y1503898D03*
X300433Y1514922D03*
X309094Y1519252D03*
X300433Y1555867D03*
X309094Y1560197D03*
X300433Y1571221D03*
X309094Y1575552D03*
X300433Y1586575D03*
X309094Y1590906D03*
X300433Y1601930D03*
X309094Y1606260D03*
X300433Y1617284D03*
X309094Y1621615D03*
X317756Y1453504D03*
X326417Y1457835D03*
X317756Y1468859D03*
X326417Y1473189D03*
X317756Y1484213D03*
X326417Y1488544D03*
X317756Y1499567D03*
X326417Y1503898D03*
X317756Y1514922D03*
X326417Y1519252D03*
X317756Y1555867D03*
X326417Y1560197D03*
X317756Y1571221D03*
X326417Y1575552D03*
X317756Y1586575D03*
X326417Y1590906D03*
X317756Y1601930D03*
X326417Y1606260D03*
X317756Y1617284D03*
X326417Y1621615D03*
X335078Y1453504D03*
X343740Y1457835D03*
X335078Y1468859D03*
X343740Y1473189D03*
X335078Y1484213D03*
X343740Y1488544D03*
X335078Y1499567D03*
X343740Y1503898D03*
X335078Y1514922D03*
X343740Y1519252D03*
X335078Y1555867D03*
X343740Y1560197D03*
X335078Y1571221D03*
X343740Y1575552D03*
X335078Y1586575D03*
X343740Y1590906D03*
X335078Y1601930D03*
X343740Y1606260D03*
X335078Y1617284D03*
X343740Y1621615D03*
X352401Y1453504D03*
X361063Y1457835D03*
X352401Y1468859D03*
X361063Y1473189D03*
X352401Y1484213D03*
X361063Y1488544D03*
X352401Y1499567D03*
X361063Y1503898D03*
X352401Y1514922D03*
X361063Y1519252D03*
X352401Y1555867D03*
X361063Y1560197D03*
X352401Y1571221D03*
X361063Y1575552D03*
X352401Y1586575D03*
X361063Y1590906D03*
X352401Y1601930D03*
X361063Y1606260D03*
X352401Y1617284D03*
X361063Y1621615D03*
X456339Y1453504D03*
Y1468859D03*
Y1484213D03*
Y1499567D03*
Y1514922D03*
Y1555867D03*
Y1571221D03*
Y1586575D03*
Y1601930D03*
Y1617284D03*
X473662Y1453504D03*
X465000Y1457835D03*
X473662Y1468859D03*
X465000Y1473189D03*
X473662Y1484213D03*
X465000Y1488544D03*
X473662Y1499567D03*
Y1514922D03*
X465000Y1503898D03*
Y1519252D03*
X473662Y1555867D03*
X465000Y1560197D03*
X473662Y1571221D03*
X465000Y1575552D03*
X473662Y1586575D03*
X465000Y1590906D03*
X473662Y1601930D03*
X465000Y1606260D03*
X473662Y1617284D03*
X465000Y1621615D03*
X490985Y1453504D03*
X482323Y1457835D03*
X490985Y1468859D03*
X482323Y1473189D03*
X490985Y1484213D03*
X482323Y1488544D03*
X490985Y1499567D03*
Y1514922D03*
X482323Y1503898D03*
Y1519252D03*
X490985Y1555867D03*
X482323Y1560197D03*
X490985Y1571221D03*
X482323Y1575552D03*
X490985Y1586575D03*
X482323Y1590906D03*
X490985Y1601930D03*
X482323Y1606260D03*
X490985Y1617284D03*
X482323Y1621615D03*
X508307Y1453504D03*
X499646Y1457835D03*
X508307Y1468859D03*
X499646Y1473189D03*
X508307Y1484213D03*
X499646Y1488544D03*
X508307Y1499567D03*
Y1514922D03*
X499646Y1503898D03*
Y1519252D03*
X508307Y1555867D03*
X499646Y1560197D03*
X508307Y1571221D03*
X499646Y1575552D03*
X508307Y1586575D03*
X499646Y1590906D03*
X508307Y1601930D03*
X499646Y1606260D03*
X508307Y1617284D03*
X499646Y1621615D03*
X516969Y1457835D03*
Y1473189D03*
Y1488544D03*
Y1503898D03*
Y1519252D03*
Y1560197D03*
Y1575552D03*
Y1590906D03*
Y1606260D03*
Y1621615D03*
X525630Y1453504D03*
X534292Y1457835D03*
X525630Y1468859D03*
X534292Y1473189D03*
X525630Y1484213D03*
X534292Y1488544D03*
X525630Y1499567D03*
X534292Y1503898D03*
X525630Y1514922D03*
X534292Y1519252D03*
X525630Y1555867D03*
X534292Y1560197D03*
X525630Y1571221D03*
X534292Y1575552D03*
X525630Y1586575D03*
X534292Y1590906D03*
X525630Y1601930D03*
X534292Y1606260D03*
X525630Y1617284D03*
X534292Y1621615D03*
X629567Y1453504D03*
X638228Y1457835D03*
X629567Y1468859D03*
X638228Y1473189D03*
X629567Y1484213D03*
X638228Y1488544D03*
X629567Y1499567D03*
X638228Y1503898D03*
X629567Y1514922D03*
X638228Y1519252D03*
X629567Y1555867D03*
X638228Y1560197D03*
X629567Y1571221D03*
X638228Y1575552D03*
X629567Y1586575D03*
X638228Y1590906D03*
X629567Y1601930D03*
X638228Y1606260D03*
X629567Y1617284D03*
X638228Y1621615D03*
X646890Y1453504D03*
Y1468859D03*
Y1484213D03*
Y1499567D03*
Y1514922D03*
Y1555867D03*
Y1571221D03*
Y1586575D03*
Y1601930D03*
Y1617284D03*
X664213Y1453504D03*
X655551Y1457835D03*
X664213Y1468859D03*
X655551Y1473189D03*
X664213Y1484213D03*
X655551Y1488544D03*
X664213Y1499567D03*
Y1514922D03*
X655551Y1503898D03*
Y1519252D03*
X664213Y1555867D03*
X655551Y1560197D03*
X664213Y1571221D03*
X655551Y1575552D03*
X664213Y1586575D03*
X655551Y1590906D03*
X664213Y1601930D03*
X655551Y1606260D03*
X664213Y1617284D03*
X655551Y1621615D03*
X681535Y1453504D03*
X672874Y1457835D03*
X681535Y1468859D03*
X672874Y1473189D03*
X681535Y1484213D03*
X672874Y1488544D03*
X681535Y1499567D03*
Y1514922D03*
X672874Y1503898D03*
Y1519252D03*
X681535Y1555867D03*
X672874Y1560197D03*
X681535Y1571221D03*
X672874Y1575552D03*
X681535Y1586575D03*
X672874Y1590906D03*
X681535Y1601930D03*
X672874Y1606260D03*
X681535Y1617284D03*
X672874Y1621615D03*
X698858Y1453504D03*
X690197Y1457835D03*
X698858Y1468859D03*
X690197Y1473189D03*
X698858Y1484213D03*
X690197Y1488544D03*
X698858Y1499567D03*
Y1514922D03*
X690197Y1503898D03*
Y1519252D03*
X698858Y1555867D03*
X690197Y1560197D03*
X698858Y1571221D03*
X690197Y1575552D03*
X698858Y1586575D03*
X690197Y1590906D03*
X698858Y1601930D03*
X690197Y1606260D03*
X698858Y1617284D03*
X690197Y1621615D03*
X707520Y1457835D03*
Y1473189D03*
Y1488544D03*
Y1503898D03*
Y1519252D03*
Y1560197D03*
Y1575552D03*
Y1590906D03*
Y1606260D03*
Y1621615D03*
X1131850Y1453504D03*
X1140511Y1457835D03*
X1131850Y1468859D03*
X1140511Y1473189D03*
X1131850Y1484213D03*
X1140511Y1488544D03*
X1131850Y1499567D03*
X1140511Y1503898D03*
X1131850Y1514922D03*
X1140511Y1519252D03*
X1131850Y1555867D03*
X1140511Y1560197D03*
X1131850Y1571221D03*
X1140511Y1575552D03*
X1131850Y1586575D03*
X1140511Y1590906D03*
X1131850Y1601930D03*
X1140511Y1606260D03*
X1131850Y1617284D03*
X1140511Y1621615D03*
X1149173Y1453504D03*
X1157834Y1457835D03*
X1149173Y1468859D03*
X1157834Y1473189D03*
X1149173Y1484213D03*
X1157834Y1488544D03*
X1149173Y1499567D03*
X1157834Y1503898D03*
X1149173Y1514922D03*
X1157834Y1519252D03*
X1149173Y1555867D03*
X1157834Y1560197D03*
X1149173Y1571221D03*
X1157834Y1575552D03*
X1149173Y1586575D03*
X1157834Y1590906D03*
X1149173Y1601930D03*
X1157834Y1606260D03*
X1149173Y1617284D03*
X1157834Y1621615D03*
X1166496Y1453504D03*
Y1468859D03*
Y1484213D03*
Y1499567D03*
Y1514922D03*
Y1555867D03*
Y1571221D03*
Y1586575D03*
Y1601930D03*
Y1617284D03*
X1183818Y1453504D03*
X1175157Y1457835D03*
X1183818Y1468859D03*
X1175157Y1473189D03*
X1183818Y1484213D03*
X1175157Y1488544D03*
X1183818Y1499567D03*
Y1514922D03*
X1175157Y1503898D03*
Y1519252D03*
X1183818Y1555867D03*
X1175157Y1560197D03*
X1183818Y1571221D03*
X1175157Y1575552D03*
X1183818Y1586575D03*
X1175157Y1590906D03*
X1183818Y1601930D03*
X1175157Y1606260D03*
X1183818Y1617284D03*
X1175157Y1621615D03*
X1201141Y1453504D03*
X1192480Y1457835D03*
X1201141Y1468859D03*
X1192480Y1473189D03*
X1201141Y1484213D03*
X1192480Y1488544D03*
X1201141Y1499567D03*
Y1514922D03*
X1192480Y1503898D03*
Y1519252D03*
X1201141Y1555867D03*
X1192480Y1560197D03*
X1201141Y1571221D03*
X1192480Y1575552D03*
X1201141Y1586575D03*
X1192480Y1590906D03*
X1201141Y1601930D03*
X1192480Y1606260D03*
X1201141Y1617284D03*
X1192480Y1621615D03*
X1209803Y1457835D03*
Y1473189D03*
Y1488544D03*
Y1503898D03*
Y1519252D03*
Y1560197D03*
Y1575552D03*
Y1590906D03*
Y1606260D03*
Y1621615D03*
X1305079Y1453504D03*
X1313740Y1457835D03*
X1305079Y1468859D03*
X1313740Y1473189D03*
X1305079Y1484213D03*
X1313740Y1488544D03*
X1305079Y1499567D03*
X1313740Y1503898D03*
X1305079Y1514922D03*
X1313740Y1519252D03*
X1305079Y1555867D03*
X1313740Y1560197D03*
X1305079Y1571221D03*
X1313740Y1575552D03*
X1305079Y1586575D03*
X1313740Y1590906D03*
X1305079Y1601930D03*
X1313740Y1606260D03*
X1305079Y1617284D03*
X1313740Y1621615D03*
X1322402Y1453504D03*
X1331063Y1457835D03*
X1322402Y1468859D03*
X1331063Y1473189D03*
X1322402Y1484213D03*
X1331063Y1488544D03*
X1322402Y1499567D03*
X1331063Y1503898D03*
X1322402Y1514922D03*
X1331063Y1519252D03*
X1322402Y1555867D03*
X1331063Y1560197D03*
X1322402Y1571221D03*
X1331063Y1575552D03*
X1322402Y1586575D03*
X1331063Y1590906D03*
X1322402Y1601930D03*
X1331063Y1606260D03*
X1322402Y1617284D03*
X1331063Y1621615D03*
X1339725Y1453504D03*
X1348386Y1457835D03*
X1339725Y1468859D03*
X1348386Y1473189D03*
X1339725Y1484213D03*
X1348386Y1488544D03*
X1339725Y1499567D03*
X1348386Y1503898D03*
X1339725Y1514922D03*
X1348386Y1519252D03*
X1339725Y1555867D03*
X1348386Y1560197D03*
X1339725Y1571221D03*
X1348386Y1575552D03*
X1339725Y1586575D03*
X1348386Y1590906D03*
X1339725Y1601930D03*
X1348386Y1606260D03*
X1339725Y1617284D03*
X1348386Y1621615D03*
X1357047Y1453504D03*
X1365709Y1457835D03*
X1357047Y1468859D03*
X1365709Y1473189D03*
X1357047Y1484213D03*
X1365709Y1488544D03*
X1357047Y1499567D03*
X1365709Y1503898D03*
X1357047Y1514922D03*
X1365709Y1519252D03*
X1357047Y1555867D03*
X1365709Y1560197D03*
X1357047Y1571221D03*
X1365709Y1575552D03*
X1357047Y1586575D03*
X1365709Y1590906D03*
X1357047Y1601930D03*
X1365709Y1606260D03*
X1357047Y1617284D03*
X1365709Y1621615D03*
X1374370Y1453504D03*
X1383032Y1457835D03*
X1374370Y1468859D03*
X1383032Y1473189D03*
X1374370Y1484213D03*
X1383032Y1488544D03*
X1374370Y1499567D03*
X1383032Y1503898D03*
X1374370Y1514922D03*
X1383032Y1519252D03*
X1374370Y1555867D03*
X1383032Y1560197D03*
X1374370Y1571221D03*
X1383032Y1575552D03*
X1374370Y1586575D03*
X1383032Y1590906D03*
X1374370Y1601930D03*
X1383032Y1606260D03*
X1374370Y1617284D03*
X1383032Y1621615D03*
X1478307Y1453504D03*
Y1468859D03*
Y1484213D03*
Y1499567D03*
Y1514922D03*
Y1555867D03*
Y1571221D03*
Y1586575D03*
Y1601930D03*
Y1617284D03*
X1495630Y1453504D03*
X1486968Y1457835D03*
X1495630Y1468859D03*
X1486968Y1473189D03*
X1495630Y1484213D03*
X1486968Y1488544D03*
X1495630Y1499567D03*
Y1514922D03*
X1486968Y1503898D03*
Y1519252D03*
X1495630Y1555867D03*
X1486968Y1560197D03*
X1495630Y1571221D03*
X1486968Y1575552D03*
X1495630Y1586575D03*
X1486968Y1590906D03*
X1495630Y1601930D03*
X1486968Y1606260D03*
X1495630Y1617284D03*
X1486968Y1621615D03*
X1512953Y1453504D03*
X1504291Y1457835D03*
X1512953Y1468859D03*
X1504291Y1473189D03*
X1512953Y1484213D03*
X1504291Y1488544D03*
X1512953Y1499567D03*
Y1514922D03*
X1504291Y1503898D03*
Y1519252D03*
X1512953Y1555867D03*
X1504291Y1560197D03*
X1512953Y1571221D03*
X1504291Y1575552D03*
X1512953Y1586575D03*
X1504291Y1590906D03*
X1512953Y1601930D03*
X1504291Y1606260D03*
X1512953Y1617284D03*
X1504291Y1621615D03*
X1530275Y1453504D03*
X1521614Y1457835D03*
X1530275Y1468859D03*
X1521614Y1473189D03*
X1530275Y1484213D03*
X1521614Y1488544D03*
X1530275Y1499567D03*
Y1514922D03*
X1521614Y1503898D03*
Y1519252D03*
X1530275Y1555867D03*
X1521614Y1560197D03*
X1530275Y1571221D03*
X1521614Y1575552D03*
X1530275Y1586575D03*
X1521614Y1590906D03*
X1530275Y1601930D03*
X1521614Y1606260D03*
X1530275Y1617284D03*
X1521614Y1621615D03*
X1547598Y1453504D03*
X1538937Y1457835D03*
X1547598Y1468859D03*
X1538937Y1473189D03*
X1547598Y1484213D03*
X1538937Y1488544D03*
X1547598Y1499567D03*
Y1514922D03*
X1538937Y1503898D03*
Y1519252D03*
X1547598Y1555867D03*
X1538937Y1560197D03*
X1547598Y1571221D03*
X1538937Y1575552D03*
X1547598Y1586575D03*
X1538937Y1590906D03*
X1547598Y1601930D03*
X1538937Y1606260D03*
X1547598Y1617284D03*
X1538937Y1621615D03*
X1556260Y1457835D03*
Y1473189D03*
Y1488544D03*
Y1503898D03*
Y1519252D03*
Y1560197D03*
Y1575552D03*
Y1590906D03*
Y1606260D03*
Y1621615D03*
X1651535Y1453504D03*
X1660196Y1457835D03*
X1651535Y1468859D03*
X1660196Y1473189D03*
X1651535Y1484213D03*
X1660196Y1488544D03*
X1651535Y1499567D03*
X1660196Y1503898D03*
X1651535Y1514922D03*
X1660196Y1519252D03*
X1651535Y1555867D03*
X1660196Y1560197D03*
X1651535Y1571221D03*
X1660196Y1575552D03*
X1651535Y1586575D03*
X1660196Y1590906D03*
X1651535Y1601930D03*
X1660196Y1606260D03*
X1651535Y1617284D03*
X1660196Y1621615D03*
X1668858Y1453504D03*
X1677519Y1457835D03*
X1668858Y1468859D03*
X1677519Y1473189D03*
X1668858Y1484213D03*
X1677519Y1488544D03*
X1668858Y1499567D03*
X1677519Y1503898D03*
X1668858Y1514922D03*
X1677519Y1519252D03*
X1668858Y1555867D03*
X1677519Y1560197D03*
X1668858Y1571221D03*
X1677519Y1575552D03*
X1668858Y1586575D03*
X1677519Y1590906D03*
X1668858Y1601930D03*
X1677519Y1606260D03*
X1668858Y1617284D03*
X1677519Y1621615D03*
X1686181Y1453504D03*
Y1468859D03*
Y1484213D03*
Y1499567D03*
Y1514922D03*
Y1555867D03*
Y1571221D03*
Y1586575D03*
Y1601930D03*
Y1617284D03*
X1703503Y1453504D03*
X1694842Y1457835D03*
X1703503Y1468859D03*
X1694842Y1473189D03*
X1703503Y1484213D03*
X1694842Y1488544D03*
X1703503Y1499567D03*
Y1514922D03*
X1694842Y1503898D03*
Y1519252D03*
X1703503Y1555867D03*
X1694842Y1560197D03*
X1703503Y1571221D03*
X1694842Y1575552D03*
X1703503Y1586575D03*
X1694842Y1590906D03*
X1703503Y1601930D03*
X1694842Y1606260D03*
X1703503Y1617284D03*
X1694842Y1621615D03*
X1720826Y1453504D03*
X1712165Y1457835D03*
X1720826Y1468859D03*
X1712165Y1473189D03*
X1720826Y1484213D03*
X1712165Y1488544D03*
X1720826Y1499567D03*
Y1514922D03*
X1712165Y1503898D03*
Y1519252D03*
X1720826Y1555867D03*
X1712165Y1560197D03*
X1720826Y1571221D03*
X1712165Y1575552D03*
X1720826Y1586575D03*
X1712165Y1590906D03*
X1720826Y1601930D03*
X1712165Y1606260D03*
X1720826Y1617284D03*
X1712165Y1621615D03*
X1729488Y1457835D03*
Y1473189D03*
Y1488544D03*
Y1503898D03*
Y1519252D03*
Y1560197D03*
Y1575552D03*
Y1590906D03*
Y1606260D03*
Y1621615D03*
G54D40*
X235433Y1606142D03*
X581890D03*
X1259055D03*
X1605512D03*
G54D16*
X15139Y198883D03*
Y201683D03*
X18564Y238589D03*
X6690Y1496782D03*
X34520Y213539D03*
X36201Y238714D03*
X21530Y236121D03*
X27966Y238689D03*
X27625Y663094D03*
X25818Y682139D03*
X28818D03*
X32079Y1517641D03*
X65189Y228961D03*
Y231461D03*
Y223661D03*
Y226461D03*
X54733Y231226D03*
Y228726D03*
Y223726D03*
Y226226D03*
X67622Y572842D03*
X64408Y572975D03*
X73110Y101701D03*
X78501Y110445D03*
Y115401D03*
Y129574D03*
Y124618D03*
X73158Y229286D03*
X76851Y222212D03*
Y224712D03*
X73158Y231786D03*
X75777Y585507D03*
X71184D03*
X71730Y579475D03*
X71228Y590145D03*
X75822Y590190D03*
X75684Y605443D03*
X83684D03*
X78129Y656900D03*
X72314Y680207D03*
Y683407D03*
X82714Y674707D03*
X71928Y873683D03*
X88903Y117557D03*
Y122513D03*
Y131731D03*
Y136687D03*
X94390Y293645D03*
Y290845D03*
Y288345D03*
X91890Y293645D03*
Y290845D03*
Y288345D03*
X93456Y649838D03*
X89432Y668293D03*
X92134D03*
X85614Y674707D03*
X87714Y684607D03*
X117501Y198883D03*
Y201683D03*
X111275Y1008262D03*
Y1011762D03*
X130328Y238689D03*
X123892Y236121D03*
X120926Y238589D03*
X136882Y213539D03*
X138563Y238714D03*
X143186Y402291D03*
Y397335D03*
X140786Y416465D03*
Y411509D03*
Y425682D03*
Y430638D03*
Y439855D03*
Y444811D03*
Y468609D03*
Y473565D03*
Y487738D03*
Y482782D03*
Y512743D03*
Y517699D03*
Y531872D03*
Y526916D03*
X157095Y228726D03*
Y231226D03*
X167551Y223661D03*
X157095Y226226D03*
Y223726D03*
X151188Y390223D03*
Y395179D03*
Y404396D03*
Y409352D03*
Y423525D03*
Y418569D03*
Y432743D03*
Y437699D03*
Y489895D03*
Y480677D03*
Y475721D03*
Y494851D03*
Y519855D03*
Y538984D03*
Y534028D03*
Y524811D03*
X175472Y101701D03*
X175520Y229286D03*
X179213Y224712D03*
Y222212D03*
X167551Y231461D03*
Y228961D03*
Y226461D03*
X175520Y231786D03*
X194189Y103621D03*
X196752Y293645D03*
Y290845D03*
Y288345D03*
X194252Y293645D03*
Y290845D03*
Y288345D03*
X203740Y567914D03*
Y565414D03*
Y570414D03*
Y575414D03*
Y572914D03*
X219863Y198883D03*
Y201683D03*
X226254Y236121D03*
X223288Y238589D03*
X239244Y213539D03*
X232690Y238689D03*
X240925Y238714D03*
X259457Y228726D03*
Y231226D03*
Y226226D03*
Y223726D03*
X251802Y824128D03*
X277834Y101701D03*
X269913Y228961D03*
Y226461D03*
Y223661D03*
X277882Y229286D03*
X269913Y231461D03*
X277882Y231786D03*
X286129Y36971D03*
X296551Y103621D03*
X281575Y224712D03*
Y222212D03*
X296614Y293645D03*
Y290845D03*
Y288345D03*
X309106Y37543D03*
X299114Y290845D03*
Y288345D03*
Y293645D03*
X302966Y324139D03*
X310013Y316731D03*
X301158Y380307D03*
X301308Y395346D03*
X301393Y400039D03*
X322225Y198883D03*
Y201683D03*
X325650Y238589D03*
X328616Y236121D03*
X321549Y445315D03*
Y448115D03*
X323489Y471484D03*
Y466528D03*
Y480701D03*
Y485657D03*
Y515617D03*
Y510661D03*
Y529791D03*
Y524835D03*
Y565657D03*
Y560701D03*
Y574874D03*
Y579830D03*
Y589047D03*
Y594003D03*
Y603221D03*
Y608177D03*
X330905Y11806D03*
Y23806D03*
Y31806D03*
X341606Y213539D03*
X335052Y238689D03*
X343287Y238714D03*
X345050Y458334D03*
X333891Y473640D03*
Y487813D03*
Y478596D03*
Y492769D03*
Y522730D03*
Y517774D03*
Y531947D03*
Y536903D03*
Y572769D03*
Y567813D03*
Y586943D03*
Y581987D03*
Y596160D03*
Y601116D03*
Y610333D03*
Y615289D03*
X347450Y447486D03*
X353670Y488618D03*
Y491118D03*
Y493618D03*
Y496118D03*
X372275Y226461D03*
X361819Y231226D03*
Y228726D03*
Y223726D03*
Y226226D03*
X372275Y228961D03*
Y231461D03*
Y223661D03*
X364954Y450091D03*
X367564Y452740D03*
X365332Y490070D03*
Y487570D03*
X361887Y493758D03*
Y496258D03*
X377020Y782535D03*
X368491Y815092D03*
X368273Y928100D03*
X380196Y101701D03*
X380244Y229286D03*
X383937Y222212D03*
Y224712D03*
X380244Y231786D03*
X393837Y466409D03*
X393823Y487382D03*
X398913Y103621D03*
X398976Y293645D03*
X401476D03*
Y288345D03*
Y290845D03*
X398976Y288345D03*
Y290845D03*
X406843Y399161D03*
Y401661D03*
Y396661D03*
X405603Y668060D03*
X408103D03*
X403103D03*
X400603D03*
Y678060D03*
X405603D03*
X408103D03*
X403103D03*
X406967Y878764D03*
X406415Y874840D03*
X399285Y1081599D03*
X398915Y1097278D03*
X396415D03*
X401711Y1419771D03*
X406667D03*
X400911Y1537902D03*
X407048D03*
X400911Y1544424D03*
X407048Y1549936D03*
X400911D03*
X420050Y33425D03*
X418876Y401661D03*
Y396661D03*
Y399161D03*
X411754Y474513D03*
X424731Y508152D03*
Y513452D03*
Y515952D03*
X414275Y508217D03*
Y510717D03*
Y515717D03*
Y513217D03*
X424731Y510952D03*
X410603Y668060D03*
Y678060D03*
X425759Y869921D03*
Y872721D03*
Y875521D03*
Y867121D03*
Y878321D03*
X411214Y892109D03*
X413012Y1537902D03*
Y1544098D03*
X426196Y1534087D03*
X413012Y1549936D03*
X421616Y1549885D03*
X442704Y506427D03*
X427693Y506520D03*
X438353Y508685D03*
X427693Y509020D03*
X432700Y516277D03*
X429210Y784833D03*
X428759Y869921D03*
Y867121D03*
Y872721D03*
Y875521D03*
Y878321D03*
X432332Y892049D03*
Y897649D03*
Y894849D03*
Y900449D03*
X453544Y461961D03*
X451144Y472809D03*
X447836Y711199D03*
X451889Y1301067D03*
X456832Y1299121D03*
X451889Y1306023D03*
X472226Y198883D03*
Y201683D03*
X473658Y467215D03*
X471048Y464566D03*
X469495Y1011303D03*
Y1023303D03*
Y1017303D03*
X491607Y213539D03*
X478617Y236121D03*
X475651Y238589D03*
X485053Y238689D03*
X481495Y1011303D03*
X475495D03*
X481495Y1023303D03*
Y1017303D03*
X475495Y1023303D03*
X484800Y1302000D03*
X493288Y238714D03*
X522276Y223661D03*
Y226461D03*
Y228961D03*
Y231461D03*
X511820Y231226D03*
Y228726D03*
Y223726D03*
Y226226D03*
X521494Y572975D03*
X524475Y952290D03*
X509471Y981608D03*
X517374Y1287222D03*
X514363Y1287370D03*
X520548Y1287181D03*
X530197Y101701D03*
X530245Y229286D03*
X533938Y222212D03*
Y224712D03*
X530245Y231786D03*
X524708Y572842D03*
X532863Y585507D03*
X528270D03*
X528816Y579475D03*
X532908Y590190D03*
X528314Y590145D03*
X532770Y605443D03*
X528868Y873683D03*
X548914Y103621D03*
X551477Y288345D03*
Y290845D03*
X548977Y288345D03*
Y290845D03*
Y293645D03*
X551477D03*
X540770Y605443D03*
X574588Y201683D03*
X568362Y1008262D03*
Y1011762D03*
X574588Y198883D03*
X587415Y238689D03*
X580979Y236121D03*
X578013Y238589D03*
X577249Y965445D03*
X593969Y213539D03*
X595650Y238714D03*
X600272Y397335D03*
Y402291D03*
X597872Y425682D03*
Y416465D03*
Y411509D03*
Y439855D03*
Y430638D03*
Y444811D03*
Y468609D03*
Y473565D03*
Y487738D03*
Y482782D03*
Y517699D03*
Y531872D03*
Y526916D03*
X606142Y965665D03*
X614182Y223726D03*
Y226226D03*
Y231226D03*
Y228726D03*
X608274Y390223D03*
Y395179D03*
Y404396D03*
Y409352D03*
Y418569D03*
Y423525D03*
Y432743D03*
Y437699D03*
Y489895D03*
Y480677D03*
Y475721D03*
Y494851D03*
Y519855D03*
Y538984D03*
Y534028D03*
Y524811D03*
X632559Y101701D03*
X624638Y231461D03*
X636300Y222212D03*
Y224712D03*
X632607Y229286D03*
X624638Y223661D03*
Y226461D03*
Y228961D03*
X632607Y231786D03*
X651276Y103621D03*
X651339Y290845D03*
Y293645D03*
X653839D03*
Y288345D03*
Y290845D03*
X651339Y288345D03*
X660826Y570414D03*
Y567914D03*
Y565414D03*
Y575414D03*
Y572914D03*
X676950Y201683D03*
X680375Y238589D03*
X683341Y236121D03*
X696331Y213539D03*
X698012Y238714D03*
X689777Y238689D03*
X716544Y228726D03*
Y231226D03*
Y226226D03*
Y223726D03*
X704446Y760611D03*
X713425Y786029D03*
X734921Y101701D03*
X727000Y228961D03*
Y226461D03*
Y223661D03*
X734969Y229286D03*
X727000Y231461D03*
X734969Y231786D03*
X721218Y742131D03*
X720271Y782481D03*
X738662Y224712D03*
Y222212D03*
X744069Y746617D03*
X735576Y861780D03*
X753638Y103621D03*
X760407Y324494D03*
X767099Y316731D03*
X767310Y1599164D03*
X756358Y1616917D03*
X779312Y198883D03*
Y201683D03*
X782737Y238589D03*
X780575Y471484D03*
Y466528D03*
Y480701D03*
Y485657D03*
Y510661D03*
Y515617D03*
Y524835D03*
Y529791D03*
Y560701D03*
Y565657D03*
Y579830D03*
Y574874D03*
Y589047D03*
Y594003D03*
Y603221D03*
Y608177D03*
X798693Y213539D03*
X792139Y238689D03*
X785703Y236121D03*
X790977Y473640D03*
Y487813D03*
Y478596D03*
Y492769D03*
Y517774D03*
Y522730D03*
Y531947D03*
Y536903D03*
Y567813D03*
Y572769D03*
Y581987D03*
Y586943D03*
Y601116D03*
Y596160D03*
Y615289D03*
Y610333D03*
X800374Y238714D03*
X804536Y441486D03*
X802136Y452334D03*
X810756Y491118D03*
Y488618D03*
Y483618D03*
Y486118D03*
X815492Y732917D03*
X829362Y231461D03*
Y228961D03*
Y226461D03*
Y223661D03*
X818906Y228726D03*
Y231226D03*
Y226226D03*
Y223726D03*
X829381Y348036D03*
X824650Y446740D03*
X822040Y444091D03*
X826262Y462326D03*
Y459326D03*
X818973Y491258D03*
Y488758D03*
X822418Y485070D03*
Y482570D03*
X823790Y713375D03*
X823843Y732109D03*
X819890Y736924D03*
X828423Y964731D03*
X837283Y101701D03*
X837331Y229286D03*
X841024Y224712D03*
Y222212D03*
X837331Y231786D03*
X839573Y325327D03*
X856000Y103621D03*
X858563Y293645D03*
Y290845D03*
X856063Y293645D03*
Y290845D03*
X858563Y288345D03*
X856063D03*
X854622Y359004D03*
X873885Y340892D03*
X873733Y357844D03*
X871382Y373971D03*
X875907Y486256D03*
X870137Y669461D03*
X875916Y808965D03*
X886026Y346584D03*
X896592Y362369D03*
Y366369D03*
Y370369D03*
X882907Y480350D03*
X892023Y570176D03*
X890959Y579788D03*
X890956Y588325D03*
X894015Y588253D03*
X895933Y618143D03*
X910076Y304843D03*
X905120D03*
X913206Y336489D03*
X910040Y353532D03*
X902169Y413002D03*
Y418002D03*
Y415502D03*
X913853Y561487D03*
X904393Y570176D03*
X908517D03*
X898815D03*
X898232Y588320D03*
X902635Y588305D03*
X906999Y588274D03*
X905313Y709259D03*
X905050Y720268D03*
X913716Y800815D03*
X899916D03*
X911053Y800510D03*
X901428Y1136426D03*
X904897Y1145169D03*
X902397D03*
X929978Y186854D03*
Y184054D03*
X917906Y321670D03*
X922629Y336609D03*
X922198Y342051D03*
X917858Y331453D03*
X927309Y357267D03*
X921389D03*
X915395D03*
Y363212D03*
X927309Y363239D03*
Y369210D03*
X921468D03*
X915395D03*
X927072Y386992D03*
X919072D03*
X923072D03*
X914202Y418002D03*
Y413002D03*
Y415502D03*
X916590Y800636D03*
X921790Y810965D03*
X926044Y1545370D03*
Y1542370D03*
X938125Y230891D03*
X942805Y223860D03*
X936369Y221292D03*
X940158Y245707D03*
X946064Y252998D03*
X941845Y278968D03*
X939606Y310521D03*
X939653Y317474D03*
X940924Y328959D03*
X936608Y326058D03*
X945120Y326441D03*
X930398Y342050D03*
X936453Y345336D03*
X945599Y345383D03*
X940972Y338238D03*
X943663Y355674D03*
X944900Y363700D03*
X938499Y362202D03*
X940600Y370600D03*
X939314Y707847D03*
X931244Y720471D03*
X936026Y730600D03*
X941916Y808965D03*
X949359Y198710D03*
X951040Y223885D03*
X956348Y356371D03*
X952170Y356131D03*
X958823Y362802D03*
X954888Y369513D03*
X948400Y370045D03*
X956035Y1545333D03*
X959035D03*
X953035D03*
X950035D03*
X959035Y1542333D03*
X956035D03*
X953035D03*
X950035D03*
X968906Y223726D03*
Y228726D03*
Y231226D03*
X979362Y223661D03*
X968906Y226226D03*
X973338Y345018D03*
X978581Y572975D03*
X971144Y908972D03*
X965405Y1136426D03*
X987283Y101701D03*
X987331Y229286D03*
X991024Y224712D03*
Y222212D03*
X979362Y231461D03*
Y228961D03*
Y226461D03*
X987331Y231786D03*
X992045Y366559D03*
X984045D03*
X988045D03*
X981795Y572842D03*
X985903Y579475D03*
X985357Y585507D03*
X989950D03*
X985401Y590145D03*
X989995Y590190D03*
X989857Y605443D03*
X983712Y722064D03*
X1006000Y103621D03*
X1008563Y293645D03*
X1006063D03*
Y290845D03*
Y288345D03*
X1008563Y290845D03*
Y288345D03*
X997857Y605443D03*
X1010606Y1547824D03*
X1010659Y1568771D03*
Y1565771D03*
X1010653Y1571669D03*
X1021451Y322879D03*
X1026032Y322906D03*
X1018238Y678647D03*
X1018155Y684132D03*
X1025116Y698332D03*
X1024932Y717856D03*
X1016320Y828481D03*
X1026340Y917761D03*
X1025448Y1008262D03*
Y1011762D03*
X1013606Y1547824D03*
X1016606D03*
X1019606D03*
X1013659Y1568771D03*
X1016659D03*
X1019659D03*
X1013659Y1565771D03*
X1016659D03*
X1019659D03*
X1013653Y1571669D03*
X1016653D03*
X1019653D03*
X1031674Y198883D03*
Y201683D03*
X1038065Y236121D03*
X1035099Y238589D03*
X1030184Y288709D03*
X1038068Y298789D03*
X1033112D03*
X1030753Y732213D03*
X1051055Y213539D03*
X1044501Y238689D03*
X1052736Y238714D03*
X1048695Y280161D03*
X1057359Y402291D03*
Y397335D03*
X1054959Y411509D03*
Y425682D03*
Y416465D03*
Y430638D03*
Y439855D03*
Y444811D03*
Y468609D03*
Y473565D03*
Y487738D03*
Y482782D03*
Y517699D03*
Y512743D03*
Y531872D03*
Y526916D03*
X1071268Y226226D03*
Y223726D03*
Y228726D03*
Y231226D03*
X1065361Y390223D03*
Y395179D03*
Y404396D03*
Y409352D03*
Y423525D03*
Y418569D03*
Y432743D03*
Y437699D03*
Y489895D03*
Y480677D03*
Y475721D03*
Y494851D03*
Y519855D03*
Y524811D03*
Y538984D03*
Y534028D03*
X1089645Y101701D03*
X1081724Y226461D03*
Y223661D03*
X1089693Y229286D03*
X1081724Y231461D03*
Y228961D03*
X1089693Y231786D03*
X1079863Y345660D03*
X1090747Y1617415D03*
X1108362Y103621D03*
X1093386Y224712D03*
Y222212D03*
X1108425Y293645D03*
Y290845D03*
Y288345D03*
X1096264Y1562285D03*
X1093713Y1585583D03*
X1110925Y293645D03*
Y290845D03*
Y288345D03*
X1117913Y565414D03*
Y567914D03*
Y570414D03*
Y572914D03*
Y575414D03*
X1122718Y598857D03*
X1121191Y612555D03*
X1120512Y617332D03*
X1121022Y607750D03*
X1134036Y198883D03*
Y201683D03*
X1137461Y238589D03*
X1140427Y236121D03*
X1138166Y534759D03*
X1153417Y213539D03*
X1146863Y238689D03*
X1155098Y238714D03*
X1149437Y728541D03*
X1152316Y746625D03*
X1173630Y226226D03*
Y223726D03*
Y228726D03*
Y231226D03*
X1161274Y550462D03*
X1170603Y715281D03*
X1163751Y719498D03*
X1168577Y733812D03*
X1169266Y800799D03*
X1184086Y231461D03*
Y228961D03*
Y226461D03*
Y223661D03*
X1176577Y885974D03*
X1188431Y936568D03*
X1192007Y101701D03*
X1192055Y229286D03*
X1195748Y224712D03*
Y222212D03*
X1192055Y231786D03*
X1192990Y914873D03*
X1195118Y936296D03*
X1210724Y103621D03*
X1213287Y293645D03*
Y290845D03*
Y288345D03*
X1210787Y293645D03*
Y290845D03*
Y288345D03*
X1217139Y324139D03*
X1222909Y-83456D03*
Y-78500D03*
Y-68500D03*
Y-73456D03*
X1228265Y-44406D03*
Y-39450D03*
Y-29450D03*
Y-34406D03*
X1236398Y198883D03*
Y201683D03*
X1224186Y316731D03*
X1237662Y466528D03*
Y471484D03*
Y480701D03*
Y485657D03*
Y515617D03*
Y510661D03*
Y524835D03*
Y529791D03*
Y565657D03*
Y560701D03*
Y589047D03*
Y574874D03*
Y579830D03*
Y603221D03*
Y594003D03*
Y608177D03*
X1239823Y238589D03*
X1242789Y236121D03*
X1248064Y473640D03*
Y487813D03*
Y478596D03*
Y492769D03*
Y517774D03*
Y522730D03*
Y531947D03*
Y536903D03*
X1255779Y213539D03*
X1257460Y238714D03*
X1264481Y300223D03*
X1261623Y447486D03*
X1259223Y458334D03*
X1267843Y488618D03*
Y491118D03*
Y493618D03*
X1275992Y223726D03*
Y226226D03*
Y231226D03*
Y228726D03*
X1286448Y223661D03*
Y226461D03*
Y228961D03*
Y231461D03*
X1279127Y450091D03*
X1281737Y452740D03*
X1279505Y487570D03*
Y490070D03*
X1276060Y496258D03*
Y493758D03*
X1294369Y101701D03*
X1294417Y229286D03*
X1298110Y222212D03*
Y224712D03*
X1294417Y231786D03*
X1313086Y103621D03*
X1313149Y288345D03*
Y290845D03*
Y293645D03*
X1315649Y288345D03*
Y290845D03*
Y293645D03*
X1308010Y466409D03*
X1307996Y487382D03*
X1313459Y1081599D03*
X1310589Y1097278D03*
X1313089D03*
X1334223Y33425D03*
X1333049Y399268D03*
Y401768D03*
Y396768D03*
X1321016Y399161D03*
Y401661D03*
Y396661D03*
X1325927Y474513D03*
X1386399Y201683D03*
X1383669Y1011303D03*
Y1017303D03*
Y1023303D03*
X1386399Y198883D03*
X1399226Y238689D03*
X1392790Y236121D03*
X1389824Y238589D03*
X1395669Y1011303D03*
X1389669D03*
X1395669Y1017303D03*
Y1023303D03*
X1389669D03*
X1405780Y213539D03*
X1407461Y238714D03*
X1425993Y231226D03*
Y228726D03*
Y226226D03*
Y223726D03*
X1444370Y101701D03*
X1436449Y228961D03*
X1444418Y229286D03*
X1436449Y226461D03*
Y223661D03*
X1448111Y222212D03*
Y224712D03*
X1436449Y231461D03*
X1444418Y231786D03*
X1438882Y572842D03*
X1447037Y585507D03*
X1442444D03*
X1442990Y579475D03*
X1435668Y572975D03*
X1442488Y590145D03*
X1447082Y590190D03*
X1446944Y605443D03*
X1443041Y873683D03*
X1463087Y103621D03*
X1465650Y293645D03*
Y288345D03*
Y290845D03*
X1463150Y288345D03*
Y290845D03*
Y293645D03*
X1454944Y605443D03*
X1479409Y-83456D03*
Y-78500D03*
Y-68500D03*
Y-73456D03*
X1476822Y40780D03*
X1498621Y15043D03*
Y35043D03*
Y27043D03*
X1488761Y198883D03*
Y201683D03*
X1492186Y238589D03*
X1495152Y236121D03*
X1483813Y368516D03*
X1482535Y1008262D03*
Y1002453D03*
Y1011762D03*
X1514765Y-44536D03*
Y-39580D03*
Y-29580D03*
Y-34536D03*
X1508142Y213539D03*
X1509823Y238714D03*
X1501588Y238689D03*
X1514446Y402291D03*
Y397335D03*
X1512046Y411509D03*
Y425682D03*
Y416465D03*
Y439855D03*
Y430638D03*
Y444811D03*
Y468609D03*
Y473565D03*
Y487738D03*
Y482782D03*
Y517699D03*
Y512743D03*
Y531872D03*
Y526916D03*
X1528355Y228726D03*
Y223726D03*
Y226226D03*
Y231226D03*
X1515779Y351594D03*
X1522448Y390223D03*
Y395179D03*
Y404396D03*
Y409352D03*
Y423525D03*
Y418569D03*
Y437699D03*
Y432743D03*
Y489895D03*
Y480677D03*
Y475721D03*
Y494851D03*
Y519855D03*
Y538984D03*
Y534028D03*
Y524811D03*
X1546732Y101701D03*
X1538811Y226461D03*
Y228961D03*
Y231461D03*
X1546780Y229286D03*
X1538811Y223661D03*
X1546780Y231786D03*
X1550473Y222212D03*
Y224712D03*
X1565449Y103621D03*
X1565512Y288345D03*
X1568012Y293645D03*
Y290845D03*
Y288345D03*
X1565512Y293645D03*
Y290845D03*
X1575000Y565414D03*
Y567914D03*
Y570414D03*
Y572914D03*
Y575414D03*
X1579753Y599100D03*
X1578679Y613047D03*
X1578114Y607563D03*
X1591123Y198883D03*
Y201683D03*
X1594548Y238589D03*
X1610504Y213539D03*
X1597514Y236121D03*
X1612185Y238714D03*
X1603950Y238689D03*
X1641173Y231461D03*
X1630717Y223726D03*
Y226226D03*
Y231226D03*
Y228726D03*
X1641173Y223661D03*
Y226461D03*
Y228961D03*
X1649094Y101701D03*
X1649142Y229286D03*
X1652835Y222212D03*
Y224712D03*
X1649142Y231786D03*
X1667811Y103621D03*
X1670374Y290845D03*
Y288345D03*
X1667874Y290845D03*
Y288345D03*
X1670374Y293645D03*
X1667874D03*
X1674226Y324139D03*
X1693485Y198883D03*
Y201683D03*
X1681273Y316731D03*
X1699876Y236121D03*
X1696910Y238589D03*
X1706312Y238689D03*
X1694749Y466528D03*
Y471484D03*
X1705151Y473640D03*
Y487813D03*
Y478596D03*
X1694749Y480701D03*
Y485657D03*
X1705151Y492769D03*
Y517774D03*
Y522730D03*
X1694749Y510661D03*
Y515617D03*
X1705151Y536903D03*
Y531947D03*
X1694749Y524835D03*
Y529791D03*
X1705151Y572769D03*
Y567813D03*
X1694749Y565657D03*
Y560701D03*
Y579830D03*
X1705151Y586943D03*
Y581987D03*
X1694749Y589047D03*
Y574874D03*
Y603221D03*
X1705151Y601116D03*
Y596160D03*
X1694749Y594003D03*
X1705151Y615289D03*
X1694749Y608177D03*
X1705151Y610333D03*
X1712866Y213539D03*
X1714547Y238714D03*
X1718710Y447486D03*
X1716310Y458334D03*
X1724930Y491118D03*
Y488618D03*
Y493618D03*
Y496118D03*
X1733909Y-83456D03*
Y-78500D03*
Y-68500D03*
Y-73456D03*
X1733079Y223726D03*
Y226226D03*
Y231226D03*
Y228726D03*
X1743535Y223661D03*
X1738824Y452740D03*
X1736214Y450091D03*
X1736592Y487570D03*
Y490070D03*
X1733147Y493758D03*
Y496258D03*
X1751456Y101701D03*
X1743535Y226461D03*
X1755197Y224712D03*
X1743535Y228961D03*
Y231461D03*
X1751504Y229286D03*
X1755197Y222212D03*
X1751504Y231786D03*
X1770173Y103621D03*
X1772736Y293645D03*
X1770236D03*
Y290845D03*
Y288345D03*
X1772736Y290845D03*
Y288345D03*
X1765097Y466409D03*
X1765083Y487382D03*
X1772768Y818696D03*
X1790136Y399161D03*
Y401661D03*
Y396661D03*
X1778103Y399161D03*
Y401661D03*
Y396661D03*
X1783014Y474513D03*
X1778801Y836469D03*
X1786256Y927626D03*
X1784306Y924601D03*
X1786256Y930626D03*
X1799265Y-44666D03*
Y-39710D03*
Y-29710D03*
Y-34666D03*
X1791302Y829031D03*
X1816385Y1136912D03*
X1813885D03*
Y1144912D03*
X1816385D03*
G54D21*
X51043Y60709D03*
Y150197D03*
X153405Y60709D03*
Y150197D03*
X255767Y60709D03*
Y150197D03*
X279360Y368760D03*
Y421555D03*
Y501752D03*
Y550020D03*
Y636752D03*
X358129Y60709D03*
Y150197D03*
X508130Y60709D03*
Y150197D03*
X610492Y60709D03*
Y150197D03*
X712854Y60709D03*
Y150197D03*
X736446Y368760D03*
Y421555D03*
Y501752D03*
Y550020D03*
Y636752D03*
X815216Y60709D03*
Y150197D03*
X965216Y60709D03*
Y150197D03*
X1067578Y60709D03*
Y150197D03*
X1169940Y60709D03*
Y150197D03*
X1193533Y368760D03*
Y421555D03*
Y501752D03*
Y550020D03*
Y636752D03*
X1272302Y60709D03*
Y150197D03*
X1422303Y60709D03*
Y150197D03*
X1524665Y60709D03*
Y150197D03*
X1627027Y60709D03*
Y150197D03*
X1650620Y368760D03*
Y421555D03*
Y501752D03*
Y550020D03*
Y636752D03*
X1729389Y60709D03*
Y150197D03*
G54D49*
X843012Y1592787D03*
Y1602787D03*
Y1612787D03*
Y1622787D03*
X853012Y1592787D03*
Y1602787D03*
Y1612787D03*
Y1622787D03*
X878012Y1592787D03*
Y1602787D03*
Y1612787D03*
Y1622787D03*
X888012Y1592787D03*
Y1602787D03*
Y1612787D03*
Y1622787D03*
X913012Y1592787D03*
Y1602787D03*
Y1612787D03*
Y1622787D03*
X923012Y1592787D03*
Y1602787D03*
Y1612787D03*
Y1622787D03*
X948012Y1592787D03*
Y1602787D03*
Y1612787D03*
Y1622787D03*
X958012Y1592787D03*
Y1602787D03*
Y1612787D03*
Y1622787D03*
X983012Y1592787D03*
X993012D03*
X983012Y1602787D03*
Y1612787D03*
X993012Y1602787D03*
Y1612787D03*
X983012Y1622787D03*
X993012D03*
X1018012Y1592787D03*
X1028012D03*
X1018012Y1602787D03*
Y1612787D03*
X1028012Y1602787D03*
Y1612787D03*
X1018012Y1622787D03*
X1028012D03*
G54D12*
X3035Y1578036D03*
X3017Y1639466D03*
X14751Y62381D03*
X12601Y92110D03*
X9364Y107501D03*
X16728Y107910D03*
X12652Y116894D03*
X13615Y153263D03*
X10966Y155873D03*
Y152873D03*
X12709Y175777D03*
X9745Y245784D03*
X19075Y278429D03*
X7036Y268371D03*
X14252Y1121333D03*
X11552D03*
X16752D03*
X8952D03*
X14152Y1111633D03*
X11452D03*
X8852D03*
X16652D03*
X14252Y1130333D03*
X16752D03*
X14306Y1138705D03*
X16806D03*
X20079Y1429347D03*
X12327Y1519202D03*
X11995Y1535134D03*
X6567Y1554215D03*
X14375Y1553121D03*
X18409Y1554202D03*
X12000Y1644980D03*
X33288Y109410D03*
Y116497D03*
X30788D03*
X25988D03*
X22439Y106495D03*
X30788Y123584D03*
X33288Y123583D03*
X25988Y123584D03*
X33288Y130670D03*
X30788D03*
X25988D03*
X30788Y137757D03*
X25988D03*
X29201Y151651D03*
X26201D03*
X20709Y175777D03*
X28740Y247292D03*
X21449Y253198D03*
X28740Y267292D03*
X21386Y273198D03*
X23479Y295619D03*
X32452Y581222D03*
X29652D03*
X35252D03*
Y591215D03*
X29652D03*
X32452D03*
X34254Y611091D03*
X29451Y633560D03*
X30369Y663048D03*
X27854Y671553D03*
X30414Y671508D03*
X26596Y874520D03*
X26844Y920354D03*
X24132Y958151D03*
X25371Y980696D03*
X34314Y1215403D03*
X22284Y1464612D03*
X32079Y1525641D03*
X35237Y1532096D03*
X35850Y1556096D03*
X32000Y1644980D03*
X46450Y82984D03*
Y77784D03*
Y75184D03*
Y80384D03*
X48364Y92473D03*
X46450Y85584D03*
X37988Y109410D03*
Y102323D03*
Y116496D03*
Y130670D03*
Y123583D03*
X52437Y137756D03*
X37988D03*
X45984Y163264D03*
X37284Y285272D03*
X42690Y451466D03*
X48596Y458466D03*
X39643Y555194D03*
X36843D03*
X39643Y563194D03*
X36843D03*
X39643Y571194D03*
X36843D03*
X49265Y886660D03*
X52922Y900295D03*
X47916Y947622D03*
X50366Y1086981D03*
Y1082388D03*
X38200Y1089721D03*
X44365Y1086404D03*
X38216Y1093757D03*
X49500Y1199066D03*
X51197Y1218206D03*
X39452Y1250932D03*
X48195Y1511279D03*
X48079Y1525641D03*
Y1529641D03*
Y1521641D03*
X52048Y1556062D03*
X52000Y1644980D03*
X56098Y109410D03*
Y116496D03*
X55964Y103037D03*
X56098Y123583D03*
Y130670D03*
X68896Y226141D03*
X58279Y293796D03*
X66293Y285690D03*
X68793D03*
X66293Y288190D03*
X68793D03*
X60779Y293796D03*
X65759Y437508D03*
X61759D03*
X57759D03*
X54936Y449352D03*
X59522Y448874D03*
X68619Y447269D03*
X68497Y450201D03*
X64550Y504699D03*
X62050D03*
X59550D03*
X68236Y519458D03*
X61752Y516979D03*
X64252D03*
X59252D03*
X55318Y629362D03*
X53129Y627948D03*
X55307Y688473D03*
X66342Y880067D03*
X67316Y865869D03*
X64175Y897500D03*
X67461Y912983D03*
X63303Y912835D03*
X57178Y981386D03*
X69263Y1053152D03*
X55049Y1082343D03*
X55004Y1086937D03*
X58981Y1105100D03*
X56381D03*
X61581D03*
X64281D03*
X61681Y1114800D03*
X56481D03*
X59081D03*
X64381D03*
X57218Y1123867D03*
X55397Y1133688D03*
X57897D03*
X58250Y1220896D03*
X65940Y1209382D03*
X58250Y1227796D03*
Y1230296D03*
Y1237196D03*
Y1234696D03*
Y1223396D03*
X57185Y1480808D03*
X57144Y1491047D03*
X56114Y1556061D03*
X68743Y1583498D03*
X73381Y94017D03*
X69381D03*
X71422Y151540D03*
X75072Y191941D03*
X81572Y184619D03*
X74939Y188727D03*
X83552Y206760D03*
X71696Y226141D03*
X76766Y256535D03*
X84766D03*
X71593Y285690D03*
Y288190D03*
X75819Y290755D03*
X79819D03*
X83819D03*
X71826Y480705D03*
X75736Y519458D03*
X73236D03*
X70736D03*
X81740Y636250D03*
X69670Y633205D03*
Y636005D03*
X81740Y633450D03*
X69670Y638805D03*
X81740Y639050D03*
X74414Y681907D03*
X76991Y946134D03*
X84679Y1018368D03*
X70059Y1071656D03*
X69373Y1063389D03*
X70059Y1079656D03*
X80290Y1345691D03*
Y1350683D03*
X75334Y1345691D03*
Y1350683D03*
X80290Y1357603D03*
Y1362595D03*
X75334Y1357603D03*
Y1362595D03*
X80290Y1381801D03*
Y1369889D03*
Y1374881D03*
X75334Y1381801D03*
Y1374881D03*
Y1369889D03*
X80290Y1386793D03*
X75334D03*
X87000Y1597855D03*
X76005Y1580680D03*
X82433Y1580590D03*
X72000Y1644980D03*
X88080Y103603D03*
X87002Y146461D03*
X85904Y152367D03*
X87604Y180572D03*
X92287Y180527D03*
X96010Y192421D03*
X92242Y185121D03*
X87604Y185165D03*
X85796Y279208D03*
X89900Y281307D03*
X90257Y445506D03*
X88875Y840940D03*
X91581Y877859D03*
Y874859D03*
X87853Y899220D03*
X91128Y1006487D03*
X99836Y997860D03*
X95836D03*
X100594Y1035088D03*
X97247Y1030568D03*
X103124Y1165091D03*
X87574Y1345691D03*
Y1350683D03*
X99814D03*
Y1345691D03*
X92530D03*
Y1350683D03*
X87574Y1362595D03*
Y1357603D03*
X99814Y1362595D03*
Y1357603D03*
X92530Y1362595D03*
Y1357603D03*
X87574Y1374881D03*
Y1369795D03*
Y1381801D03*
X99814D03*
Y1374881D03*
Y1369889D03*
X92530Y1374881D03*
Y1369795D03*
Y1381801D03*
X87574Y1399079D03*
Y1393993D03*
Y1386793D03*
X99814Y1399079D03*
Y1394087D03*
Y1386793D03*
X92530Y1393993D03*
Y1399079D03*
Y1386793D03*
X87574Y1410991D03*
Y1405999D03*
X99814Y1410991D03*
Y1405999D03*
X92530Y1410991D03*
Y1405999D03*
X92000Y1644980D03*
X107364Y113394D03*
Y110394D03*
X110013Y110784D03*
X110152Y130898D03*
X117607Y133298D03*
X111754Y134579D03*
X107540Y172665D03*
Y180665D03*
X107572Y200864D03*
Y212864D03*
Y216864D03*
Y221864D03*
X109329Y252371D03*
X112474Y716315D03*
X114397Y727974D03*
X113601Y881266D03*
X107641Y865224D03*
X103836Y997860D03*
X111836D03*
X114770Y1009354D03*
X107836Y997860D03*
X115836D03*
X108933Y1102091D03*
X112433D03*
X103124D03*
X112433Y1114691D03*
X103124D03*
X108933D03*
Y1127291D03*
X112433D03*
X103124D03*
X112433Y1139891D03*
X103124Y1152491D03*
X108933D03*
X112433D03*
X108933Y1165091D03*
X112433D03*
X103184Y1177691D03*
X108933D03*
X112433D03*
X109415Y1202103D03*
X112795Y1223749D03*
X104770Y1350683D03*
Y1345691D03*
X112054D03*
Y1350683D03*
X117010Y1345691D03*
Y1350683D03*
X104770Y1362595D03*
Y1357603D03*
X112054Y1362595D03*
Y1357603D03*
X117010Y1362595D03*
Y1357603D03*
Y1369889D03*
Y1374881D03*
Y1381801D03*
X104770D03*
Y1374881D03*
Y1369889D03*
X112054D03*
Y1374881D03*
Y1381801D03*
X104770Y1399079D03*
Y1394087D03*
Y1386793D03*
X112054Y1399079D03*
Y1394087D03*
Y1386793D03*
X117010Y1394087D03*
Y1399079D03*
Y1386793D03*
X104770Y1410991D03*
Y1405999D03*
X112054Y1410991D03*
Y1405999D03*
X117010Y1410991D03*
Y1405999D03*
X107669Y1456451D03*
Y1465913D03*
X116330Y1465513D03*
X107669Y1461182D03*
X116330Y1460782D03*
X107669Y1481267D03*
X116330Y1480867D03*
X107669Y1476536D03*
X116330Y1476136D03*
Y1470244D03*
X107669Y1471805D03*
X116330Y1491490D03*
Y1485598D03*
X107669Y1487159D03*
Y1496621D03*
X116330Y1496221D03*
X107669Y1491890D03*
X116330Y1506845D03*
Y1500952D03*
X107669Y1502514D03*
X116330Y1511576D03*
X107669Y1511976D03*
Y1507245D03*
X116330Y1516307D03*
X107669Y1563544D03*
X116330Y1563144D03*
X107669Y1558813D03*
Y1568275D03*
X116330Y1567875D03*
X107669Y1578898D03*
X116330Y1578498D03*
Y1572606D03*
X107669Y1574167D03*
Y1583629D03*
X116330Y1583229D03*
X107669Y1594253D03*
X116330Y1593853D03*
Y1587960D03*
X107669Y1589522D03*
Y1609607D03*
X116330Y1609207D03*
X107669Y1598984D03*
X116330Y1598584D03*
Y1603315D03*
X107669Y1604876D03*
X116330Y1613938D03*
Y1618669D03*
X107669Y1614338D03*
X112000Y1644980D03*
X128350Y116497D03*
X133150D03*
X124606Y106495D03*
X125599Y109172D03*
X122599D03*
X133150Y123584D03*
X128350D03*
X133150Y130670D03*
X128350D03*
Y137757D03*
X133150D03*
X126246Y141228D03*
X124340Y146012D03*
X129134Y150847D03*
X131102Y247292D03*
X123811Y253198D03*
X125125Y362403D03*
X118122Y747565D03*
X122887Y884000D03*
X127067Y891495D03*
X124079Y1009354D03*
X119836Y997860D03*
X131836D03*
X127836D03*
X123836D03*
X120579Y1009354D03*
Y1021954D03*
X124079D03*
X133870Y1105091D03*
Y1117691D03*
Y1130291D03*
Y1142891D03*
Y1155491D03*
Y1168091D03*
X121211Y1215195D03*
X126937Y1209607D03*
X124294Y1350683D03*
Y1345691D03*
X129250Y1350683D03*
Y1345691D03*
X124294Y1362595D03*
Y1357603D03*
X129250D03*
Y1362595D03*
X124294Y1374881D03*
Y1369889D03*
Y1381801D03*
X129250Y1374881D03*
Y1369889D03*
Y1381801D03*
X124294Y1394087D03*
Y1399079D03*
Y1386793D03*
X129250Y1394087D03*
Y1399079D03*
Y1386793D03*
X124294Y1405999D03*
Y1410991D03*
X129250Y1405999D03*
Y1410991D03*
X124992Y1465913D03*
Y1456451D03*
Y1461182D03*
X133653Y1465513D03*
Y1460782D03*
X124992Y1471805D03*
Y1476536D03*
Y1481267D03*
X133653Y1476136D03*
Y1470244D03*
Y1480867D03*
Y1496221D03*
X124992Y1487159D03*
Y1491890D03*
Y1496621D03*
X133653Y1491490D03*
Y1485598D03*
Y1506845D03*
Y1500952D03*
Y1511576D03*
X124992Y1511976D03*
Y1507245D03*
Y1502514D03*
X133653Y1516307D03*
X124992Y1558813D03*
Y1563544D03*
X133653Y1563144D03*
Y1567875D03*
X124992Y1574167D03*
Y1578898D03*
X133653Y1578498D03*
Y1572606D03*
X124992Y1568275D03*
Y1589522D03*
Y1594253D03*
X133653Y1593853D03*
Y1587960D03*
X124992Y1583629D03*
X133653Y1583229D03*
X124992Y1609607D03*
Y1604876D03*
Y1598984D03*
X133653Y1609207D03*
Y1598584D03*
Y1603315D03*
X124992Y1614338D03*
X133653Y1613938D03*
Y1618669D03*
X132000Y1644980D03*
X148812Y80384D03*
Y82984D03*
Y75184D03*
Y77784D03*
Y85584D03*
X135650Y109410D03*
X140350Y116496D03*
Y109410D03*
Y102323D03*
X135650Y116497D03*
Y123583D03*
Y130670D03*
X140350D03*
Y123583D03*
Y137756D03*
X136604Y450750D03*
X140703Y536382D03*
X145670Y597580D03*
X147893Y599588D03*
X147155Y589556D03*
X147094Y592354D03*
X145609Y594668D03*
X147896Y596095D03*
X147925Y615600D03*
X147893Y607588D03*
X139836Y997860D03*
X147836D03*
X143836D03*
X135836D03*
X145516Y1024954D03*
Y1012354D03*
X148534Y1046476D03*
X134457Y1180654D03*
X141490Y1345691D03*
Y1350683D03*
X136534D03*
Y1345691D03*
X148774Y1350683D03*
Y1345691D03*
X141490Y1357603D03*
Y1362595D03*
X136534D03*
Y1357603D03*
X148774D03*
Y1362595D03*
X141490Y1369889D03*
Y1374881D03*
Y1381801D03*
X136534Y1369889D03*
Y1381801D03*
Y1374881D03*
X148774Y1369889D03*
Y1381801D03*
Y1374881D03*
X141490Y1386793D03*
Y1394087D03*
Y1399079D03*
X136534D03*
Y1394087D03*
Y1386793D03*
X148774Y1394087D03*
Y1399079D03*
Y1386793D03*
X141490Y1405999D03*
Y1410991D03*
X136534D03*
Y1405999D03*
X148774D03*
Y1410991D03*
X142315Y1456451D03*
Y1461182D03*
Y1465913D03*
Y1471805D03*
Y1476536D03*
Y1481267D03*
Y1487159D03*
Y1491890D03*
Y1496621D03*
Y1507245D03*
Y1502514D03*
Y1511976D03*
Y1558813D03*
Y1563544D03*
Y1574167D03*
Y1578898D03*
Y1568275D03*
Y1589522D03*
Y1594253D03*
Y1583629D03*
Y1609607D03*
Y1604876D03*
Y1598984D03*
Y1614338D03*
X151366Y92849D03*
X158460Y116496D03*
X158326Y103037D03*
X158460Y109410D03*
Y130670D03*
Y123583D03*
X155051Y137756D03*
X163141Y293796D03*
X160641D03*
X166528Y312392D03*
X157375Y555234D03*
X157090Y562003D03*
X152386Y634946D03*
X151836Y997860D03*
X159836D03*
X164028Y1041468D03*
X155513Y1065148D03*
X161014Y1345691D03*
Y1350683D03*
X153730Y1345691D03*
Y1350683D03*
X165970Y1345691D03*
Y1350683D03*
X161014Y1362595D03*
Y1357603D03*
X153730Y1362595D03*
Y1357603D03*
X165970Y1362595D03*
Y1357603D03*
X161014Y1381801D03*
Y1369889D03*
Y1374881D03*
X153730Y1369889D03*
Y1381801D03*
Y1374881D03*
X165970D03*
Y1381801D03*
Y1369889D03*
X161014Y1394087D03*
Y1386793D03*
X153730Y1394087D03*
Y1386793D03*
X165970Y1394087D03*
Y1386793D03*
X161014Y1399079D03*
X153730D03*
X165970D03*
X161014Y1410991D03*
Y1405999D03*
X153730D03*
Y1410991D03*
X165970D03*
Y1405999D03*
X159637Y1461182D03*
X150976Y1465513D03*
Y1460782D03*
X159637Y1465913D03*
Y1456451D03*
X150976Y1476136D03*
Y1470244D03*
Y1480867D03*
X159637Y1471805D03*
Y1476536D03*
Y1481267D03*
Y1496621D03*
X150976Y1491490D03*
Y1485598D03*
Y1496221D03*
X159637Y1487159D03*
Y1491890D03*
X150976Y1500952D03*
Y1511576D03*
X159637Y1507245D03*
Y1502514D03*
Y1511976D03*
X150976Y1506845D03*
Y1516307D03*
X159637Y1558813D03*
Y1563544D03*
X150976Y1563144D03*
X159637Y1578898D03*
X150976Y1567875D03*
Y1578498D03*
Y1572606D03*
X159637Y1568275D03*
Y1574167D03*
X150976Y1583229D03*
Y1593853D03*
Y1587960D03*
X159637Y1583629D03*
Y1589522D03*
Y1594253D03*
X150976Y1609207D03*
Y1598584D03*
Y1603315D03*
X159637Y1609607D03*
Y1604876D03*
Y1598984D03*
X150976Y1613938D03*
Y1618669D03*
X159637Y1614338D03*
X152000Y1644980D03*
X179743Y94017D03*
X175743D03*
X171743D03*
X175871Y110445D03*
X180863Y115401D03*
Y110445D03*
X175871Y115401D03*
X180863Y129574D03*
Y124618D03*
X175871Y129574D03*
Y124618D03*
X173784Y151540D03*
X177434Y191941D03*
X177301Y188727D03*
X171258Y226141D03*
X174058D03*
X179128Y256535D03*
X173955Y285690D03*
Y288190D03*
X171155Y285690D03*
X168655Y288190D03*
X171155D03*
X168655Y285690D03*
X182181Y290755D03*
X178181D03*
X177369Y389154D03*
Y396240D03*
Y403327D03*
Y410413D03*
Y417500D03*
Y424587D03*
Y431673D03*
Y438760D03*
Y445847D03*
Y467539D03*
Y474626D03*
Y488799D03*
Y481713D03*
Y495886D03*
Y511673D03*
Y518760D03*
Y525847D03*
Y532933D03*
Y540020D03*
Y547106D03*
X176650Y602197D03*
X177114Y595108D03*
X173254Y1345691D03*
Y1350683D03*
X178210Y1345691D03*
Y1350683D03*
X173254Y1362595D03*
Y1357603D03*
X178210D03*
Y1362595D03*
X173254Y1374881D03*
Y1369889D03*
Y1381801D03*
X178210Y1374881D03*
Y1369889D03*
Y1381801D03*
X173254Y1394087D03*
Y1386793D03*
X178210Y1394087D03*
Y1386793D03*
X173254Y1399079D03*
X178210D03*
X173254Y1405999D03*
Y1410991D03*
X178210Y1405999D03*
Y1410991D03*
X168299Y1465513D03*
Y1460782D03*
X176960Y1465914D03*
Y1456452D03*
Y1461183D03*
X168299Y1476136D03*
Y1470244D03*
Y1480867D03*
X176960Y1476537D03*
Y1471806D03*
Y1481268D03*
X168299Y1491490D03*
Y1485598D03*
Y1496221D03*
X176960Y1491891D03*
Y1487160D03*
Y1496622D03*
Y1507246D03*
Y1502515D03*
X168299Y1506845D03*
Y1500952D03*
Y1511576D03*
X176960Y1511977D03*
X168299Y1516307D03*
Y1563144D03*
X176960Y1563544D03*
Y1558813D03*
Y1568275D03*
X168299Y1578498D03*
Y1572606D03*
Y1567875D03*
Y1583229D03*
X176960Y1583629D03*
X168299Y1593853D03*
Y1587960D03*
X176960Y1594253D03*
Y1589522D03*
X168299Y1609207D03*
Y1598584D03*
Y1603315D03*
X176960Y1609607D03*
Y1598984D03*
Y1604876D03*
X168299Y1613938D03*
Y1618669D03*
X176960Y1614338D03*
X172000Y1644980D03*
X188820Y80140D03*
Y84140D03*
Y76140D03*
X183752Y94017D03*
X186273Y117557D03*
X191265D03*
X186273Y131731D03*
Y122513D03*
X191265D03*
Y131731D03*
X189364Y146461D03*
X186273Y136687D03*
X191265D03*
X188266Y152367D03*
X194649Y180527D03*
X189966Y180572D03*
X198372Y192421D03*
X189966Y185165D03*
X194604Y185121D03*
X183934Y184619D03*
X185914Y206760D03*
X187128Y256535D03*
X188158Y279208D03*
X192262Y281307D03*
X186181Y290755D03*
X191988Y389154D03*
X190518Y396240D03*
X194603Y422864D03*
X195295Y414823D03*
X194673Y429832D03*
X194278Y436447D03*
X196313Y447953D03*
X195480Y467539D03*
X194222Y472772D03*
X194956Y487711D03*
X195069Y479104D03*
X195480Y495886D03*
X190829Y516841D03*
X194080Y510565D03*
X185654Y552872D03*
X185776Y550123D03*
X185099Y562443D03*
X186867Y560675D03*
X187408Y572334D03*
X185640Y574102D03*
X193723Y656942D03*
X185494Y1345597D03*
Y1350683D03*
X190450Y1345597D03*
Y1350683D03*
X197734Y1345691D03*
Y1350683D03*
X185494Y1362595D03*
Y1357603D03*
X197734Y1362595D03*
Y1357603D03*
X190450Y1362595D03*
Y1357603D03*
X185494Y1374881D03*
Y1381801D03*
Y1369889D03*
X197734D03*
Y1381801D03*
Y1374881D03*
X190450Y1369889D03*
Y1374881D03*
Y1381801D03*
X185494Y1393993D03*
Y1386793D03*
X190450Y1393993D03*
Y1386793D03*
X197734Y1394087D03*
Y1386793D03*
X185494Y1399079D03*
X190450D03*
X197734D03*
X185494Y1410991D03*
Y1405999D03*
X190450Y1410991D03*
Y1405999D03*
X197734D03*
Y1410991D03*
X185622Y1465513D03*
Y1460782D03*
Y1480868D03*
Y1476137D03*
Y1470244D03*
Y1485599D03*
X192000Y1644980D03*
X211262Y60922D03*
X206398Y55513D03*
X208463Y96472D03*
X202195Y117261D03*
X209726Y113394D03*
Y110394D03*
X212375Y110784D03*
X211969Y133298D03*
X214116Y134579D03*
X209902Y172665D03*
Y180665D03*
X209934Y200864D03*
Y212864D03*
Y216864D03*
Y221864D03*
X211691Y252371D03*
X215380Y389153D03*
X210580D03*
X215380Y396240D03*
X208080Y403327D03*
X215380Y403326D03*
X210580D03*
X208080Y410413D03*
X210580D03*
X215380D03*
X208080Y396240D03*
X210580D03*
X208080Y417500D03*
X215380Y417499D03*
X210580D03*
X208080Y424586D03*
X210580D03*
X215380D03*
X208080Y431673D03*
Y438760D03*
X210580D03*
X215380D03*
Y431673D03*
X210580D03*
X208080Y445847D03*
X215380Y467539D03*
X210580D03*
X208080Y474626D03*
X210580D03*
X215380D03*
Y488799D03*
X208080D03*
X210580D03*
Y481712D03*
X208080D03*
X215380D03*
X208080Y495886D03*
X215380Y518760D03*
X210580D03*
X208080D03*
X210580Y511673D03*
X215380D03*
X210580Y532933D03*
X208080D03*
Y540020D03*
Y525846D03*
X210580D03*
X215380D03*
Y532933D03*
X212460Y560500D03*
X209429Y625300D03*
X202690Y1345597D03*
Y1350683D03*
Y1362595D03*
Y1357603D03*
Y1369889D03*
Y1381801D03*
Y1374881D03*
Y1394087D03*
Y1386793D03*
Y1399079D03*
Y1405999D03*
Y1410991D03*
X211473Y1446675D03*
X213296Y1438215D03*
X211473Y1451631D03*
Y1462631D03*
Y1457675D03*
X224961Y109172D03*
X226968Y106495D03*
X230712Y116497D03*
X227961Y109172D03*
X230712Y123584D03*
Y130670D03*
X219969Y133298D03*
X228608Y141228D03*
X230712Y137757D03*
X226702Y146012D03*
X231496Y150847D03*
X226173Y253198D03*
X228760Y316122D03*
X223925Y543925D03*
X224500Y555000D03*
X222646Y607542D03*
X217945Y1423924D03*
X217799Y1433684D03*
X216465Y1446675D03*
X222253Y1438483D03*
X216465Y1451631D03*
Y1462631D03*
Y1457675D03*
X229260Y1469587D03*
X218171Y1474460D03*
X224176Y1492816D03*
X223235Y1506770D03*
X222908Y1502028D03*
X226957Y1510442D03*
X216342Y1515642D03*
X217519Y1537172D03*
X242712Y116496D03*
Y109410D03*
Y102323D03*
X238012Y116497D03*
X235512D03*
X238012Y109410D03*
Y123583D03*
Y130670D03*
X235512D03*
X242712D03*
Y123583D03*
X235512Y123584D03*
Y137757D03*
X242712Y137756D03*
X233464Y247292D03*
X236349Y339428D03*
X247333Y599506D03*
X241967Y616063D03*
X243078Y636486D03*
X240249Y628328D03*
X241084Y638243D03*
X246583Y665140D03*
X241850Y678462D03*
X247600Y848500D03*
X240845Y1345691D03*
Y1350683D03*
X245801Y1345691D03*
Y1350683D03*
X240845Y1357603D03*
Y1362595D03*
X245801Y1357603D03*
Y1362595D03*
X240845Y1381801D03*
Y1374881D03*
Y1369889D03*
X245801Y1381801D03*
Y1374881D03*
Y1369889D03*
X240845Y1386793D03*
X245801D03*
X232675Y1466801D03*
X240466Y1503857D03*
X243268Y1501903D03*
X237700Y1531600D03*
X251174Y77784D03*
Y80384D03*
Y82984D03*
Y75184D03*
Y85584D03*
X253728Y92849D03*
X260688Y103037D03*
X260822Y116496D03*
Y109410D03*
Y130670D03*
Y123583D03*
X257413Y137756D03*
X263003Y293796D03*
X257226Y312081D03*
X265011Y403307D03*
X255000Y427017D03*
X254692Y431029D03*
X253758Y435029D03*
X254678Y449873D03*
X261605Y465492D03*
Y472579D03*
X259105D03*
X254305D03*
X261605Y486752D03*
X254305D03*
X259105Y479666D03*
X261605D03*
X254305D03*
X259105Y486752D03*
X254305Y493839D03*
X259105D03*
X261605Y516713D03*
X259105D03*
Y523800D03*
X261605D03*
X254305D03*
Y516713D03*
X261605Y509626D03*
Y530886D03*
X259105D03*
Y537973D03*
X254305Y530886D03*
Y537973D03*
Y566752D03*
X261605Y559665D03*
Y566752D03*
X259105D03*
X261605Y588012D03*
X259105Y588013D03*
X254305Y573839D03*
X261605D03*
X259105D03*
X261605Y580926D03*
X259105D03*
X254305D03*
Y588013D03*
X259105Y602186D03*
X254305D03*
Y595099D03*
X259105D03*
X261605D03*
Y602185D03*
X254305Y609272D03*
X259105D03*
X261605D03*
X259105Y616359D03*
X254305D03*
X248984Y638125D03*
X258867Y680499D03*
X258041Y1350683D03*
Y1345691D03*
X253085Y1350683D03*
Y1345691D03*
X258041Y1362595D03*
X253085D03*
X258041Y1357603D03*
X253085D03*
X258041Y1381801D03*
Y1369795D03*
Y1374881D03*
X253085Y1381801D03*
Y1369795D03*
Y1374881D03*
Y1393993D03*
Y1399079D03*
X258041Y1386793D03*
Y1399079D03*
Y1393993D03*
X253085Y1386793D03*
X258041Y1405999D03*
Y1410991D03*
X253085Y1405999D03*
Y1410991D03*
X248042Y1532900D03*
X274105Y94017D03*
X278105D03*
X278233Y115401D03*
Y110445D03*
Y129574D03*
Y124618D03*
X276146Y151540D03*
X279796Y191941D03*
X279663Y188727D03*
X276420Y226141D03*
X273620D03*
X276317Y288190D03*
X273517Y285690D03*
X271017Y288190D03*
X273517D03*
X271017Y285690D03*
X265503Y293796D03*
X276317Y285690D03*
X274425Y390500D03*
X265011Y410394D03*
X266405Y451319D03*
Y458406D03*
Y465492D03*
X266229Y462264D03*
X266405Y472579D03*
Y479665D03*
Y486752D03*
Y493839D03*
Y523799D03*
Y516713D03*
Y509626D03*
Y530886D03*
Y537973D03*
Y566752D03*
Y559665D03*
Y580926D03*
Y588012D03*
Y573839D03*
Y602185D03*
Y595099D03*
Y609272D03*
Y616358D03*
X269700Y884600D03*
X269900Y914200D03*
X270100Y946500D03*
X277565Y1350683D03*
Y1345691D03*
X265325D03*
Y1350683D03*
X270281Y1345691D03*
Y1350683D03*
X277565Y1362595D03*
X265325D03*
X270281D03*
X277565Y1357603D03*
X265325D03*
X270281D03*
X277565Y1381801D03*
Y1374881D03*
Y1369889D03*
X265325D03*
Y1374881D03*
Y1381801D03*
X270281Y1369889D03*
Y1374881D03*
Y1381801D03*
X277565Y1386793D03*
Y1394087D03*
Y1399079D03*
X265325Y1394087D03*
Y1399079D03*
Y1386793D03*
X270281Y1399079D03*
Y1394087D03*
Y1386793D03*
X265325Y1405999D03*
Y1410991D03*
X270281Y1405999D03*
Y1410991D03*
X277565Y1405999D03*
Y1410991D03*
X272000Y1644980D03*
X291182Y84140D03*
Y80140D03*
Y76140D03*
X282105Y94017D03*
X286114D03*
X288635Y117557D03*
X283225Y115401D03*
Y110445D03*
X293627Y117557D03*
X288635Y131731D03*
Y122513D03*
X283225Y129574D03*
Y124618D03*
X293627Y122513D03*
Y131731D03*
X291726Y146461D03*
X293627Y136687D03*
X288635D03*
X290628Y152367D03*
X292328Y180572D03*
Y185165D03*
X286296Y184619D03*
X288276Y206760D03*
X281490Y256535D03*
X289490D03*
X290520Y279208D03*
X294624Y281307D03*
X284543Y290755D03*
X280543D03*
X288543D03*
X284075Y381500D03*
X284482Y460250D03*
X284516Y465492D03*
X282247Y470136D03*
X284516Y472579D03*
Y479665D03*
Y486752D03*
Y493839D03*
Y516713D03*
Y509626D03*
X283377Y532756D03*
X283456Y525483D03*
X280976Y537973D03*
X284516Y559665D03*
Y566752D03*
X284366Y579978D03*
X284516Y573839D03*
X284580Y608117D03*
X282521Y1345691D03*
X289805Y1350683D03*
Y1345691D03*
X294761Y1350683D03*
Y1345691D03*
X282521Y1350683D03*
X289805Y1362595D03*
X294761D03*
X282521D03*
X289805Y1357603D03*
X294761D03*
X282521D03*
X289805Y1374881D03*
Y1369889D03*
Y1381801D03*
X294761Y1374881D03*
Y1369889D03*
Y1381801D03*
X282521D03*
Y1374881D03*
Y1369889D03*
X289805Y1394087D03*
Y1399079D03*
Y1386793D03*
X294761Y1394087D03*
Y1399079D03*
Y1386793D03*
X282521D03*
Y1399079D03*
Y1394087D03*
X289805Y1405999D03*
Y1410991D03*
X294761Y1405999D03*
Y1410991D03*
X282521Y1405999D03*
Y1410991D03*
X280897Y1465913D03*
X289558Y1465513D03*
X280897Y1461182D03*
X289558Y1460782D03*
X280897Y1456451D03*
X289558Y1480867D03*
X280897Y1476536D03*
X289558Y1476136D03*
Y1470244D03*
X280897Y1471805D03*
Y1481267D03*
Y1491890D03*
X289558Y1491490D03*
Y1485598D03*
X280897Y1487159D03*
Y1496621D03*
X289558Y1496221D03*
X280897Y1507245D03*
X289558Y1506845D03*
Y1500952D03*
X280897Y1502514D03*
X289558Y1511576D03*
X280897Y1511976D03*
X289558Y1516307D03*
X280897Y1563544D03*
X289558Y1563144D03*
X280897Y1558813D03*
Y1574167D03*
Y1568275D03*
X289558Y1567875D03*
X280897Y1578898D03*
X289558Y1578498D03*
Y1572606D03*
Y1593853D03*
Y1587960D03*
X280897Y1589522D03*
Y1583629D03*
X289558Y1583229D03*
X280897Y1594253D03*
Y1609607D03*
X289558Y1609207D03*
X280897Y1598984D03*
X289558Y1598584D03*
Y1603315D03*
X280897Y1604876D03*
Y1614338D03*
X289558Y1613938D03*
Y1618669D03*
X292000Y1644980D03*
X308760Y55513D03*
X310882Y96613D03*
X305953Y91951D03*
X312088Y113394D03*
X304557Y117261D03*
X297011Y180527D03*
X312264Y172665D03*
Y180665D03*
X299759Y190285D03*
X296966Y185121D03*
X312296Y212864D03*
Y200864D03*
Y221864D03*
Y216864D03*
X306812Y342319D03*
X309258Y389912D03*
Y393924D03*
Y385912D03*
Y409924D03*
Y405924D03*
Y401924D03*
X306673Y418838D03*
X298507Y445908D03*
X302457Y445787D03*
X302045Y1345691D03*
Y1350683D03*
X307001D03*
Y1345691D03*
X302045Y1362595D03*
X307001D03*
X302045Y1357603D03*
X307001D03*
X302045Y1374881D03*
Y1381801D03*
Y1369889D03*
X307001Y1374881D03*
Y1369889D03*
Y1381801D03*
X302045Y1386793D03*
Y1394087D03*
Y1399079D03*
X307001Y1386793D03*
Y1399079D03*
Y1394087D03*
X302045Y1405999D03*
Y1410991D03*
X307001Y1405999D03*
Y1410991D03*
X298220Y1465913D03*
Y1456451D03*
Y1461182D03*
X306881Y1465513D03*
Y1460782D03*
Y1470244D03*
Y1480867D03*
X298220Y1471805D03*
Y1476536D03*
Y1481267D03*
X306881Y1476136D03*
X298220Y1487159D03*
Y1491890D03*
Y1496621D03*
X306881Y1491490D03*
Y1485598D03*
Y1496221D03*
X298220Y1507245D03*
Y1502514D03*
X306881Y1506845D03*
Y1500952D03*
Y1511576D03*
X298220Y1511976D03*
X306881Y1516307D03*
X298220Y1558813D03*
Y1563544D03*
X306881Y1563144D03*
X298220Y1568275D03*
X306881Y1567875D03*
X298220Y1574167D03*
Y1578898D03*
X306881Y1578498D03*
Y1572606D03*
X298220Y1583629D03*
X306881Y1583229D03*
X298220Y1589522D03*
Y1594253D03*
X306881Y1593853D03*
Y1587960D03*
Y1598584D03*
Y1603315D03*
X298220Y1609607D03*
Y1604876D03*
Y1598984D03*
X306881Y1609207D03*
X298220Y1614338D03*
X306881Y1613938D03*
Y1618669D03*
X312000Y1644980D03*
X313624Y60922D03*
X327323Y109172D03*
X314737Y110784D03*
X314854Y130898D03*
X322331Y133298D03*
X329064Y146012D03*
X316478Y134579D03*
X328535Y253198D03*
X314053Y252371D03*
X323882Y303839D03*
X315904Y336324D03*
X320483Y353506D03*
X319241Y1350683D03*
Y1345691D03*
X314285D03*
Y1350683D03*
X326525Y1345691D03*
Y1350683D03*
X319241Y1362595D03*
X314285D03*
X326525D03*
X319241Y1357603D03*
X314285D03*
X326525D03*
X319241Y1374881D03*
Y1381801D03*
Y1369889D03*
X314285Y1374881D03*
Y1381801D03*
Y1369889D03*
X326525Y1381801D03*
Y1369889D03*
Y1374881D03*
X319241Y1386793D03*
Y1399079D03*
Y1394087D03*
X314285Y1386793D03*
Y1399079D03*
Y1394087D03*
X326525Y1399079D03*
Y1394087D03*
Y1386793D03*
X319241Y1410991D03*
Y1405999D03*
X314285Y1410991D03*
Y1405999D03*
X326525Y1410991D03*
Y1405999D03*
X315543Y1465913D03*
Y1456451D03*
Y1461182D03*
X324204Y1465513D03*
Y1460782D03*
Y1480867D03*
X315543Y1471805D03*
Y1476536D03*
Y1481267D03*
X324204Y1476136D03*
Y1470244D03*
X315543Y1487159D03*
Y1491890D03*
Y1496621D03*
X324204Y1491490D03*
Y1485598D03*
Y1496221D03*
Y1500952D03*
Y1511576D03*
X315543Y1507245D03*
Y1502514D03*
Y1511976D03*
X324204Y1506845D03*
Y1516307D03*
X315543Y1558813D03*
Y1563544D03*
X324204Y1563144D03*
X315543Y1574167D03*
Y1578898D03*
X324204Y1567875D03*
Y1578498D03*
Y1572606D03*
X315543Y1568275D03*
Y1583629D03*
Y1589522D03*
Y1594253D03*
X324204Y1583229D03*
Y1593853D03*
Y1587960D03*
X315543Y1609607D03*
Y1604876D03*
Y1598984D03*
X324204Y1609207D03*
Y1598584D03*
Y1603315D03*
X315543Y1614338D03*
X324204Y1613938D03*
Y1618669D03*
X329330Y106495D03*
X345074Y116496D03*
X337874Y116497D03*
X340374D03*
X345074Y109410D03*
Y102323D03*
X340374Y109410D03*
X333074Y116497D03*
X330323Y109172D03*
X337874Y130670D03*
X345074D03*
Y123583D03*
X340374D03*
X337874Y123584D03*
X333074D03*
Y130670D03*
X340374D03*
X333074Y137757D03*
X337874D03*
X330970Y141228D03*
X345074Y137756D03*
X333858Y150847D03*
X335826Y247292D03*
X338358Y554861D03*
X337564Y1018294D03*
X337629Y1186071D03*
X336901Y1196407D03*
X338765Y1350683D03*
Y1345691D03*
X331481D03*
Y1350683D03*
X343721Y1345691D03*
Y1350683D03*
X331481Y1362595D03*
X343721D03*
X338765D03*
X331481Y1357603D03*
X343721D03*
X338765D03*
X331481Y1374881D03*
Y1381801D03*
Y1369889D03*
X343721Y1381801D03*
Y1369889D03*
Y1374881D03*
X338765Y1381801D03*
Y1369889D03*
Y1374881D03*
X331481Y1399079D03*
Y1394087D03*
Y1386793D03*
X343721D03*
Y1394087D03*
Y1399079D03*
X338765Y1386793D03*
Y1394087D03*
Y1399079D03*
X331481Y1410991D03*
Y1405999D03*
X343721Y1410991D03*
Y1405999D03*
X338765Y1410991D03*
Y1405999D03*
X341527Y1460782D03*
X332865Y1465913D03*
Y1456451D03*
Y1461182D03*
X341527Y1465513D03*
Y1476136D03*
Y1470244D03*
Y1480867D03*
X332865Y1471805D03*
Y1476536D03*
Y1481267D03*
X341527Y1491490D03*
Y1485598D03*
Y1496221D03*
X332865Y1487159D03*
Y1491890D03*
Y1496621D03*
Y1511976D03*
X341527Y1506845D03*
Y1500952D03*
Y1511576D03*
X332865Y1507245D03*
Y1502514D03*
X341527Y1516307D03*
X332865Y1558813D03*
Y1563544D03*
X341527Y1563144D03*
X332865Y1578898D03*
X341527Y1567875D03*
Y1578498D03*
Y1572606D03*
X332865Y1568275D03*
Y1574167D03*
Y1583629D03*
Y1589522D03*
Y1594253D03*
X341527Y1583229D03*
Y1593853D03*
Y1587960D03*
X332865Y1598984D03*
X341527Y1609207D03*
Y1598584D03*
Y1603315D03*
X332865Y1609607D03*
Y1604876D03*
X341527Y1613938D03*
Y1618669D03*
X332865Y1614338D03*
X332000Y1644980D03*
X353536Y82984D03*
Y80384D03*
Y77784D03*
Y75184D03*
X356090Y92849D03*
X353536Y85584D03*
X359525Y137756D03*
X356423Y301288D03*
X348375Y322284D03*
X348968Y333138D03*
X359278Y491870D03*
X356778D03*
X358096Y867459D03*
X358086Y884616D03*
X357962Y898800D03*
X358024Y912085D03*
X358085Y923327D03*
X355929Y1132042D03*
X351563Y1132410D03*
X349700Y1148000D03*
X357947Y1159455D03*
X352536Y1160168D03*
X357297Y1192709D03*
X360659Y1209789D03*
X355961Y1350683D03*
X351005Y1345597D03*
Y1350683D03*
X355961Y1345597D03*
X351005Y1362595D03*
X355961D03*
X351005Y1357603D03*
X355961D03*
X351005Y1374881D03*
Y1381801D03*
Y1369889D03*
X355961Y1381801D03*
Y1374881D03*
Y1369889D03*
X351005Y1399079D03*
Y1393993D03*
Y1386793D03*
X355961D03*
Y1399079D03*
Y1393993D03*
X351005Y1410991D03*
Y1405999D03*
X355961D03*
Y1410991D03*
X350188Y1491891D03*
Y1487160D03*
Y1496622D03*
Y1507246D03*
Y1502515D03*
Y1511977D03*
X358850Y1511576D03*
Y1506845D03*
Y1516307D03*
X350188Y1563544D03*
Y1558813D03*
Y1568275D03*
Y1578898D03*
Y1574167D03*
Y1583629D03*
Y1594253D03*
Y1589522D03*
Y1604876D03*
Y1609607D03*
Y1598984D03*
Y1614338D03*
X352000Y1644980D03*
X376467Y94017D03*
X363050Y103037D03*
X363184Y116496D03*
Y109410D03*
Y130670D03*
Y123583D03*
X375982Y226141D03*
X378782D03*
X365365Y293796D03*
X367865D03*
X373379Y288190D03*
X375879Y285690D03*
X373379D03*
X375879Y288190D03*
X368057Y354184D03*
X364933Y374232D03*
X373264Y370010D03*
X366443Y472189D03*
X373504Y517954D03*
X375040Y932959D03*
X371424Y937185D03*
X367944Y946082D03*
X368657Y1146937D03*
X366133Y1162817D03*
X368661Y1182649D03*
X368917Y1195419D03*
X365029Y1214158D03*
X362735Y1211864D03*
X369839Y1218940D03*
X363245Y1345691D03*
Y1350683D03*
X368201Y1345691D03*
Y1350683D03*
X363245Y1362595D03*
X368201D03*
X363245Y1357603D03*
X368201D03*
X363245Y1369889D03*
Y1381801D03*
Y1374881D03*
X368201D03*
Y1381801D03*
Y1369889D03*
X363245Y1399079D03*
Y1394087D03*
Y1386793D03*
X368201D03*
Y1394087D03*
Y1399079D03*
X363245Y1405999D03*
Y1410991D03*
X368201D03*
Y1405999D03*
X372000Y1644980D03*
X393544Y76140D03*
Y84140D03*
Y80140D03*
X384467Y94017D03*
X388476D03*
X380467D03*
X390997Y117557D03*
X385587Y115401D03*
X380595D03*
X385587Y110445D03*
X380595D03*
X390997Y131731D03*
Y122513D03*
X385587Y129574D03*
X380595D03*
X385587Y124618D03*
X380595D03*
X390997Y136687D03*
X382158Y191941D03*
X388658Y184619D03*
X382025Y188727D03*
X390638Y206760D03*
X391852Y256535D03*
X383852D03*
X392882Y279208D03*
X378679Y285690D03*
Y288190D03*
X386905Y290755D03*
X382905D03*
X390905D03*
X392387Y337599D03*
Y342555D03*
X392444Y401949D03*
X393893Y413611D03*
X393833Y423944D03*
X393652Y482382D03*
X393746Y478382D03*
X388593Y664232D03*
X386350Y693559D03*
X391478Y690675D03*
X391614Y938651D03*
X381377Y1003008D03*
X381045Y1009444D03*
X391284Y1307238D03*
X394000Y1508100D03*
X382017Y1555700D03*
Y1547700D03*
Y1551700D03*
X392000Y1644980D03*
X408493Y117577D03*
X395989Y117557D03*
Y131731D03*
Y122513D03*
Y136687D03*
X399373Y180527D03*
X394690Y180572D03*
X403096Y192421D03*
X394690Y185165D03*
X399328Y185121D03*
X396986Y281307D03*
X409484Y314921D03*
X398951Y333711D03*
X397374Y344439D03*
X407493Y354142D03*
X394237Y370899D03*
X394944Y398949D03*
X399518Y402642D03*
X402018D03*
X396633Y423944D03*
X396693Y413611D03*
X399193D03*
X401693D03*
X401633Y423944D03*
X399133D03*
X409284Y741316D03*
X401121Y936686D03*
X409121Y939186D03*
X401121D03*
X409121Y936686D03*
X409231Y1123101D03*
X406105Y1139435D03*
X410131Y1129301D03*
X407631D03*
X409231Y1125801D03*
X406105Y1131935D03*
Y1134435D03*
Y1136935D03*
Y1141935D03*
Y1146935D03*
Y1144435D03*
X403263Y1152684D03*
X406319Y1204405D03*
Y1206905D03*
Y1211905D03*
Y1209405D03*
X397695Y1287071D03*
X399716Y1295198D03*
X408523Y1332967D03*
X404657D03*
X408937Y1351568D03*
X403981D03*
X401990Y1446807D03*
X399731Y1442755D03*
X397245Y1511640D03*
X404053Y1513673D03*
X397220Y1521207D03*
X409461Y1569560D03*
X405461D03*
X426147Y151540D03*
X414626Y180665D03*
Y172665D03*
X414658Y212864D03*
Y200864D03*
Y216864D03*
Y221864D03*
X422873Y309966D03*
X419955Y306966D03*
X414999D03*
X411984Y314921D03*
X421231Y338523D03*
Y331255D03*
Y345776D03*
X413432Y346797D03*
X416318Y367903D03*
X424479Y367859D03*
X418754Y468607D03*
X418226Y653288D03*
Y646480D03*
Y648980D03*
Y655788D03*
X425121Y936686D03*
Y939186D03*
X417121Y936686D03*
Y939186D03*
X417677Y1052215D03*
X425175Y1098767D03*
X417171Y1098887D03*
X419987Y1098518D03*
X419731Y1123101D03*
X417231D03*
X422631Y1125801D03*
X425131Y1129301D03*
X422631D03*
X420131D03*
X417631D03*
X415131D03*
X412631D03*
X420131Y1125801D03*
X417631D03*
X425131D03*
X422495Y1152713D03*
Y1155213D03*
X412095Y1152713D03*
Y1155213D03*
X422934Y1200821D03*
Y1198321D03*
X420619Y1204617D03*
Y1207117D03*
Y1209617D03*
Y1212117D03*
X411174Y1282776D03*
X418537Y1300197D03*
X423741Y1300115D03*
X413354Y1300197D03*
X425582Y1291743D03*
X423762Y1305298D03*
X413374D03*
X418558Y1310523D03*
X413395Y1310481D03*
X423721Y1310523D03*
X425283Y1373958D03*
X411147Y1474993D03*
X419818Y1474945D03*
X415241Y1492990D03*
X415095Y1502750D03*
X411353Y1519440D03*
X419467Y1519706D03*
X420279Y1525978D03*
X410626Y1525991D03*
X413461Y1569560D03*
X412000Y1644980D03*
X441727Y146461D03*
X440629Y152367D03*
X435703Y306966D03*
X430747D03*
X427829Y309966D03*
X428459Y331255D03*
X435793D03*
X428500Y345776D03*
X435793Y345738D03*
X430439Y358115D03*
X435702Y367813D03*
X430746D03*
X427782Y464026D03*
X438396Y511493D03*
X435834Y509580D03*
X431804Y536682D03*
Y539182D03*
X441832Y626193D03*
X433206Y1055498D03*
X430706D03*
Y1057998D03*
X433206D03*
Y1060498D03*
Y1062998D03*
X430706D03*
Y1060498D03*
X441359Y1123101D03*
X438233Y1139435D03*
X441359Y1125801D03*
X439759Y1129301D03*
X442259D03*
X429331Y1136935D03*
Y1134435D03*
Y1139435D03*
Y1131935D03*
X435733D03*
Y1134435D03*
Y1136935D03*
Y1139435D03*
X438233Y1131935D03*
Y1134435D03*
Y1136935D03*
X429331Y1141935D03*
X435733D03*
Y1146935D03*
Y1144435D03*
X438233Y1141935D03*
Y1146935D03*
Y1144435D03*
X437231Y1154902D03*
Y1152402D03*
X429331Y1146935D03*
Y1144435D03*
X433249Y1204405D03*
Y1209405D03*
Y1211905D03*
Y1206905D03*
X437991Y1286544D03*
X440896Y1311366D03*
X432485Y1325784D03*
X439624Y1345691D03*
Y1350683D03*
Y1357603D03*
Y1362595D03*
Y1381801D03*
Y1369889D03*
Y1374881D03*
X436002Y1382252D03*
X439624Y1386793D03*
X437675Y1550158D03*
X429784Y1548222D03*
X432000Y1644980D03*
X458454Y328963D03*
Y324007D03*
Y339755D03*
Y344711D03*
X453463Y370694D03*
X448092Y375770D03*
X443094Y491251D03*
X455104Y536582D03*
Y539082D03*
X447279Y633881D03*
X454815Y974622D03*
X448999Y994483D03*
X456210Y1004680D03*
X452319Y1000828D03*
X449731Y1000855D03*
X453710Y1018825D03*
X443091Y1022766D03*
Y1030266D03*
X450063Y1043140D03*
X449767Y1047047D03*
X457303Y1098767D03*
X452115Y1098518D03*
X446863Y1098428D03*
X449359Y1123101D03*
X451859D03*
X457259Y1129301D03*
X449759Y1125801D03*
X452259D03*
X444759Y1129301D03*
X447259D03*
X449759D03*
X452259D03*
X454759Y1125801D03*
X457259D03*
X454759Y1129301D03*
X443223Y1155213D03*
Y1152713D03*
X452623D03*
Y1155213D03*
X447549Y1204617D03*
X449864Y1198321D03*
Y1200821D03*
X447549Y1209617D03*
Y1207117D03*
Y1212117D03*
X454120Y1269498D03*
X456213Y1286776D03*
X451304Y1293045D03*
X456820Y1345691D03*
X451864D03*
Y1350683D03*
X456820D03*
X444580Y1345691D03*
Y1350683D03*
X456820Y1362595D03*
Y1357603D03*
X451864Y1362595D03*
Y1357603D03*
X444580D03*
Y1362595D03*
X456820Y1374881D03*
X451864D03*
X444580Y1369889D03*
X456820Y1369795D03*
X451864D03*
X444580Y1374881D03*
Y1381801D03*
X456820D03*
X451864D03*
X456820Y1399079D03*
X451864Y1393993D03*
Y1399079D03*
X456820Y1393993D03*
Y1386793D03*
X451864D03*
X444580D03*
X456820Y1405999D03*
X451864D03*
Y1410991D03*
X456820D03*
X454125Y1461182D03*
Y1465913D03*
Y1471805D03*
Y1481267D03*
Y1476536D03*
Y1491890D03*
Y1487159D03*
Y1496621D03*
Y1511976D03*
Y1507245D03*
Y1502514D03*
Y1558813D03*
Y1578898D03*
Y1568275D03*
Y1563544D03*
Y1574167D03*
Y1583629D03*
Y1589522D03*
Y1594253D03*
Y1609607D03*
Y1598984D03*
Y1604876D03*
Y1614338D03*
X452000Y1644980D03*
X464738Y110784D03*
X462089Y113394D03*
X472332Y133298D03*
X464332D03*
X466479Y134579D03*
X464054Y252371D03*
X461454Y336837D03*
Y331881D03*
Y347629D03*
Y352585D03*
X466375Y366365D03*
X470389Y389553D03*
X468558Y491669D03*
Y503669D03*
Y507669D03*
Y512669D03*
X462242Y809792D03*
X475032Y843252D03*
X474678Y857919D03*
X463134Y859203D03*
X460455Y867050D03*
X475046Y885952D03*
X467494Y924532D03*
X462427Y1030218D03*
X460277Y1090268D03*
Y1093068D03*
X474818Y1123101D03*
X469192Y1131935D03*
X474818Y1125801D03*
X473218Y1129301D03*
X461459Y1136935D03*
Y1134435D03*
Y1139435D03*
Y1131935D03*
X471692Y1139435D03*
Y1136935D03*
Y1134435D03*
Y1131935D03*
X469192Y1139435D03*
Y1136935D03*
Y1134435D03*
X471692Y1146935D03*
Y1141935D03*
X469192Y1144435D03*
Y1146935D03*
Y1141935D03*
X471692Y1144435D03*
X461459D03*
X462687Y1152684D03*
X468850D03*
X461459Y1141935D03*
Y1146935D03*
X463216Y1254164D03*
Y1250760D03*
Y1244055D03*
X461613Y1286776D03*
X469060Y1345691D03*
Y1350683D03*
X464104Y1345691D03*
Y1350683D03*
X469060Y1357603D03*
Y1362595D03*
X464104D03*
Y1357603D03*
Y1381801D03*
X469060D03*
X464104Y1369889D03*
X469060D03*
X464104Y1374881D03*
X469060D03*
Y1386793D03*
X464104D03*
X469060Y1399079D03*
X464104Y1394087D03*
X469060D03*
X464104Y1399079D03*
Y1405999D03*
X469060D03*
X464104Y1410991D03*
X469060D03*
X471448Y1461182D03*
X462786Y1460782D03*
X471448Y1465913D03*
X462786Y1465513D03*
X471448Y1481267D03*
X462786Y1480867D03*
X471448Y1471805D03*
Y1476536D03*
X462786Y1476136D03*
Y1470244D03*
X471448Y1496621D03*
X462786Y1496221D03*
X471448Y1491890D03*
X462786Y1491490D03*
Y1485598D03*
X471448Y1487159D03*
Y1511976D03*
Y1502514D03*
Y1507245D03*
X462786Y1511576D03*
Y1506845D03*
Y1500952D03*
Y1516307D03*
Y1563144D03*
X471448Y1558813D03*
X462786Y1578498D03*
X471448Y1574167D03*
Y1568275D03*
Y1563544D03*
X462786Y1567875D03*
Y1572606D03*
X471448Y1578898D03*
Y1594253D03*
X462786Y1593853D03*
X471448Y1589522D03*
Y1583629D03*
X462786Y1583229D03*
Y1587960D03*
X471448Y1598984D03*
X462786Y1609207D03*
Y1598584D03*
Y1603315D03*
X471448Y1609607D03*
Y1604876D03*
Y1614338D03*
X462786Y1613938D03*
Y1618669D03*
X472000Y1644980D03*
X480324Y109172D03*
X477324D03*
X479331Y106495D03*
X483075Y116497D03*
X487875D03*
X490375Y109410D03*
Y116497D03*
X483075Y130670D03*
X487875Y123584D03*
Y130670D03*
X490375Y123583D03*
Y130670D03*
X483075Y123584D03*
X479065Y146012D03*
X480971Y141228D03*
X483075Y137757D03*
X487875D03*
X483859Y150847D03*
X485827Y247292D03*
X478536Y253198D03*
X483242Y366481D03*
X483584Y375840D03*
X483736Y371266D03*
X483541Y380306D03*
X481724Y391589D03*
Y387089D03*
X488438Y425464D03*
X482532Y418464D03*
X482484Y444517D03*
X486738Y581222D03*
X489538D03*
Y591215D03*
X486738D03*
X491340Y611091D03*
X485005Y659771D03*
X491324Y667293D03*
X485303Y681841D03*
X486246Y804497D03*
X485824Y819787D03*
X481593Y826387D03*
X491453Y834546D03*
X491527Y843206D03*
X488469Y857013D03*
X481943Y924633D03*
X488388Y938903D03*
X483636Y952152D03*
X490143Y989521D03*
X476148Y1057998D03*
Y1055498D03*
X478648D03*
Y1057998D03*
X476148Y1060498D03*
Y1062998D03*
X478648D03*
Y1060498D03*
X490762Y1098767D03*
X485574Y1098518D03*
X480322Y1098428D03*
X485318Y1123101D03*
X482818D03*
X490718Y1129301D03*
X483218Y1125801D03*
X485718D03*
X475718Y1129301D03*
X478218D03*
X480718D03*
X483218D03*
X485718D03*
X488218Y1125801D03*
X490718D03*
X488218Y1129301D03*
X477682Y1152713D03*
Y1155213D03*
X488082D03*
Y1152713D03*
X479521Y1204405D03*
Y1206905D03*
Y1211905D03*
Y1209405D03*
X488584Y1345691D03*
Y1350683D03*
X481300Y1345691D03*
X476344D03*
X481300Y1350683D03*
X476344D03*
X488584Y1357603D03*
Y1362595D03*
X481300D03*
Y1357603D03*
X476344Y1362595D03*
Y1357603D03*
X488584Y1381801D03*
X481300D03*
X488584Y1374881D03*
Y1369889D03*
X481300D03*
Y1374881D03*
X476344Y1381801D03*
Y1369889D03*
Y1374881D03*
X488584Y1386793D03*
X481300D03*
Y1399079D03*
X476344Y1394087D03*
Y1399079D03*
X488584Y1394087D03*
X481300D03*
X488584Y1399079D03*
X476344Y1386793D03*
Y1410991D03*
X481300Y1405999D03*
X476344D03*
X488584D03*
Y1410991D03*
X481300D03*
X480109Y1460782D03*
Y1465513D03*
X488771Y1465913D03*
Y1461182D03*
X480109Y1476136D03*
Y1470244D03*
X488771Y1471805D03*
Y1476536D03*
Y1481267D03*
X480109Y1480867D03*
Y1496221D03*
X488771Y1487159D03*
Y1491890D03*
X480109Y1491490D03*
Y1485598D03*
X488771Y1496621D03*
Y1511976D03*
X480109Y1511576D03*
Y1506845D03*
Y1500952D03*
X488771Y1502514D03*
Y1507245D03*
X480109Y1516307D03*
X488771Y1558813D03*
X480109Y1563144D03*
X488771Y1578898D03*
X480109Y1578498D03*
X488771Y1574167D03*
Y1568275D03*
Y1563544D03*
X480109Y1567875D03*
Y1572606D03*
X488771Y1589522D03*
Y1583629D03*
X480109Y1583229D03*
Y1587960D03*
X488771Y1594253D03*
X480109Y1593853D03*
X488771Y1609607D03*
Y1604876D03*
Y1598984D03*
X480109Y1609207D03*
Y1598584D03*
Y1603315D03*
X488771Y1614338D03*
X480109Y1613938D03*
Y1618669D03*
X503537Y77784D03*
Y75184D03*
Y80384D03*
Y82984D03*
X506091Y92849D03*
X503537Y85584D03*
X495075Y116496D03*
Y102323D03*
Y109410D03*
Y130670D03*
Y123583D03*
Y137756D03*
X497424Y354559D03*
X492317Y376252D03*
X503682Y455466D03*
X497776Y448466D03*
X493929Y555194D03*
X496729D03*
X493929Y563194D03*
X496729D03*
X493929Y571194D03*
X496729D03*
X492338Y581222D03*
Y591215D03*
X494632Y654622D03*
X501618Y698355D03*
X499012Y699819D03*
X503311Y715652D03*
X500705Y705524D03*
X507546Y738539D03*
X505673Y767961D03*
X500717D03*
X504341Y812040D03*
X491655Y829173D03*
X506246Y824689D03*
X492799Y846488D03*
X503741Y846830D03*
X497467Y833027D03*
X499640Y861538D03*
X499595Y963963D03*
X493050Y976078D03*
X506566Y1000766D03*
Y1004766D03*
Y1016266D03*
Y1030766D03*
X505981Y1052487D03*
X506946Y1123101D03*
Y1125801D03*
X505346Y1129301D03*
X507846D03*
X503820Y1139435D03*
Y1136935D03*
Y1134435D03*
Y1131935D03*
X501320Y1139435D03*
Y1136935D03*
Y1134435D03*
Y1131935D03*
X494918Y1136935D03*
Y1134435D03*
Y1139435D03*
Y1131935D03*
X503820Y1144435D03*
Y1146935D03*
Y1141935D03*
X501320Y1144435D03*
Y1146935D03*
Y1141935D03*
X494918Y1146935D03*
Y1144435D03*
Y1141935D03*
X502562Y1152713D03*
Y1155213D03*
X506451Y1204405D03*
X493821Y1204617D03*
X496136Y1200821D03*
Y1198321D03*
X506451Y1206905D03*
Y1211905D03*
Y1209405D03*
X493821Y1207117D03*
Y1209617D03*
Y1212117D03*
X500824Y1350683D03*
Y1345691D03*
X505780Y1350683D03*
Y1345691D03*
X493540D03*
Y1350683D03*
X505780Y1362595D03*
Y1357603D03*
X500824Y1362595D03*
Y1357603D03*
X493540Y1362595D03*
Y1357603D03*
Y1381801D03*
Y1374881D03*
Y1369889D03*
X505780Y1381801D03*
Y1374881D03*
Y1369889D03*
X500824D03*
Y1381801D03*
Y1374881D03*
Y1394087D03*
X505780Y1399079D03*
X500824D03*
X505780Y1394087D03*
X493540Y1386793D03*
Y1394087D03*
Y1399079D03*
X505780Y1386793D03*
X500824D03*
X505780Y1410991D03*
X500824D03*
X505780Y1405999D03*
X500824D03*
X493540D03*
Y1410991D03*
X497432Y1465513D03*
X506093Y1465913D03*
X497432Y1460782D03*
X506093Y1461182D03*
X497432Y1480867D03*
X506093Y1481267D03*
X497432Y1476136D03*
Y1470244D03*
X506093Y1471805D03*
Y1476536D03*
X497432Y1496221D03*
Y1491490D03*
Y1485598D03*
X506093Y1487159D03*
Y1491890D03*
Y1496621D03*
Y1511976D03*
X497432Y1506845D03*
Y1500952D03*
X506093Y1502514D03*
Y1507245D03*
X497432Y1511576D03*
Y1516307D03*
Y1563144D03*
X506093Y1558813D03*
X497432Y1578498D03*
X506093Y1578898D03*
X497432Y1567875D03*
Y1572606D03*
X506093Y1574167D03*
Y1568275D03*
Y1563544D03*
X497432Y1587960D03*
X506093Y1589522D03*
Y1583629D03*
X497432Y1593853D03*
X506093Y1594253D03*
X497432Y1583229D03*
X506093Y1604876D03*
Y1598984D03*
X497432Y1609207D03*
X506093Y1609607D03*
X497432Y1598584D03*
Y1603315D03*
Y1613938D03*
Y1618669D03*
X506093Y1614338D03*
X492000Y1644980D03*
X513051Y103037D03*
X513185Y116496D03*
Y109410D03*
Y130670D03*
Y123583D03*
X509251Y137756D03*
X517866Y293796D03*
X515366D03*
X523380Y285690D03*
Y288190D03*
X511342Y311124D03*
X520845Y434508D03*
X516845D03*
X512845D03*
X514608Y445874D03*
X510022Y446352D03*
X523705Y444269D03*
X523583Y447201D03*
X521636Y504699D03*
X516636D03*
X519136D03*
X516338Y516979D03*
X521338D03*
X518838D03*
X512404Y629362D03*
X510215Y627948D03*
X511990Y686365D03*
X518001Y694940D03*
X522410Y694881D03*
X518067Y699378D03*
X518530Y703584D03*
X522628Y703884D03*
X508237Y723585D03*
X512502Y738539D03*
X516953Y738575D03*
X521909D03*
X520159Y758832D03*
X509063Y782867D03*
X517194Y773232D03*
X522316Y793574D03*
X509316Y793224D03*
X508130Y787488D03*
X521178Y814001D03*
X521565Y820931D03*
X520720Y846133D03*
X517832Y834558D03*
X508049Y877789D03*
X523272Y880067D03*
X509428Y888390D03*
X521115Y897500D03*
X511025Y911443D03*
X509673Y900295D03*
X516256Y939157D03*
X514886Y952189D03*
X519792Y1031271D03*
X517702Y1098518D03*
X512450Y1098428D03*
X522890Y1098767D03*
X514946Y1123101D03*
X517446D03*
X522846Y1129301D03*
X515346Y1125801D03*
X517846D03*
X510346Y1129301D03*
X512846D03*
X515346D03*
X517846D03*
X520346Y1125801D03*
X522846D03*
X520346Y1129301D03*
X518210Y1155213D03*
Y1152713D03*
X508810D03*
Y1155213D03*
X520751Y1204617D03*
X523066Y1200821D03*
Y1198321D03*
X520751Y1207117D03*
Y1209617D03*
Y1212117D03*
X513064Y1345691D03*
X518020Y1350683D03*
X513064D03*
X518020Y1345691D03*
Y1357603D03*
X513064Y1362595D03*
Y1357603D03*
X518020Y1362595D03*
X513064Y1369889D03*
Y1381801D03*
Y1374881D03*
X518020Y1369889D03*
Y1381801D03*
Y1374881D03*
Y1394087D03*
Y1399079D03*
X513064Y1394087D03*
Y1399079D03*
Y1386793D03*
X518020D03*
Y1405999D03*
Y1410991D03*
X513064D03*
Y1405999D03*
X514755Y1460782D03*
Y1465513D03*
Y1480867D03*
Y1476136D03*
Y1470244D03*
Y1491490D03*
Y1485598D03*
Y1496221D03*
Y1511576D03*
Y1506845D03*
Y1500952D03*
Y1516307D03*
Y1563144D03*
Y1567875D03*
Y1572606D03*
Y1578498D03*
Y1593853D03*
Y1583229D03*
Y1587960D03*
Y1603315D03*
Y1609207D03*
Y1598584D03*
Y1613938D03*
Y1618669D03*
X512000Y1644980D03*
X526468Y94017D03*
X534468D03*
X538477D03*
X530468D03*
X530596Y115401D03*
X535588Y110445D03*
Y115401D03*
X530596Y110445D03*
Y124618D03*
Y129574D03*
X535588Y124618D03*
Y129574D03*
X528509Y151540D03*
X538659Y184619D03*
X532159Y191941D03*
X532026Y188727D03*
X528783Y226141D03*
X525983D03*
X533853Y256535D03*
X525880Y285690D03*
X528680D03*
X525880Y288190D03*
X528680D03*
X532906Y290755D03*
X536906D03*
X540906D03*
X524206Y354119D03*
X533027Y351836D03*
X530215Y364422D03*
X535142Y397552D03*
X532936Y519544D03*
X527936D03*
X525436D03*
X530436D03*
X538826Y633450D03*
X526756Y636005D03*
Y633205D03*
X538826Y636250D03*
Y639050D03*
X526756Y638805D03*
X524653Y643595D03*
X534940Y684489D03*
X539111Y681459D03*
X526956Y694959D03*
X526951Y699443D03*
X535387Y712617D03*
X526933Y703820D03*
X532628Y720776D03*
X526276Y721339D03*
X539763Y734097D03*
X534807D03*
X531763Y739097D03*
X526807D03*
X532450Y767474D03*
X532278Y762736D03*
X531501Y792331D03*
X531260Y794934D03*
X531666Y815724D03*
X531313Y822693D03*
X527733Y847026D03*
X527346Y911458D03*
X528674Y964851D03*
X527046Y1131935D03*
Y1139435D03*
Y1134435D03*
Y1136935D03*
X528274Y1152684D03*
X527046Y1146935D03*
Y1144435D03*
Y1141935D03*
X525304Y1345691D03*
X530260D03*
X537544Y1350683D03*
X525304D03*
X530260D03*
X537544Y1345691D03*
Y1357603D03*
X525304Y1362595D03*
X530260D03*
X525304Y1357603D03*
X530260D03*
X537544Y1362595D03*
Y1374881D03*
X525304Y1369889D03*
Y1381801D03*
Y1374881D03*
X530260Y1369889D03*
Y1381801D03*
Y1374881D03*
X537544Y1369889D03*
Y1381801D03*
Y1399079D03*
Y1394087D03*
X530260D03*
Y1399079D03*
X525304Y1394087D03*
Y1399079D03*
X537544Y1386793D03*
X525304D03*
X530260D03*
X537544Y1410991D03*
Y1405999D03*
X530260D03*
X525304D03*
X530260Y1410991D03*
X525304D03*
X532000Y1644980D03*
X543545Y84140D03*
Y80140D03*
Y76140D03*
X540998Y117557D03*
X545990D03*
Y122513D03*
Y131731D03*
X540998Y122513D03*
Y131731D03*
X544089Y146461D03*
X545990Y136687D03*
X540998D03*
X542991Y152367D03*
X549374Y180527D03*
X544691Y180572D03*
X553097Y192421D03*
X549329Y185121D03*
X544691Y185165D03*
X540639Y206760D03*
X541853Y256535D03*
X542883Y279208D03*
X546987Y281307D03*
X541644Y389047D03*
X553731Y388487D03*
X541706Y381723D03*
X552905Y430829D03*
X550274Y658676D03*
X556574Y684031D03*
Y700031D03*
Y688987D03*
Y716031D03*
Y704987D03*
Y720987D03*
X552384Y762892D03*
X552188Y766577D03*
X553871Y811298D03*
X545741Y804149D03*
X548464Y823156D03*
X540807Y816556D03*
X541129Y828335D03*
Y838865D03*
X545981Y846389D03*
X549241Y841388D03*
X545237Y850319D03*
X548521Y877859D03*
Y874859D03*
X545144Y909025D03*
X544793Y899220D03*
X548215Y1006560D03*
X552923Y997860D03*
X541766Y1018368D03*
X557681Y1035088D03*
X554740Y1345597D03*
X542500Y1345691D03*
X549784Y1345597D03*
X542500Y1350683D03*
X549784D03*
X554740D03*
Y1362595D03*
Y1357603D03*
X542500Y1362595D03*
X549784D03*
X542500Y1357603D03*
X549784D03*
X554740Y1381801D03*
Y1374881D03*
X542500D03*
X549784Y1369889D03*
Y1381801D03*
Y1374881D03*
X542500Y1369889D03*
Y1381801D03*
X554740Y1369889D03*
Y1399079D03*
Y1393993D03*
X542500Y1399079D03*
X549784Y1393993D03*
Y1399079D03*
X542500Y1394087D03*
X554740Y1386793D03*
X549784D03*
X542500D03*
X554740Y1410991D03*
Y1405999D03*
X542500Y1410991D03*
X549784D03*
X542500Y1405999D03*
X549784D03*
X552000Y1644980D03*
X566287Y60922D03*
X561123Y55513D03*
X563224Y96813D03*
X558316Y91951D03*
X556920Y117261D03*
X567100Y110784D03*
X564451Y113394D03*
X567290Y130898D03*
X568841Y134579D03*
X564627Y180665D03*
Y172665D03*
X569969Y195176D03*
X564659Y212864D03*
Y200864D03*
X569829Y203393D03*
X564659Y221864D03*
Y216864D03*
X566416Y252371D03*
X570634Y375453D03*
X559074Y696987D03*
Y692031D03*
Y712987D03*
Y708031D03*
X561886Y728138D03*
X559625Y739609D03*
X557813Y747814D03*
X570578Y749800D03*
X570695Y767052D03*
X564276Y776701D03*
X558241Y796389D03*
X569186Y787332D03*
X561401Y811242D03*
X567316Y806224D03*
X561061Y803606D03*
X563099Y829943D03*
X567316Y827724D03*
X559741Y822149D03*
X572171Y842346D03*
X559196Y846296D03*
X569577Y886913D03*
X560814Y901022D03*
X564923Y997860D03*
X560923D03*
X568923D03*
X556923D03*
X571857Y1009354D03*
X565451Y1035102D03*
X569520Y1102091D03*
X560211D03*
X566020D03*
X569520Y1114691D03*
X566020D03*
X560211D03*
X569520Y1139891D03*
X566020D03*
X560211D03*
X566020Y1127291D03*
X560211D03*
X569520D03*
X566020Y1152491D03*
X560211D03*
X569520D03*
X566020Y1165091D03*
X560211D03*
X569520D03*
X560211Y1177691D03*
X566020D03*
X569520D03*
X566502Y1202103D03*
X569882Y1223749D03*
X562024Y1350683D03*
Y1345691D03*
X566980D03*
Y1350683D03*
X562024Y1357603D03*
X566980D03*
Y1362595D03*
X562024D03*
Y1369889D03*
Y1381801D03*
Y1374881D03*
X566980Y1369889D03*
Y1381801D03*
Y1374881D03*
Y1399079D03*
Y1394087D03*
X562024Y1399079D03*
Y1394087D03*
X566980Y1386793D03*
X562024D03*
X566980Y1410991D03*
X562024D03*
X566980Y1405999D03*
X562024D03*
X565600Y1530800D03*
X569349Y1541947D03*
X560635Y1543531D03*
X566800Y1541800D03*
X582686Y109172D03*
X579686D03*
X581693Y106495D03*
X585437Y116497D03*
X574694Y133298D03*
X585437Y123584D03*
Y130670D03*
X581427Y146012D03*
X583333Y141228D03*
X585437Y137757D03*
X586221Y150847D03*
X588189Y247292D03*
X580898Y253198D03*
X581487Y336676D03*
X573805Y728301D03*
X574620Y772724D03*
X584624Y781850D03*
X581001Y814123D03*
X579758Y817753D03*
X579827Y884000D03*
X579251Y903364D03*
X582706Y908959D03*
X580923Y997860D03*
X576923D03*
X588923D03*
X577666Y1009354D03*
X581166D03*
X572923Y997860D03*
X584923D03*
X581166Y1021954D03*
X577666D03*
X578298Y1215195D03*
X584024Y1209607D03*
X587689Y1505724D03*
X583661Y1529142D03*
X573784Y1530646D03*
X575332Y1523740D03*
X583800Y1518000D03*
X583740Y1520640D03*
X587858Y1517942D03*
X577645Y1540982D03*
X580700Y1544100D03*
X592737Y109410D03*
X590237Y116497D03*
X592737D03*
X597437Y102323D03*
Y109410D03*
Y116496D03*
Y123583D03*
Y130670D03*
X592737Y123583D03*
X590237Y123584D03*
Y130670D03*
X592737D03*
X597437Y137756D03*
X590237Y137757D03*
X590178Y309760D03*
X593690Y450750D03*
X597872Y512743D03*
X592880D03*
X597789Y536382D03*
X602756Y597580D03*
X604979Y599588D03*
X604241Y589556D03*
X604180Y592354D03*
X602695Y594668D03*
X604982Y596095D03*
X605011Y615600D03*
X604979Y607588D03*
X592238Y880612D03*
X597129Y913386D03*
X602385Y940920D03*
X596923Y997860D03*
X592923D03*
X604923D03*
X600923D03*
X602603Y1012354D03*
Y1024954D03*
X604405Y1034870D03*
X591898Y1035011D03*
X590957Y1105091D03*
Y1117691D03*
Y1130291D03*
Y1155491D03*
Y1142891D03*
Y1168091D03*
Y1180691D03*
X592978Y1514812D03*
X591858Y1523542D03*
X598800Y1546400D03*
X605899Y80384D03*
Y82984D03*
Y77784D03*
Y75184D03*
X608453Y92849D03*
X605899Y85584D03*
X615413Y103037D03*
X615547Y116496D03*
Y109410D03*
Y130670D03*
Y123583D03*
X612138Y137756D03*
X617728Y293796D03*
X620228D03*
X614461Y555234D03*
X614176Y562003D03*
X609472Y634946D03*
X612489Y941024D03*
X616923Y997860D03*
X608923D03*
X620151Y1040363D03*
X619086Y1056453D03*
X620715Y1046785D03*
X612000Y1644980D03*
X636830Y94017D03*
X628830D03*
X632830D03*
X632958Y110445D03*
Y115401D03*
Y124618D03*
Y129574D03*
X630871Y151540D03*
X634521Y191941D03*
X634388Y188727D03*
X631145Y226141D03*
X628345D03*
X636215Y256535D03*
X631042Y288190D03*
Y285690D03*
X625742Y288190D03*
X628242Y285690D03*
X625742D03*
X628242Y288190D03*
X635268Y290755D03*
X634455Y389154D03*
Y396240D03*
Y403327D03*
Y410413D03*
Y417500D03*
Y424587D03*
Y431673D03*
Y438760D03*
Y445847D03*
Y467539D03*
Y474626D03*
Y488799D03*
Y481713D03*
Y495886D03*
Y511673D03*
Y518760D03*
Y525847D03*
Y532933D03*
Y540020D03*
Y547106D03*
X633736Y602197D03*
X634200Y595108D03*
X622270Y864781D03*
X630466Y1394087D03*
X625510Y1399079D03*
Y1394087D03*
X630466Y1399079D03*
X625510Y1405999D03*
X630466D03*
X625510Y1410991D03*
X630466D03*
X636015Y1460782D03*
X627354Y1461182D03*
X636015Y1465513D03*
X627354Y1465913D03*
Y1456451D03*
X636015Y1476136D03*
X627354Y1476536D03*
X636015Y1480867D03*
X627354Y1481267D03*
Y1471805D03*
X636015Y1470244D03*
X627354Y1487159D03*
X636015Y1485598D03*
Y1491490D03*
X627354Y1491890D03*
X636015Y1496221D03*
X627354Y1496621D03*
Y1507245D03*
Y1511976D03*
X636015Y1511576D03*
X627354Y1502514D03*
X636015Y1500952D03*
Y1506845D03*
Y1516307D03*
X627354Y1558813D03*
X636015Y1563144D03*
X627354Y1563544D03*
X636015Y1567875D03*
X627354Y1568275D03*
Y1574167D03*
X636015Y1572606D03*
Y1578498D03*
X627354Y1578898D03*
X636015Y1593853D03*
X627354Y1594253D03*
X636015Y1583229D03*
X627354Y1583629D03*
Y1589522D03*
X636015Y1587960D03*
X627354Y1604876D03*
X636015Y1603315D03*
Y1598584D03*
X627354Y1598984D03*
X636015Y1609207D03*
X627354Y1609607D03*
X636015Y1618669D03*
Y1613938D03*
X627354Y1614338D03*
X632000Y1644980D03*
X645907Y76140D03*
Y84140D03*
Y80140D03*
X640839Y94017D03*
X643360Y117557D03*
X637950Y110445D03*
Y115401D03*
X648352Y117557D03*
X643360Y122513D03*
Y131731D03*
X637950Y124618D03*
Y129574D03*
X648352Y122513D03*
Y131731D03*
X646451Y146461D03*
X643360Y136687D03*
X648352D03*
X645353Y152367D03*
X647053Y180572D03*
X651736Y180527D03*
X651691Y185121D03*
X647053Y185165D03*
X641021Y184619D03*
X643001Y206760D03*
X644215Y256535D03*
X645245Y279208D03*
X649349Y281307D03*
X639268Y290755D03*
X643268D03*
X649074Y389154D03*
X647604Y396240D03*
X652381Y414823D03*
X651689Y422864D03*
X651759Y429832D03*
X651364Y436447D03*
X653399Y447953D03*
X652566Y467539D03*
X651308Y472772D03*
X652042Y487711D03*
X652155Y479104D03*
X652566Y495886D03*
X647915Y516841D03*
X651166Y510565D03*
X642862Y550123D03*
X642740Y552872D03*
X644494Y572334D03*
X642185Y562443D03*
X643953Y560675D03*
X642726Y574102D03*
X647361Y653161D03*
X648352Y645467D03*
X650958Y677843D03*
X649990Y1350683D03*
Y1345691D03*
Y1357603D03*
Y1362595D03*
Y1381801D03*
X642706Y1374881D03*
Y1381801D03*
Y1369889D03*
X649990Y1374881D03*
Y1369889D03*
X637750Y1374881D03*
Y1381801D03*
Y1369889D03*
X649990Y1399079D03*
Y1394087D03*
X642706Y1386793D03*
X649990D03*
X637750Y1399079D03*
X642706Y1394087D03*
X637750D03*
X642706Y1399079D03*
X637750Y1386793D03*
X649990Y1405999D03*
Y1410991D03*
X637750D03*
X642706D03*
Y1405999D03*
X637750D03*
X653338Y1465513D03*
X644677Y1461182D03*
Y1456451D03*
Y1465913D03*
X653338Y1460782D03*
X644677Y1476536D03*
Y1471805D03*
X653338Y1480867D03*
Y1470244D03*
Y1476136D03*
X644677Y1481267D03*
X653338Y1491490D03*
X644677Y1496621D03*
Y1491890D03*
Y1487159D03*
X653338Y1496221D03*
Y1485598D03*
X644677Y1511976D03*
X653338Y1511576D03*
Y1500952D03*
Y1506845D03*
X644677Y1502514D03*
Y1507245D03*
X653338Y1516307D03*
X644677Y1558813D03*
X653338Y1563144D03*
X644677Y1563544D03*
X653338Y1572606D03*
Y1578498D03*
X644677Y1578898D03*
Y1574167D03*
X653338Y1567875D03*
X644677Y1568275D03*
X653338Y1587960D03*
Y1593853D03*
X644677Y1594253D03*
Y1589522D03*
X653338Y1583229D03*
X644677Y1583629D03*
X653338Y1609207D03*
X644677Y1598984D03*
Y1604876D03*
Y1609607D03*
X653338Y1603315D03*
Y1598584D03*
Y1613938D03*
X644677Y1614338D03*
X653338Y1618669D03*
X652000Y1644980D03*
X668649Y60922D03*
X666209Y57297D03*
X665423Y96853D03*
X660678Y91951D03*
X659282Y117261D03*
X666813Y113394D03*
X669462Y110784D03*
X669056Y133298D03*
X666989Y172665D03*
Y180665D03*
X655459Y192421D03*
X667021Y200864D03*
Y212864D03*
Y221864D03*
Y216864D03*
X668778Y252371D03*
X667666Y389153D03*
X665166Y396240D03*
X667666D03*
X665166Y403327D03*
X667666Y403326D03*
X665166Y410413D03*
X667666D03*
Y417499D03*
X665166Y424586D03*
X667666D03*
X665166Y417500D03*
Y431673D03*
Y438760D03*
X667666D03*
Y431673D03*
X665166Y445847D03*
X667666Y467539D03*
X665166Y474626D03*
X667666D03*
X665166Y488799D03*
X667666D03*
Y481712D03*
X665166D03*
Y495886D03*
X667666Y518760D03*
X665166D03*
X667666Y511673D03*
Y532933D03*
X665166D03*
Y540020D03*
Y525846D03*
X667666D03*
X669546Y560500D03*
X655752Y668885D03*
X661776Y662981D03*
X656157Y691851D03*
X661768Y705043D03*
X654946Y1350683D03*
X662230D03*
X667186D03*
Y1345691D03*
X654946D03*
X662230D03*
X654946Y1357603D03*
Y1362595D03*
X662230Y1357603D03*
Y1362595D03*
X667186Y1357603D03*
Y1362595D03*
X662230Y1369889D03*
X667186Y1374881D03*
Y1381801D03*
Y1369889D03*
X662230Y1374881D03*
Y1381801D03*
X654946D03*
Y1369889D03*
Y1374881D03*
X667186Y1399079D03*
Y1393993D03*
X662230D03*
Y1399079D03*
X655046D03*
Y1394087D03*
X667186Y1386793D03*
X662230D03*
X654946D03*
X667186Y1410991D03*
Y1405999D03*
X662230D03*
Y1410991D03*
X655046Y1405999D03*
Y1410991D03*
X662000Y1456451D03*
Y1465913D03*
Y1461182D03*
Y1481267D03*
Y1476536D03*
Y1471805D03*
Y1496621D03*
Y1491890D03*
Y1487159D03*
Y1511976D03*
Y1502514D03*
Y1507245D03*
Y1563544D03*
Y1558813D03*
Y1568275D03*
Y1578898D03*
Y1574167D03*
Y1594253D03*
Y1589522D03*
Y1583629D03*
Y1598984D03*
Y1604876D03*
Y1609607D03*
Y1614338D03*
X682048Y109172D03*
X685048D03*
X684055Y106495D03*
X677056Y133298D03*
X671203Y134579D03*
X683789Y146012D03*
X685695Y141228D03*
X677331Y195176D03*
X676950Y198883D03*
X683260Y253198D03*
X686012Y339795D03*
X672466Y389153D03*
Y410413D03*
Y396240D03*
Y403326D03*
Y424586D03*
Y417499D03*
Y438760D03*
Y431673D03*
Y467539D03*
Y474626D03*
Y488799D03*
Y481712D03*
Y518760D03*
Y511673D03*
Y525846D03*
Y532933D03*
X681586Y555000D03*
X681011Y543925D03*
X679426Y1350683D03*
X674470Y1345691D03*
X679426D03*
X674470Y1350683D03*
Y1357603D03*
Y1362595D03*
X679426Y1357603D03*
Y1362595D03*
Y1374881D03*
X674470D03*
Y1381801D03*
X679426D03*
Y1369889D03*
X674470D03*
X679426Y1399079D03*
X674470Y1394087D03*
X679426D03*
X674470Y1399079D03*
Y1386793D03*
X679426D03*
X674470Y1405999D03*
X679426D03*
X674470Y1410991D03*
X679426D03*
X679322Y1461182D03*
Y1456451D03*
Y1465913D03*
X670661Y1460782D03*
Y1465513D03*
Y1470244D03*
Y1476136D03*
X679322Y1481267D03*
Y1476536D03*
Y1471805D03*
X670661Y1480867D03*
X679322Y1487159D03*
X670661Y1496221D03*
Y1485598D03*
Y1491490D03*
X679322Y1496621D03*
Y1491890D03*
X670661Y1500952D03*
Y1506845D03*
X679322Y1511976D03*
Y1502514D03*
Y1507245D03*
X670661Y1511576D03*
Y1516307D03*
X679322Y1558813D03*
X670661Y1563144D03*
X679322Y1563544D03*
Y1578898D03*
Y1574167D03*
Y1568275D03*
X670661Y1572606D03*
Y1578498D03*
Y1567875D03*
X679322Y1583629D03*
X670661Y1587960D03*
Y1593853D03*
Y1583229D03*
X679322Y1594253D03*
Y1589522D03*
Y1604876D03*
Y1609607D03*
X670661Y1603315D03*
Y1598584D03*
Y1609207D03*
X679322Y1598984D03*
Y1614338D03*
X670661Y1618669D03*
Y1613938D03*
X672000Y1644980D03*
X695099Y109410D03*
X687799Y116497D03*
X692599D03*
X695099D03*
X699799Y116496D03*
Y109410D03*
Y102323D03*
X687799Y123584D03*
X695099Y123583D03*
X692599Y123584D03*
X687799Y130670D03*
X692599D03*
X695099D03*
X699799Y123583D03*
Y130670D03*
X687799Y137757D03*
X692599D03*
X699799Y137756D03*
X688583Y150847D03*
X690551Y247292D03*
X700164Y636842D03*
X698936Y678462D03*
X702691Y766471D03*
Y753471D03*
X702677Y771159D03*
Y784659D03*
X698950Y1350683D03*
Y1345597D03*
X686710Y1350683D03*
X691666D03*
X686710Y1345691D03*
X691666D03*
X698950Y1362595D03*
Y1357603D03*
X686710D03*
Y1362595D03*
X691666Y1357603D03*
Y1362595D03*
X698950Y1374881D03*
Y1381801D03*
Y1369889D03*
X691666D03*
Y1374881D03*
Y1381801D03*
X686710Y1374881D03*
Y1369889D03*
Y1381801D03*
X698950Y1399079D03*
Y1394087D03*
X686710D03*
Y1399079D03*
X691666Y1394087D03*
Y1399079D03*
X698950Y1386793D03*
X691666D03*
X686710D03*
X698950Y1405999D03*
Y1410991D03*
X686710D03*
X691666D03*
X686710Y1405999D03*
X691666D03*
X696645Y1461183D03*
Y1456452D03*
Y1465914D03*
X687984Y1460782D03*
Y1465513D03*
Y1470244D03*
Y1476136D03*
X696645Y1481268D03*
Y1471806D03*
Y1476537D03*
X687984Y1480867D03*
X696645Y1491891D03*
X687984Y1496221D03*
Y1485598D03*
Y1491490D03*
X696645Y1496622D03*
Y1487160D03*
Y1511977D03*
Y1502515D03*
Y1507246D03*
X687984Y1511576D03*
Y1500952D03*
Y1506845D03*
Y1516307D03*
X696645Y1558813D03*
Y1563544D03*
X687984Y1563144D03*
X696645Y1574167D03*
Y1578898D03*
X687984Y1572606D03*
Y1578498D03*
X696645Y1568275D03*
X687984Y1567875D03*
Y1583229D03*
X696645Y1589522D03*
Y1594253D03*
X687984Y1587960D03*
Y1593853D03*
X696645Y1583629D03*
Y1598984D03*
Y1609607D03*
X687984Y1603315D03*
Y1598584D03*
Y1609207D03*
X696645Y1604876D03*
X687984Y1613938D03*
X696645Y1614338D03*
X687984Y1618669D03*
X692000Y1644980D03*
X718488Y-27642D03*
X718503Y-25127D03*
X708261Y82984D03*
Y80384D03*
Y77784D03*
Y75184D03*
X710815Y92849D03*
X708261Y85584D03*
X717775Y103037D03*
X717909Y116496D03*
Y109410D03*
Y130670D03*
Y123583D03*
X714500Y137756D03*
X713162Y434493D03*
X711764Y449873D03*
X718691Y465492D03*
Y472579D03*
X716191D03*
X711391D03*
X716191Y479666D03*
X718691D03*
X711391D03*
Y486752D03*
X716191D03*
X718691D03*
X711391Y493839D03*
X716191D03*
Y516713D03*
Y523800D03*
X718691D03*
X711391D03*
Y516713D03*
X718691D03*
Y509626D03*
Y530886D03*
X716191D03*
Y537973D03*
X711391Y530886D03*
Y537973D03*
Y566752D03*
X718691Y559665D03*
Y566752D03*
X716191D03*
X711391Y573839D03*
X718691D03*
X716191D03*
X711391Y588013D03*
X718691Y588012D03*
X716191Y588013D03*
X718691Y580926D03*
X716191D03*
X711391D03*
X716191Y602186D03*
X711391D03*
X718691Y602185D03*
Y595099D03*
X711391D03*
X716191D03*
X711391Y609272D03*
X716191D03*
X718691D03*
X716191Y616359D03*
X711391D03*
X706070Y638125D03*
X716656Y646429D03*
X703669Y665140D03*
X716350Y699477D03*
X703604Y699653D03*
X716146Y1350683D03*
X711190D03*
X716146Y1345691D03*
X711190D03*
X703906Y1350683D03*
Y1345597D03*
X716146Y1357603D03*
X711190D03*
Y1362595D03*
X716146D03*
X703906Y1357603D03*
Y1362595D03*
X716146Y1374881D03*
Y1381801D03*
Y1369889D03*
X711190D03*
Y1374881D03*
Y1381801D03*
X703906D03*
Y1369889D03*
Y1374881D03*
X716146Y1399079D03*
X711190D03*
X716146Y1393993D03*
X711190D03*
X703906Y1394087D03*
Y1399079D03*
X716146Y1386793D03*
X711190D03*
X703906D03*
X716146Y1405999D03*
X711190D03*
X716146Y1410991D03*
X711190D03*
X703906Y1405999D03*
Y1410991D03*
X712000Y1644980D03*
X721741Y-27628D03*
X721756Y-25113D03*
X724781Y-26433D03*
X735192Y94017D03*
X731192D03*
X733233Y151540D03*
X736750Y188727D03*
X730707Y226141D03*
X733507D03*
X733404Y285690D03*
X720090Y293796D03*
X722590D03*
X728104Y288190D03*
X730604Y285690D03*
X728104D03*
X730604Y288190D03*
X733404D03*
X731511Y390500D03*
X734606Y379562D03*
X722097Y410394D03*
Y403307D03*
X723491Y458406D03*
Y451319D03*
Y465492D03*
X723315Y462264D03*
X723491Y472579D03*
Y479665D03*
Y486752D03*
Y493839D03*
Y523799D03*
Y516713D03*
Y509626D03*
Y530886D03*
Y537973D03*
Y566752D03*
Y559665D03*
Y573839D03*
Y588012D03*
Y580926D03*
Y595099D03*
Y602185D03*
Y609272D03*
Y616358D03*
X734819Y646429D03*
X725318Y890354D03*
X720373Y940310D03*
X724547Y958287D03*
X723430Y1350683D03*
X728386Y1345691D03*
X723430D03*
X728386Y1350683D03*
Y1357603D03*
Y1362595D03*
X723430Y1357603D03*
Y1362595D03*
X728386Y1381801D03*
Y1374881D03*
Y1369889D03*
X723430D03*
Y1381801D03*
Y1374881D03*
X728386Y1386793D03*
X723430D03*
X728386Y1398985D03*
Y1393993D03*
X723430Y1398985D03*
Y1393993D03*
X728386Y1410897D03*
Y1405905D03*
X723430Y1410897D03*
Y1405905D03*
X732000Y1644980D03*
X748269Y84140D03*
Y76140D03*
Y80140D03*
X743201Y94017D03*
X739192D03*
X750714Y117557D03*
X745722D03*
X740312Y115401D03*
Y110445D03*
X735320D03*
Y115401D03*
X745722Y131731D03*
Y122513D03*
X740312Y129574D03*
Y124618D03*
X735320D03*
Y129574D03*
X750714Y131731D03*
Y122513D03*
Y136687D03*
X745722D03*
X748813Y146461D03*
X747715Y152367D03*
X749415Y180572D03*
Y185165D03*
X743383Y184619D03*
X736883Y191941D03*
X745363Y206760D03*
X738577Y256535D03*
X746577D03*
X747607Y279208D03*
X751711Y281307D03*
X741630Y290755D03*
X737630D03*
X745630D03*
X741161Y381500D03*
X741602Y465492D03*
X741568Y460250D03*
X739333Y470136D03*
X741602Y472579D03*
X741072Y478958D03*
X741602Y486752D03*
Y493839D03*
Y509626D03*
Y516713D03*
X738062Y537973D03*
X740542Y525483D03*
X740463Y532756D03*
X741602Y559665D03*
Y566752D03*
X741452Y579978D03*
X741602Y573839D03*
X741666Y608117D03*
X741000Y771100D03*
X738707Y987952D03*
X745673Y1007009D03*
X747910Y1345691D03*
Y1350683D03*
X735670D03*
X740626D03*
X735670Y1345691D03*
X740626D03*
X747910Y1357603D03*
Y1362595D03*
X735670Y1357603D03*
Y1362595D03*
X740626Y1357603D03*
Y1362595D03*
X747910Y1374881D03*
Y1381801D03*
Y1369889D03*
X740626Y1381801D03*
Y1369889D03*
Y1374881D03*
X735670Y1381801D03*
Y1369889D03*
Y1374881D03*
X747910Y1386793D03*
X735670Y1393993D03*
X740626D03*
Y1398985D03*
X735670D03*
X740626Y1386793D03*
X735670D03*
Y1405905D03*
Y1410897D03*
X740626Y1405905D03*
Y1410897D03*
X742655Y1445733D03*
X747590Y1627871D03*
X765847Y55513D03*
X762065Y117040D03*
X754098Y180527D03*
X757821Y192421D03*
X754053Y185121D03*
X756201Y288345D03*
Y290845D03*
X753701Y288345D03*
Y290845D03*
Y293645D03*
X756201D03*
X763898Y342319D03*
X766344Y393924D03*
Y389912D03*
Y385912D03*
X758038Y381143D03*
X766344Y409924D03*
Y405924D03*
Y401924D03*
X752341Y407148D03*
X756800Y403824D03*
X758381Y395391D03*
X759543Y445787D03*
X755593Y445908D03*
X765106Y1350683D03*
Y1345597D03*
X760150D03*
Y1350683D03*
X752866Y1345691D03*
Y1350683D03*
X765106Y1362595D03*
Y1357603D03*
X760150D03*
Y1362595D03*
X752866Y1357603D03*
Y1362595D03*
X765106Y1374881D03*
Y1381801D03*
Y1369889D03*
X760150Y1374881D03*
Y1381801D03*
Y1369889D03*
X752866Y1374881D03*
Y1381801D03*
Y1369889D03*
X765106Y1386793D03*
X760150D03*
X752866D03*
X766433Y1583713D03*
X752150Y1627871D03*
X762776Y1629415D03*
X752000Y1644980D03*
X771011Y60922D03*
X767929Y96890D03*
X771824Y110784D03*
X769175Y113394D03*
X779418Y133298D03*
X771960Y130898D03*
X773565Y134579D03*
X769351Y172665D03*
Y180665D03*
X769383Y200864D03*
Y212864D03*
Y221864D03*
Y216864D03*
X771140Y252371D03*
X780968Y303839D03*
X772990Y336324D03*
X777569Y353506D03*
X772390Y1350683D03*
X777346D03*
Y1345691D03*
X772390D03*
Y1357603D03*
Y1362595D03*
X777346Y1357603D03*
Y1362595D03*
X777114Y1442270D03*
X778045Y1622545D03*
X782289Y1620109D03*
X773822Y1627418D03*
X772000Y1644980D03*
X784410Y109172D03*
X787410D03*
X794961Y116497D03*
X797461D03*
X790161D03*
X786417Y106495D03*
X797461Y109410D03*
Y123583D03*
X794961Y123584D03*
X790161D03*
X794961Y130670D03*
X797461D03*
X790161D03*
X794961Y137757D03*
X790161D03*
X788057Y141228D03*
X786151Y146012D03*
X793221Y140296D03*
X790945Y150847D03*
X792913Y247292D03*
X785622Y253198D03*
X788522Y290304D03*
X799937Y347340D03*
X791686Y1025440D03*
X794716Y1186071D03*
X792183Y1334030D03*
Y1331230D03*
X789383Y1334030D03*
Y1331230D03*
X794506Y1411307D03*
X793723Y1468071D03*
X793564Y1642682D03*
X810623Y77784D03*
Y82984D03*
Y80384D03*
Y75184D03*
X813177Y92849D03*
X810623Y85584D03*
X802161Y116496D03*
Y109410D03*
Y102323D03*
Y130670D03*
Y123583D03*
Y137756D03*
X816364Y486870D03*
X813864D03*
X813566Y744187D03*
X812661Y810032D03*
X812980Y824166D03*
X816016Y838036D03*
X813182Y852800D03*
X814731Y889365D03*
X812811Y908162D03*
X809682Y1133284D03*
X806787Y1148000D03*
X815034Y1159455D03*
X809623Y1160168D03*
X809393Y1187252D03*
X807487Y1193019D03*
X815487D03*
X811487D03*
X817446Y1210089D03*
X800627Y1392748D03*
X800703Y1426779D03*
X811457Y1639797D03*
X820137Y103037D03*
X820271Y116496D03*
Y109410D03*
Y130670D03*
Y123583D03*
X816637Y137756D03*
X824952Y293796D03*
X822452D03*
X830466Y285690D03*
Y288190D03*
X825792Y305225D03*
X823529Y467189D03*
X830318Y674164D03*
X829784Y713939D03*
X832284Y731216D03*
X830484Y746701D03*
X819993Y754109D03*
X817500Y760000D03*
X820547Y780314D03*
X826925Y769000D03*
X820500Y777500D03*
X826925Y787000D03*
X820500Y792000D03*
X818500Y814000D03*
X820432Y800529D03*
X826925Y805000D03*
Y823000D03*
X826165Y863000D03*
X819134Y863607D03*
X829000Y852000D03*
X825686Y869496D03*
X826797Y883756D03*
X825508Y913869D03*
X822462Y915095D03*
X818347Y939610D03*
X828193Y949324D03*
X832432Y977982D03*
X832711Y993268D03*
X828385Y1120599D03*
X817006Y1133027D03*
X822006Y1130208D03*
X825744Y1146937D03*
X823220Y1162817D03*
X823487Y1193019D03*
X819487D03*
X826612Y1219254D03*
X819522Y1212164D03*
X821816Y1214458D03*
X832084Y1461072D03*
X831457Y1639797D03*
X844781Y-65613D03*
X841756Y-64293D03*
X838503Y-64307D03*
X841741Y-66808D03*
X838488Y-66822D03*
X841554Y94017D03*
X837554D03*
X845563D03*
X833554D03*
X837682Y110445D03*
Y115401D03*
X848084Y117557D03*
X842674Y115401D03*
Y110445D03*
Y129574D03*
Y124618D03*
X837682D03*
Y129574D03*
X848084Y131731D03*
Y122513D03*
Y136687D03*
X839112Y188727D03*
X839245Y191941D03*
X845745Y184619D03*
X847725Y206760D03*
X833069Y226141D03*
X835869D03*
X848939Y256535D03*
X840939D03*
X832966Y288190D03*
Y285690D03*
X835766Y288190D03*
Y285690D03*
X843992Y290755D03*
X839992D03*
X847992D03*
X835236Y533174D03*
X845729Y661263D03*
X836503Y667845D03*
X845784Y713939D03*
X848284Y731181D03*
X846484Y746701D03*
X841500Y758161D03*
Y776161D03*
Y794161D03*
Y812161D03*
X838685Y832987D03*
X845654Y895437D03*
X833870Y881860D03*
X839381Y915839D03*
X839122Y939655D03*
X843734Y1008778D03*
X848520Y1016855D03*
X850631Y84140D03*
Y80140D03*
Y76140D03*
X864006Y117261D03*
X853076Y117557D03*
Y131731D03*
Y122513D03*
Y136687D03*
X851777Y180572D03*
X856460Y180527D03*
X860183Y192421D03*
X851777Y185165D03*
X856415Y185121D03*
X849969Y279208D03*
X854073Y281307D03*
X864920Y343168D03*
X854086Y385000D03*
X858586D03*
X850733Y461382D03*
X850832Y473382D03*
X850738Y477382D03*
X850909Y482382D03*
X853900Y627700D03*
X858202Y646330D03*
X851111Y656635D03*
X856145Y677887D03*
X855646Y685230D03*
X858186Y713170D03*
X867227Y722060D03*
X849500Y761000D03*
X864575Y770500D03*
X849500Y779000D03*
X864575Y788500D03*
X849500Y797000D03*
Y815000D03*
X864575Y806500D03*
X865004Y831273D03*
X864464Y828503D03*
X864575Y824500D03*
X851782Y823720D03*
X851161Y855205D03*
X856628Y915242D03*
X864253D03*
X849600Y915266D03*
X855867Y935540D03*
X849088Y951081D03*
X852247Y1009529D03*
X849996Y1091073D03*
X850023Y1095179D03*
X863342Y1120636D03*
X855542D03*
X858142D03*
X860842D03*
X863442Y1130336D03*
X858242D03*
X855642D03*
X860942D03*
Y1139336D03*
X863442D03*
X861119Y1148080D03*
X863619D03*
X851457Y1639797D03*
X873373Y60922D03*
X868209Y55513D03*
X870395Y96738D03*
X865402Y91951D03*
X871713Y172665D03*
Y180665D03*
X871745Y200864D03*
Y212864D03*
Y216864D03*
Y221864D03*
X876246Y302754D03*
X869313Y688486D03*
X872069Y700894D03*
X876286Y686970D03*
X880501Y710611D03*
X873021Y715729D03*
X877616Y749484D03*
X873318Y744597D03*
X873250Y798750D03*
X872700Y816615D03*
X872628Y915242D03*
X880628D03*
X876481Y941126D03*
X868908Y933640D03*
X867199Y949372D03*
X869390Y978003D03*
X878004Y1224406D03*
X883142Y1259935D03*
X875700Y1299700D03*
X871457Y1639797D03*
X886011Y154100D03*
X895780Y237517D03*
Y232634D03*
X886261Y252090D03*
X885741Y261150D03*
X894844Y418983D03*
X889219Y426952D03*
X887770Y415290D03*
X890270D03*
X897344Y418983D03*
X894519Y426952D03*
X889596Y437264D03*
X896388Y437614D03*
X887096Y437264D03*
X892019Y426952D03*
X897019D03*
X882891Y536122D03*
X896449Y550863D03*
X893949Y550363D03*
X882949Y557363D03*
X887949Y608863D03*
X894449Y606363D03*
X884903Y694119D03*
X886836Y729778D03*
X889083Y780371D03*
X888545Y785528D03*
X888514Y797602D03*
X891916Y808965D03*
X882609Y994245D03*
X897056Y1091391D03*
X891055Y1095407D03*
X897056Y1095984D03*
X884906Y1102760D03*
X884890Y1098724D03*
X893190Y1208069D03*
X894887Y1227209D03*
X891003Y1292765D03*
X890738Y1311132D03*
X891457Y1639797D03*
X898813Y146461D03*
X897715Y152367D03*
X898851Y231496D03*
Y238583D03*
Y245669D03*
X910977Y238583D03*
X898851Y259843D03*
X898576Y253056D03*
X910977Y252756D03*
Y257480D03*
X898851Y274016D03*
X910977Y266929D03*
X898851D03*
X912786Y306697D03*
X901848Y307782D03*
Y312738D03*
X909417Y323302D03*
X912085Y332335D03*
X898888Y437614D03*
X906996Y530707D03*
X902459Y530755D03*
X911630Y543998D03*
X910578Y550186D03*
X909362Y555614D03*
X898156Y554812D03*
X909024Y586768D03*
X908730Y619120D03*
X913686D03*
X899898Y619040D03*
X904854D03*
X910036Y702285D03*
X910753Y715864D03*
X912864Y864189D03*
Y870488D03*
Y867338D03*
X899693Y895207D03*
X904833Y915340D03*
X912628Y928101D03*
X911355Y944909D03*
X906710Y962433D03*
X906909Y951494D03*
X909296Y1020224D03*
X909300Y1014639D03*
X901739Y1091346D03*
X897815Y1078042D03*
X901366Y1078069D03*
X901694Y1095940D03*
X911071Y1123803D03*
X905771D03*
X903171D03*
X908371D03*
X910971Y1114103D03*
X908271D03*
X903071D03*
X905671D03*
X911699Y1129488D03*
X909041Y1126328D03*
X911641D03*
X903908Y1132870D03*
X904063Y1135946D03*
X901940Y1236799D03*
Y1229899D03*
Y1232399D03*
Y1246199D03*
Y1243699D03*
Y1239299D03*
X904703Y1297398D03*
X911457Y1639797D03*
X919175Y113394D03*
X921824Y110784D03*
X921418Y133298D03*
X929418D03*
X923565Y134579D03*
X920142Y308501D03*
X926801Y323302D03*
X923902Y332411D03*
X924600Y533706D03*
X920961Y550075D03*
X915949Y563363D03*
X915712Y613792D03*
X915194Y666671D03*
X928043Y677795D03*
X917286Y679625D03*
X924932Y701051D03*
X920628Y928101D03*
X928628D03*
X916628D03*
X924628D03*
X924487Y951244D03*
X918648Y964717D03*
X915490Y969886D03*
X916749Y1080659D03*
Y1088659D03*
X917110Y1101902D03*
X927598Y1120636D03*
X924898D03*
X914661Y1132612D03*
X914299Y1129488D03*
X914241Y1126328D03*
X924919Y1130336D03*
X927619D03*
X924919Y1139336D03*
X927419D03*
X925097Y1147708D03*
X927597D03*
X927146Y1328597D03*
Y1323641D03*
X929094Y1542353D03*
Y1545353D03*
X926041Y1554503D03*
Y1551503D03*
Y1548503D03*
Y1557503D03*
Y1560503D03*
X944961Y116497D03*
X934410Y109172D03*
X936417Y106495D03*
X937410Y109172D03*
X940161Y116497D03*
Y123584D03*
X944961D03*
X940161Y130670D03*
X944961D03*
X940161Y137757D03*
X944961D03*
X936151Y146012D03*
X938057Y141228D03*
X940945Y150847D03*
X932388Y330517D03*
X932622Y336817D03*
X944694Y352192D03*
X931627Y561578D03*
Y565578D03*
X943825Y581222D03*
Y591215D03*
X935281Y677795D03*
X945626Y789761D03*
X932000Y831000D03*
X942634Y886520D03*
X933700Y887508D03*
X944839Y902400D03*
X938188Y900853D03*
X944628Y928101D03*
X932628D03*
X936628D03*
X940497D03*
X941981Y1224406D03*
X947119Y1259935D03*
X933254Y1308273D03*
X940848Y1310181D03*
X930441Y1455039D03*
Y1458039D03*
Y1464039D03*
Y1461039D03*
Y1467039D03*
X938670Y1510528D03*
X941270D03*
Y1505328D03*
X938670D03*
X940170Y1507928D03*
X943870Y1510528D03*
Y1505328D03*
X945370Y1507928D03*
X942770D03*
X935094Y1542353D03*
X932094D03*
X935094Y1545353D03*
X932094D03*
X938094Y1542353D03*
Y1545353D03*
X941094Y1542353D03*
X944094D03*
X941094Y1545353D03*
X944094D03*
X931457Y1639797D03*
X960623Y82984D03*
Y77784D03*
Y80384D03*
Y75184D03*
Y85584D03*
X947461Y116497D03*
X952161Y116496D03*
Y109410D03*
Y102323D03*
X947461Y109410D03*
Y130670D03*
X952161D03*
Y123583D03*
X947461D03*
X952161Y137756D03*
X949443Y208206D03*
X949579Y330517D03*
X949813Y336817D03*
X956863Y451466D03*
X953816Y555194D03*
X951016D03*
X953816Y571194D03*
X951016D03*
X953816Y563194D03*
X951016D03*
X946625Y581222D03*
X949425D03*
Y591215D03*
X946625D03*
X948427Y611091D03*
X957551Y698251D03*
X954023Y725336D03*
X951195Y727165D03*
X952681Y735256D03*
X956323Y748412D03*
X957474Y764426D03*
X955086Y779798D03*
X956051Y793937D03*
X947735Y824921D03*
X948935Y835800D03*
X954700Y842700D03*
X947735Y854935D03*
X953091Y857440D03*
X953217Y861440D03*
X955967Y860376D03*
X946700Y849200D03*
X950251Y874268D03*
X950291Y870240D03*
Y866240D03*
X953145Y874240D03*
X952738Y886624D03*
X953587Y902814D03*
X961479Y927643D03*
X957671Y991564D03*
X946642Y991361D03*
X961033Y1091391D03*
X948883Y1102760D03*
X948867Y1098724D03*
X955032Y1095407D03*
X961033Y1095984D03*
X957167Y1208069D03*
X958864Y1227209D03*
X949970Y1321749D03*
X952070Y1367717D03*
X949070D03*
X956238Y1455139D03*
Y1458139D03*
Y1461139D03*
Y1464139D03*
X952676Y1461039D03*
Y1464039D03*
Y1458039D03*
Y1455039D03*
X956238Y1467139D03*
Y1469902D03*
X952676Y1467039D03*
X946470Y1510528D03*
Y1505328D03*
X947094Y1545353D03*
Y1542353D03*
X951457Y1639797D03*
X963177Y92849D03*
X970137Y103037D03*
X970271Y116496D03*
Y109410D03*
Y130670D03*
Y123583D03*
X966347Y137756D03*
X974952Y293796D03*
X972452D03*
X972147Y323681D03*
X975932Y437508D03*
X971932D03*
X962769Y458466D03*
X973695Y448874D03*
X969109Y449352D03*
X978723Y504699D03*
X976223D03*
X973723D03*
X978425Y516979D03*
X973425D03*
X975925D03*
X967302Y627948D03*
X969491Y629362D03*
X963187Y667620D03*
X973138Y667621D03*
X978059Y747438D03*
X976764Y786563D03*
X964070Y807686D03*
Y813006D03*
X977218Y802178D03*
X964036Y818961D03*
X968319Y826191D03*
X976635Y835018D03*
X976800Y838011D03*
X974282D03*
X976902Y847135D03*
X971808Y851242D03*
X975925Y854783D03*
X978201Y897500D03*
X969806Y993033D03*
X965716Y1091346D03*
X965671Y1095940D03*
X967148Y1123803D03*
X969748D03*
X969648Y1114103D03*
X967048D03*
X972348Y1123803D03*
X975048D03*
X972248Y1114103D03*
X974948D03*
X970485Y1132870D03*
X967885D03*
X968874Y1145169D03*
X966374D03*
X965917Y1236799D03*
Y1229899D03*
Y1232399D03*
Y1246199D03*
Y1243699D03*
Y1239299D03*
X978727Y1284908D03*
X971467Y1509515D03*
X974067D03*
X972567Y1512115D03*
X969967D03*
X976667Y1509515D03*
X977767Y1506915D03*
X975167D03*
X969967D03*
X972567D03*
X975167Y1512115D03*
X977767D03*
X971140Y1514693D03*
X968540D03*
X973740D03*
X976340D03*
X971457Y1639797D03*
X983554Y94017D03*
X987554D03*
X991554D03*
X987682Y115401D03*
X992674D03*
Y110445D03*
X987682D03*
X992674Y124618D03*
X987682D03*
Y129574D03*
X992674D03*
X985595Y151540D03*
X989245Y191941D03*
X989112Y188727D03*
X983069Y226141D03*
X985869D03*
X990939Y256535D03*
X985766Y288190D03*
X982966D03*
X985766Y285690D03*
X982966D03*
X980466Y288190D03*
Y285690D03*
X993992Y290755D03*
X989992D03*
X979932Y437508D03*
X982792Y447269D03*
X982670Y450201D03*
X989936Y519531D03*
X987436D03*
X982436D03*
X984936D03*
X983843Y633205D03*
Y636005D03*
Y638805D03*
X984307Y748432D03*
X985030Y781204D03*
X988329Y781445D03*
X991990Y773974D03*
X984963Y785387D03*
X979313Y814316D03*
X987903Y818645D03*
X993061Y833135D03*
X979203Y837159D03*
X988820Y858903D03*
X980529Y879097D03*
X988231Y878203D03*
X984892Y868720D03*
X987790Y896596D03*
X995133Y888503D03*
X982787Y899757D03*
X988461Y1013841D03*
X980726Y1080659D03*
Y1088659D03*
X981087Y1101902D03*
X988389Y1302558D03*
X980501Y1369685D03*
X983501D03*
X979538Y1464039D03*
Y1461039D03*
Y1458039D03*
Y1455039D03*
Y1467039D03*
Y1469802D03*
X979267Y1509515D03*
X984467D03*
X981867D03*
X985567Y1512115D03*
Y1506915D03*
X980367D03*
X982967D03*
Y1512115D03*
X980367D03*
X989667Y1509515D03*
X992267D03*
X987067D03*
X988167Y1512115D03*
X990767D03*
Y1506915D03*
X988167D03*
X984140Y1514693D03*
X981540D03*
X978940D03*
X986740D03*
X989340D03*
X991457Y1639797D03*
X1005256Y-25113D03*
X1002003Y-25027D03*
X1005241Y-27628D03*
X1001988Y-27542D03*
X1008281Y-26433D03*
X1000631Y84140D03*
Y76140D03*
Y80140D03*
X995563Y94017D03*
X1003076Y117557D03*
X998084D03*
X1003076Y122513D03*
Y131731D03*
X998084Y122513D03*
Y131731D03*
X1001175Y146461D03*
X1003076Y136687D03*
X998084D03*
X1000077Y152367D03*
X1001777Y180572D03*
X1006460Y180527D03*
X1010183Y192421D03*
X1001777Y185165D03*
X1006415Y185121D03*
X995745Y184619D03*
X997725Y206760D03*
X998939Y256535D03*
X999826Y278734D03*
X1004061Y280808D03*
X997992Y290755D03*
X1004544Y318050D03*
X1004933Y314535D03*
X997921Y333654D03*
X995913Y633450D03*
Y636250D03*
Y639050D03*
X1008342Y761735D03*
X1003539Y762632D03*
X1002834Y777394D03*
X1006053Y787745D03*
X999825Y819488D03*
X1002887Y834342D03*
X1000369D03*
X1005607Y874859D03*
Y877859D03*
X1002930Y906785D03*
X1010009Y998100D03*
X1005301Y1006560D03*
X999700Y1018400D03*
X1008312Y1363533D03*
X1008452Y1376752D03*
X1008483Y1372734D03*
X1006211Y1397662D03*
X1009338Y1391597D03*
Y1388597D03*
X1002538Y1463939D03*
Y1460939D03*
Y1457939D03*
Y1454939D03*
Y1466939D03*
Y1469702D03*
X1008549Y1509815D03*
X1007049Y1507215D03*
X1011149Y1509815D03*
X1009649Y1507215D03*
Y1512415D03*
X1007049D03*
X1008222Y1514993D03*
X1005622D03*
X1010822D03*
X1023373Y60922D03*
X1018209Y55513D03*
X1020254Y97068D03*
X1014006Y117261D03*
X1021537Y113394D03*
X1024186Y110784D03*
X1024289Y130898D03*
X1025927Y134579D03*
X1021713Y180665D03*
Y172665D03*
X1026915Y203393D03*
X1021745Y212864D03*
Y200864D03*
Y221864D03*
Y216864D03*
X1023502Y252371D03*
X1013354Y323362D03*
X1013327Y327453D03*
X1013318Y333190D03*
X1022845Y340944D03*
X1013313Y339909D03*
X1015195Y428305D03*
X1015804Y760454D03*
X1026090Y770943D03*
X1019375Y783056D03*
X1018044Y793592D03*
X1015800Y807535D03*
X1014587Y802788D03*
X1025859Y802275D03*
X1020703Y833659D03*
X1021221Y848712D03*
X1025219Y842155D03*
X1025239Y845070D03*
X1022009Y997860D03*
X1018009D03*
X1026009D03*
X1014009D03*
X1014767Y1035088D03*
X1022594Y1035114D03*
X1017297Y1102091D03*
X1026606Y1102591D03*
X1023106Y1102091D03*
X1017297Y1114691D03*
X1023106D03*
X1026606D03*
X1023106Y1127291D03*
X1026606D03*
X1017297Y1139891D03*
X1023106D03*
X1026606D03*
X1017297Y1127291D03*
X1026606Y1152491D03*
X1017297D03*
X1023106D03*
X1017297Y1165091D03*
X1023106D03*
X1026606D03*
X1017297Y1177691D03*
X1023106D03*
X1026606D03*
X1022420Y1203204D03*
X1026968Y1223749D03*
X1025434Y1320606D03*
X1011829Y1347471D03*
Y1342515D03*
X1015286Y1344924D03*
X1021623Y1373216D03*
X1012338Y1388597D03*
Y1391597D03*
X1015338D03*
Y1388597D03*
X1021338D03*
Y1391597D03*
X1018338D03*
Y1388597D03*
X1027338D03*
Y1391597D03*
X1024338D03*
Y1388597D03*
X1025138Y1463839D03*
Y1460839D03*
Y1457839D03*
Y1454839D03*
Y1466839D03*
Y1469602D03*
X1013749Y1509815D03*
X1016349D03*
X1021549D03*
X1018949D03*
X1024149D03*
X1022649Y1507215D03*
X1025249D03*
X1017449D03*
X1020049D03*
X1014849D03*
X1012249D03*
X1026749Y1509815D03*
X1012249Y1512415D03*
X1014849D03*
X1025249D03*
X1022649D03*
X1020049D03*
X1017449D03*
X1013422Y1514993D03*
X1023822D03*
X1021222D03*
X1018622D03*
X1016022D03*
X1026422D03*
X1011457Y1639797D03*
X1036772Y109172D03*
X1039772D03*
X1038779Y106495D03*
X1042523Y116497D03*
X1031780Y133298D03*
X1042523Y130670D03*
Y123584D03*
X1038513Y146012D03*
X1040419Y141228D03*
X1042523Y137757D03*
X1043307Y150847D03*
X1037984Y253198D03*
X1031354Y325901D03*
X1031382Y340947D03*
X1031310Y337888D03*
X1031377Y333671D03*
X1031362Y329268D03*
X1038796Y763272D03*
X1042880Y794924D03*
X1028155Y879413D03*
X1030300Y881400D03*
X1043252Y902501D03*
X1030009Y997860D03*
X1034009D03*
X1038252Y1009354D03*
X1034752D03*
X1028943D03*
X1042009Y997860D03*
X1038009D03*
X1034752Y1021954D03*
X1038252D03*
X1043553Y1035384D03*
X1040600Y1210600D03*
X1035384Y1215195D03*
X1034513Y1333665D03*
X1042586Y1345824D03*
X1030338Y1391597D03*
Y1388597D03*
X1029349Y1509815D03*
X1027849Y1507215D03*
Y1512415D03*
X1031457Y1639797D03*
X1049823Y109410D03*
X1054523Y116496D03*
Y109410D03*
Y102323D03*
X1049823Y116497D03*
X1047323D03*
X1049823Y130670D03*
X1047323D03*
Y123584D03*
X1049823Y123583D03*
X1054523Y130670D03*
Y123583D03*
Y137756D03*
X1047323Y137757D03*
X1045275Y247292D03*
X1050777Y450750D03*
X1054876Y536382D03*
X1059843Y597580D03*
X1059782Y594668D03*
X1062098Y615600D03*
X1044112Y778835D03*
X1045744Y800835D03*
X1048328Y808166D03*
X1057961Y931919D03*
X1046009Y997860D03*
X1054009D03*
X1050009D03*
X1058009D03*
X1059689Y1012354D03*
Y1024954D03*
X1048043Y1105091D03*
Y1117691D03*
Y1130291D03*
Y1155491D03*
Y1142891D03*
Y1168091D03*
Y1180691D03*
X1051249Y1290288D03*
X1052221Y1336984D03*
X1058891Y1345691D03*
Y1350683D03*
X1053935Y1345691D03*
Y1350683D03*
X1058891Y1362595D03*
X1053935D03*
X1058891Y1357603D03*
X1053935D03*
X1058891Y1381801D03*
Y1374881D03*
Y1369889D03*
X1053935Y1381801D03*
Y1374881D03*
Y1369889D03*
X1058891Y1386793D03*
X1053935D03*
X1051457Y1639797D03*
X1071988Y-66722D03*
X1075241Y-66808D03*
X1072003Y-64207D03*
X1075256Y-64293D03*
X1062985Y82984D03*
Y75184D03*
Y77784D03*
Y80384D03*
X1065539Y92849D03*
X1062985Y85584D03*
X1072499Y103037D03*
X1072633Y116496D03*
Y109410D03*
Y130670D03*
Y123583D03*
X1069224Y137756D03*
X1074814Y293796D03*
X1061325Y339509D03*
X1060679Y360151D03*
Y364276D03*
X1071548Y555234D03*
X1071263Y562003D03*
X1062066Y599588D03*
X1061328Y589556D03*
X1061267Y592354D03*
X1062069Y596095D03*
X1062066Y607588D03*
X1066559Y634946D03*
X1066009Y997860D03*
X1062009D03*
X1074009D03*
X1070778Y1012252D03*
X1066933Y1040567D03*
X1071641Y1058029D03*
X1060172Y1050481D03*
X1071348Y1050503D03*
X1066175Y1350683D03*
Y1345691D03*
X1071131Y1350683D03*
Y1345691D03*
X1066175Y1357603D03*
Y1362595D03*
X1071131Y1357603D03*
Y1362595D03*
X1066175Y1381801D03*
Y1369795D03*
Y1374881D03*
X1071131Y1381801D03*
Y1369795D03*
Y1374881D03*
X1066175Y1393993D03*
Y1399079D03*
Y1386793D03*
X1071131Y1399079D03*
Y1393993D03*
Y1386793D03*
X1066175Y1405999D03*
Y1410991D03*
X1071131Y1405999D03*
Y1410991D03*
X1071457Y1639797D03*
X1078281Y-65613D03*
X1089916Y94017D03*
X1085916D03*
X1090044Y110445D03*
Y115401D03*
Y124618D03*
Y129574D03*
X1087957Y151540D03*
X1091607Y191941D03*
X1091474Y188727D03*
X1085431Y226141D03*
X1088231D03*
X1088128Y285690D03*
Y288190D03*
X1085328D03*
X1082828Y285690D03*
X1085328D03*
X1082828Y288190D03*
X1077314Y293796D03*
X1092354Y290755D03*
X1077602Y314060D03*
X1091542Y389154D03*
Y410413D03*
Y396240D03*
Y403327D03*
Y417500D03*
Y424587D03*
Y431673D03*
Y438760D03*
Y445847D03*
Y467539D03*
Y474626D03*
Y488799D03*
Y481713D03*
Y495886D03*
Y511673D03*
Y518760D03*
Y525847D03*
Y532933D03*
Y540020D03*
Y547106D03*
X1090823Y602197D03*
X1091287Y595108D03*
X1079809Y1034386D03*
X1090655Y1350683D03*
Y1345691D03*
X1083371D03*
Y1350683D03*
X1078415Y1345691D03*
Y1350683D03*
X1090655Y1357603D03*
Y1362595D03*
X1083371Y1357603D03*
Y1362595D03*
X1078415D03*
Y1357603D03*
X1090655Y1381801D03*
Y1374881D03*
Y1369889D03*
X1083371D03*
Y1374881D03*
Y1381801D03*
X1078415Y1369889D03*
Y1374881D03*
Y1381801D03*
X1090655Y1394087D03*
Y1399079D03*
Y1386793D03*
X1083371D03*
Y1399079D03*
Y1394087D03*
X1078415Y1386793D03*
Y1394087D03*
Y1399079D03*
X1090655Y1405999D03*
Y1410991D03*
X1083371Y1405999D03*
Y1410991D03*
X1078415Y1405999D03*
Y1410991D03*
X1092000Y1644980D03*
X1102993Y84140D03*
Y76140D03*
Y80140D03*
X1097925Y94017D03*
X1093916D03*
X1100446Y117557D03*
X1095036Y115401D03*
Y110445D03*
X1105438Y117557D03*
X1095036Y129574D03*
Y124618D03*
X1105438Y131731D03*
Y122513D03*
X1100446Y131731D03*
Y122513D03*
X1103537Y146461D03*
X1100446Y136687D03*
X1105438D03*
X1102439Y152367D03*
X1104139Y180572D03*
X1108822Y180527D03*
X1104139Y185165D03*
X1108777Y185121D03*
X1098107Y184619D03*
X1100087Y206760D03*
X1101301Y256535D03*
X1093301D03*
X1102331Y279208D03*
X1106435Y281307D03*
X1096354Y290755D03*
X1100354D03*
X1100703Y340560D03*
X1101999Y353495D03*
X1093994Y374003D03*
X1106161Y389154D03*
X1104691Y396240D03*
X1108776Y422864D03*
X1108846Y429832D03*
X1108451Y436447D03*
X1108395Y472772D03*
X1105002Y516841D03*
X1108253Y510565D03*
X1099949Y550123D03*
X1099827Y552872D03*
X1101581Y572334D03*
X1099272Y562443D03*
X1101040Y560675D03*
X1099813Y574102D03*
X1104448Y653161D03*
X1108045Y677843D03*
X1107851Y1345691D03*
X1102895Y1350683D03*
Y1345691D03*
X1107851Y1350683D03*
X1095611D03*
Y1345691D03*
X1107851Y1357603D03*
X1102895Y1362595D03*
Y1357603D03*
X1107851Y1362595D03*
X1095611Y1357603D03*
Y1362595D03*
X1107851Y1369889D03*
Y1374881D03*
Y1381801D03*
X1102895Y1374881D03*
Y1369889D03*
Y1381801D03*
X1095611D03*
Y1374881D03*
Y1369889D03*
X1107851Y1386793D03*
Y1394087D03*
Y1399079D03*
X1102895Y1386793D03*
Y1394087D03*
Y1399079D03*
X1095611D03*
Y1394087D03*
Y1386793D03*
X1107851Y1405999D03*
Y1410991D03*
X1102895Y1405999D03*
Y1410991D03*
X1095611Y1405999D03*
Y1410991D03*
X1099900Y1535700D03*
X1107620Y1606752D03*
X1123052Y57511D03*
X1122613Y97042D03*
X1116368Y117261D03*
X1123899Y113394D03*
X1124075Y180665D03*
Y172665D03*
X1112545Y192421D03*
X1124107Y200864D03*
Y212864D03*
Y216864D03*
Y221864D03*
X1123500Y329000D03*
Y339000D03*
Y334000D03*
X1124753Y389153D03*
X1122253Y396240D03*
X1124753D03*
X1122253Y403327D03*
X1124753Y403326D03*
X1122253Y410413D03*
X1124753D03*
X1109468Y414823D03*
X1122253Y424586D03*
X1124753D03*
X1122253Y417500D03*
X1124753Y417499D03*
X1122253Y438760D03*
X1124753D03*
Y431673D03*
X1122253D03*
X1110486Y447953D03*
X1122253Y445847D03*
X1109653Y467539D03*
X1124753D03*
X1122253Y474626D03*
X1124753D03*
X1122253Y488799D03*
X1124753D03*
X1109129Y487711D03*
X1109242Y479104D03*
X1124753Y481712D03*
X1122253D03*
Y495886D03*
X1109653D03*
X1124753Y518760D03*
X1122253D03*
X1124753Y511673D03*
Y532933D03*
X1122253D03*
Y540020D03*
Y525846D03*
X1124753D03*
X1118863Y662981D03*
X1112839Y668885D03*
X1113244Y691851D03*
X1118855Y705043D03*
X1115135Y1345691D03*
Y1350683D03*
X1120091Y1345691D03*
Y1350683D03*
X1115135Y1357603D03*
Y1362595D03*
X1120091Y1357603D03*
Y1362595D03*
X1115135Y1374881D03*
Y1381801D03*
Y1369889D03*
X1120091D03*
Y1374881D03*
Y1381801D03*
X1115135Y1394087D03*
Y1399079D03*
Y1386793D03*
X1120091Y1399079D03*
Y1394087D03*
Y1386793D03*
X1115135Y1405999D03*
Y1410991D03*
X1120091Y1405999D03*
Y1410991D03*
X1112000Y1644980D03*
X1125735Y60922D03*
X1139134Y109172D03*
X1141141Y106495D03*
X1126548Y110784D03*
X1134142Y133298D03*
X1126142D03*
X1140875Y146012D03*
X1128289Y134579D03*
X1129277Y203393D03*
X1140346Y253198D03*
X1125864Y252371D03*
X1129553Y389153D03*
Y396240D03*
Y403326D03*
Y410413D03*
Y424586D03*
Y417499D03*
Y431673D03*
Y438760D03*
X1126931Y453564D03*
X1130355Y453483D03*
X1129553Y467539D03*
X1125178Y459792D03*
X1129553Y474626D03*
Y488799D03*
Y481712D03*
Y518760D03*
Y511673D03*
Y532933D03*
Y525846D03*
X1138098Y543925D03*
X1138673Y555000D03*
X1126633Y560500D03*
X1139615Y1350683D03*
Y1345691D03*
X1132331D03*
Y1350683D03*
X1127375D03*
Y1345691D03*
X1139615Y1357603D03*
Y1362595D03*
X1132331D03*
Y1357603D03*
X1127375D03*
Y1362595D03*
X1139615Y1374881D03*
Y1369889D03*
Y1381801D03*
X1132331Y1369889D03*
Y1381801D03*
Y1374881D03*
X1127375Y1369889D03*
Y1381801D03*
Y1374881D03*
X1139615Y1394087D03*
Y1399079D03*
Y1386793D03*
X1132331D03*
Y1394087D03*
Y1399079D03*
X1127375Y1386793D03*
Y1394087D03*
Y1399079D03*
X1139615Y1405999D03*
Y1410991D03*
X1132331Y1405999D03*
Y1410991D03*
X1127375Y1405999D03*
Y1410991D03*
X1129637Y1465913D03*
Y1461182D03*
Y1456451D03*
X1138298Y1465513D03*
Y1460782D03*
X1129637Y1476536D03*
Y1481267D03*
X1138298Y1476136D03*
Y1470244D03*
Y1480867D03*
X1129637Y1471805D03*
Y1496621D03*
X1138298Y1491490D03*
Y1485598D03*
Y1496221D03*
X1129637Y1491890D03*
Y1487159D03*
X1138298Y1500952D03*
Y1511576D03*
X1129637Y1507245D03*
Y1502514D03*
Y1511976D03*
X1138298Y1506845D03*
Y1516307D03*
X1129637Y1563544D03*
Y1558813D03*
X1138298Y1563144D03*
Y1572606D03*
X1129637Y1568275D03*
Y1578898D03*
Y1574167D03*
X1138298Y1567875D03*
Y1578498D03*
X1129637Y1583629D03*
Y1594253D03*
Y1589522D03*
X1138298Y1583229D03*
Y1593853D03*
Y1587960D03*
Y1598584D03*
Y1603315D03*
X1129637Y1609607D03*
Y1598984D03*
Y1604876D03*
X1138298Y1609207D03*
X1129637Y1614338D03*
X1138298Y1613938D03*
Y1618669D03*
X1132000Y1644980D03*
X1142134Y109172D03*
X1156885Y116496D03*
Y102323D03*
Y109410D03*
X1152185D03*
Y116497D03*
X1149685D03*
X1144885D03*
X1152185Y130670D03*
X1149685D03*
Y123584D03*
X1152185Y123583D03*
X1144885Y130670D03*
Y123584D03*
X1156885Y130670D03*
Y123583D03*
X1142781Y141228D03*
X1156885Y137756D03*
X1149685Y137757D03*
X1144885D03*
X1145669Y150847D03*
X1147637Y247292D03*
X1145761Y324148D03*
X1157251Y636842D03*
X1156023Y678462D03*
X1149345Y771517D03*
X1145910Y794217D03*
X1151277Y790996D03*
X1149627Y813323D03*
X1146985Y812642D03*
X1152510Y844642D03*
X1156811Y1350683D03*
Y1345691D03*
X1151855D03*
Y1350683D03*
X1144571D03*
Y1345691D03*
X1156811Y1357603D03*
Y1362595D03*
X1151855D03*
Y1357603D03*
X1144571D03*
Y1362595D03*
X1156811Y1374881D03*
Y1369889D03*
Y1381801D03*
X1151855Y1374881D03*
Y1369889D03*
Y1381801D03*
X1144571Y1369889D03*
Y1381801D03*
Y1374881D03*
X1156811Y1386793D03*
Y1399079D03*
Y1394087D03*
X1151855Y1386793D03*
Y1399079D03*
Y1394087D03*
X1144571D03*
Y1399079D03*
Y1386793D03*
X1156811Y1405999D03*
Y1410991D03*
X1151855Y1405999D03*
Y1410991D03*
X1144571Y1405999D03*
Y1410991D03*
X1146960Y1465913D03*
Y1461182D03*
X1155621Y1465513D03*
Y1460782D03*
X1146960Y1456451D03*
X1155621Y1480867D03*
X1146960Y1471805D03*
Y1476536D03*
Y1481267D03*
X1155621Y1476136D03*
Y1470244D03*
Y1491490D03*
Y1485598D03*
Y1496221D03*
X1146960Y1487159D03*
Y1491890D03*
Y1496621D03*
Y1507245D03*
Y1502514D03*
X1155621Y1506845D03*
Y1500952D03*
Y1511576D03*
X1146960Y1511976D03*
X1155621Y1516307D03*
X1146960Y1563544D03*
X1155621Y1563144D03*
X1146960Y1558813D03*
X1155621Y1572606D03*
X1146960Y1568275D03*
X1155621Y1567875D03*
X1146960Y1574167D03*
Y1578898D03*
X1155621Y1578498D03*
X1146960Y1594253D03*
X1155621Y1593853D03*
Y1587960D03*
X1146960Y1583629D03*
X1155621Y1583229D03*
X1146960Y1589522D03*
Y1609607D03*
Y1604876D03*
Y1598984D03*
X1155621Y1609207D03*
Y1598584D03*
Y1603315D03*
X1146960Y1614338D03*
X1155621Y1613938D03*
Y1618669D03*
X1152000Y1644980D03*
X1165347Y82984D03*
Y75184D03*
Y77784D03*
Y80384D03*
X1167756Y92734D03*
X1165347Y85584D03*
X1171586Y137756D03*
X1168902Y431029D03*
X1167931Y435029D03*
X1169173Y427017D03*
X1168851Y449873D03*
X1171255Y456287D03*
X1173278Y472579D03*
X1168478D03*
X1173278Y479666D03*
X1168478D03*
Y486752D03*
X1173278D03*
X1168478Y493839D03*
X1173278D03*
X1168478Y523800D03*
Y516713D03*
X1173278D03*
Y523800D03*
Y537973D03*
X1168478D03*
X1173278Y530886D03*
X1168478D03*
X1173278Y566752D03*
X1168478D03*
Y580926D03*
X1173278D03*
Y588013D03*
X1168478D03*
X1173278Y573839D03*
X1168478D03*
Y602186D03*
X1173278D03*
Y595099D03*
X1168478D03*
X1173278Y609272D03*
X1168478D03*
Y616359D03*
X1173278D03*
X1163157Y638125D03*
X1160756Y665140D03*
X1157985Y791142D03*
X1161291Y791662D03*
X1173697Y791911D03*
X1160516Y800900D03*
X1169051Y1345597D03*
Y1350683D03*
X1164095D03*
Y1345597D03*
X1169051Y1357603D03*
Y1362595D03*
X1164095Y1357603D03*
Y1362595D03*
X1169051Y1381801D03*
Y1374881D03*
Y1369889D03*
X1164095D03*
Y1381801D03*
Y1374881D03*
X1169051Y1393993D03*
Y1399079D03*
Y1386793D03*
X1164095Y1393993D03*
Y1399079D03*
Y1386793D03*
X1169051Y1410991D03*
Y1405999D03*
X1164095D03*
Y1410991D03*
X1164283Y1465913D03*
Y1456451D03*
Y1461182D03*
X1172944Y1465513D03*
Y1460782D03*
Y1470244D03*
Y1480867D03*
X1164283Y1471805D03*
Y1476536D03*
Y1481267D03*
X1172944Y1476136D03*
X1164283Y1487159D03*
Y1491890D03*
Y1496621D03*
X1172944Y1491490D03*
Y1485598D03*
Y1496221D03*
X1164283Y1507245D03*
Y1502514D03*
X1172944Y1506845D03*
Y1500952D03*
Y1511576D03*
X1164283Y1511976D03*
X1172944Y1516307D03*
X1164283Y1558813D03*
Y1563544D03*
X1172944Y1563144D03*
Y1567875D03*
X1164283Y1574167D03*
Y1578898D03*
X1172944Y1578498D03*
Y1572606D03*
X1164283Y1568275D03*
Y1583629D03*
X1172944Y1583229D03*
X1164283Y1589522D03*
Y1594253D03*
X1172944Y1593853D03*
Y1587960D03*
Y1598584D03*
Y1603315D03*
X1164283Y1609607D03*
Y1604876D03*
Y1598984D03*
X1172944Y1609207D03*
X1164283Y1614338D03*
X1172944Y1613938D03*
Y1618669D03*
X1172000Y1644980D03*
X1188278Y94017D03*
X1174861Y103037D03*
X1174995Y116496D03*
Y109410D03*
Y130670D03*
Y123583D03*
X1187793Y226141D03*
X1190593D03*
X1179676Y293796D03*
X1187690Y288190D03*
X1185190Y285690D03*
X1187690D03*
X1185190Y288190D03*
X1177176Y293796D03*
X1182911Y336516D03*
X1177036Y334148D03*
X1188598Y390500D03*
X1179184Y410394D03*
Y403307D03*
X1180578Y458406D03*
Y451319D03*
X1180402Y462264D03*
X1175778Y465492D03*
X1180578D03*
X1175778Y472579D03*
X1180578D03*
X1175778Y479666D03*
X1180578Y479665D03*
Y486752D03*
X1175778D03*
X1180578Y493839D03*
X1175778Y509626D03*
X1180578Y523799D03*
Y516713D03*
Y509626D03*
X1175778Y516713D03*
Y523800D03*
X1180578Y537973D03*
X1175778Y530886D03*
X1180578D03*
Y559665D03*
Y566752D03*
X1175778D03*
Y559665D03*
Y580926D03*
X1180578D03*
Y588012D03*
X1175778D03*
X1180578Y573839D03*
X1175778D03*
Y602185D03*
X1180578D03*
X1175778Y595099D03*
X1180578D03*
X1175778Y609272D03*
X1180578Y616358D03*
Y609272D03*
X1177745Y771744D03*
X1177566Y778539D03*
X1190062Y844378D03*
X1187703Y849734D03*
X1186742Y855466D03*
X1183431Y868340D03*
X1177775Y894053D03*
X1178480Y915220D03*
X1178000Y936500D03*
X1187200Y963400D03*
X1181291Y1350683D03*
Y1345691D03*
X1176335D03*
Y1350683D03*
X1181291Y1362595D03*
Y1357603D03*
X1176335Y1362595D03*
Y1357603D03*
X1181291Y1369889D03*
Y1381801D03*
Y1374881D03*
X1176335Y1369889D03*
Y1381801D03*
Y1374881D03*
X1181291Y1386793D03*
Y1399079D03*
Y1394087D03*
X1176335Y1386793D03*
Y1399079D03*
Y1394087D03*
X1181291Y1405999D03*
Y1410991D03*
X1176335Y1405999D03*
Y1410991D03*
X1181605Y1465913D03*
Y1456451D03*
Y1461182D03*
Y1471805D03*
Y1476536D03*
Y1481267D03*
Y1487159D03*
Y1491890D03*
Y1496621D03*
Y1507245D03*
Y1502514D03*
Y1511976D03*
Y1558813D03*
Y1563544D03*
Y1568275D03*
Y1574167D03*
Y1578898D03*
Y1583629D03*
Y1589522D03*
Y1594253D03*
Y1598984D03*
Y1609607D03*
Y1604876D03*
Y1614338D03*
X1205355Y84140D03*
Y76140D03*
Y80140D03*
X1196278Y94017D03*
X1200287D03*
X1192278D03*
X1202808Y117557D03*
X1197398Y110445D03*
Y115401D03*
X1192406Y110445D03*
Y115401D03*
X1197398Y129574D03*
Y124618D03*
X1192406D03*
Y129574D03*
X1202808Y122513D03*
Y131731D03*
X1205899Y146461D03*
X1202808Y136687D03*
X1204801Y152367D03*
X1190319Y151540D03*
X1200469Y184619D03*
X1193969Y191941D03*
X1193836Y188727D03*
X1202449Y206760D03*
X1203663Y256535D03*
X1195663D03*
X1204693Y279208D03*
X1194716Y290755D03*
X1202716D03*
X1190490Y285690D03*
Y288190D03*
X1198716Y290755D03*
X1198248Y381500D03*
X1198689Y465492D03*
X1198655Y460250D03*
X1196420Y470136D03*
X1198689Y472579D03*
Y486752D03*
Y479665D03*
Y493839D03*
Y509626D03*
Y516713D03*
X1195149Y537973D03*
X1197629Y525483D03*
X1197550Y532756D03*
X1198689Y559665D03*
Y566752D03*
X1198539Y579978D03*
X1198689Y573839D03*
X1198753Y608117D03*
X1198997Y790610D03*
X1198845Y998504D03*
X1204919Y1021860D03*
X1202268Y1013551D03*
X1190267Y1465513D03*
Y1460782D03*
X1198928Y1465914D03*
Y1456452D03*
Y1461183D03*
Y1481268D03*
X1190267Y1476136D03*
Y1470244D03*
Y1480867D03*
X1198928Y1476537D03*
Y1471806D03*
X1190267Y1485598D03*
Y1496221D03*
X1198928Y1491891D03*
Y1487160D03*
Y1496622D03*
X1190267Y1491490D03*
Y1506845D03*
Y1500952D03*
Y1511576D03*
X1198928Y1507246D03*
Y1502515D03*
Y1511977D03*
X1190267Y1516307D03*
X1198928Y1558813D03*
X1190267Y1563144D03*
X1198928Y1563544D03*
X1190267Y1567875D03*
X1198928Y1568275D03*
X1190267Y1578498D03*
Y1572606D03*
X1198928Y1578898D03*
Y1574167D03*
X1190267Y1583229D03*
X1198928Y1583629D03*
X1190267Y1593853D03*
Y1587960D03*
X1198928Y1594253D03*
Y1589522D03*
X1190267Y1609207D03*
Y1598584D03*
Y1603315D03*
X1198928Y1609607D03*
Y1598984D03*
Y1604876D03*
X1190267Y1613938D03*
Y1618669D03*
X1198928Y1614338D03*
X1192000Y1644980D03*
X1218730Y117261D03*
X1207800Y117557D03*
Y122513D03*
Y131731D03*
Y136687D03*
X1206501Y180572D03*
X1211184Y180527D03*
X1214907Y192421D03*
X1206501Y185165D03*
X1211139Y185121D03*
X1208797Y281307D03*
X1220985Y342319D03*
X1212680Y445908D03*
X1216630Y445787D03*
X1212000Y1644980D03*
X1222933Y55513D03*
X1228097Y60922D03*
X1225041Y97080D03*
X1228910Y110784D03*
X1226261Y113394D03*
X1229195Y130898D03*
X1236504Y133298D03*
X1230651Y134579D03*
X1226437Y180665D03*
Y172665D03*
X1226469Y200864D03*
Y212864D03*
Y216864D03*
Y221864D03*
X1228226Y252371D03*
X1238055Y303839D03*
X1230077Y336324D03*
X1234656Y353506D03*
X1223431Y393924D03*
Y389912D03*
Y385912D03*
Y409924D03*
Y405924D03*
Y401924D03*
X1229548Y1350683D03*
Y1345691D03*
X1234504D03*
Y1350683D03*
X1229548Y1362595D03*
Y1357603D03*
X1234504D03*
Y1362595D03*
X1229548Y1369889D03*
Y1374881D03*
Y1381801D03*
X1234504Y1369889D03*
Y1374881D03*
Y1381801D03*
X1229548Y1386793D03*
X1234504D03*
X1232000Y1644980D03*
X1243503Y106495D03*
X1244496Y109172D03*
X1241496D03*
X1247247Y116497D03*
X1254547Y109410D03*
Y116497D03*
X1252047D03*
X1247247Y123584D03*
Y130670D03*
X1252047Y123584D03*
X1254547Y123583D03*
Y130670D03*
X1252047D03*
X1243237Y146012D03*
X1245143Y141228D03*
X1247247Y137757D03*
X1252047D03*
X1250307Y140296D03*
X1248031Y150847D03*
X1249999Y247292D03*
X1242708Y253198D03*
X1248064Y567813D03*
Y572769D03*
Y581987D03*
Y586943D03*
Y601116D03*
Y596160D03*
Y615289D03*
Y610333D03*
X1246800Y1001600D03*
X1249200Y1014000D03*
X1248721Y1025864D03*
X1251802Y1186071D03*
X1254028Y1350683D03*
Y1345691D03*
X1241788D03*
Y1350683D03*
X1246744Y1345691D03*
Y1350683D03*
X1254028Y1357603D03*
Y1362595D03*
X1241788D03*
Y1357603D03*
X1246744Y1362595D03*
Y1357603D03*
X1254028Y1381801D03*
Y1374881D03*
Y1369889D03*
X1241788Y1374881D03*
Y1369795D03*
Y1381801D03*
X1246744Y1374881D03*
Y1369795D03*
Y1381801D03*
X1254028Y1386793D03*
Y1399079D03*
Y1394087D03*
X1241788Y1399079D03*
Y1393993D03*
Y1386793D03*
X1246744Y1393993D03*
Y1399079D03*
Y1386793D03*
X1254028Y1410991D03*
Y1405999D03*
X1241788Y1410991D03*
Y1405999D03*
X1246744Y1410991D03*
Y1405999D03*
X1245900Y1528000D03*
X1267709Y82984D03*
Y75184D03*
Y77784D03*
Y80384D03*
X1270263Y92849D03*
X1267709Y85584D03*
X1259247Y116496D03*
Y102323D03*
Y109410D03*
Y130670D03*
Y123583D03*
Y137756D03*
X1258925Y324075D03*
X1270951Y491870D03*
X1270515Y908277D03*
X1269876Y1132319D03*
X1263873Y1148000D03*
X1266709Y1160168D03*
X1258736Y1188223D03*
X1268573Y1193019D03*
X1264573D03*
X1266268Y1345691D03*
Y1350683D03*
X1258984D03*
Y1345691D03*
X1266268Y1362595D03*
Y1357603D03*
X1258984Y1362595D03*
Y1357603D03*
X1266268Y1369889D03*
Y1374881D03*
Y1381801D03*
X1258984D03*
Y1369889D03*
Y1374881D03*
X1266268Y1399079D03*
Y1394087D03*
Y1386793D03*
X1258984Y1394087D03*
Y1386793D03*
Y1399079D03*
X1266268Y1410991D03*
Y1405999D03*
X1258984D03*
Y1410991D03*
X1263242Y1523458D03*
X1262985Y1519459D03*
X1260260Y1546500D03*
X1277223Y103037D03*
X1277357Y116496D03*
Y109410D03*
Y130670D03*
Y123583D03*
X1273555Y137756D03*
X1279538Y293796D03*
X1282038D03*
X1283494Y339495D03*
X1287437Y370010D03*
X1280616Y472189D03*
X1273451Y491870D03*
X1279539Y772576D03*
Y776576D03*
X1274417Y861964D03*
X1282317Y880193D03*
X1285493Y892175D03*
X1277039Y916484D03*
X1284021Y940008D03*
X1273865Y1132497D03*
X1282830Y1146937D03*
X1272120Y1159455D03*
X1280306Y1162817D03*
X1276573Y1193019D03*
X1280573D03*
X1272573D03*
X1277108Y1211664D03*
X1279402Y1213958D03*
X1275032Y1209589D03*
X1284198Y1218754D03*
X1283464Y1345691D03*
Y1350683D03*
X1278508Y1345691D03*
Y1350683D03*
X1271224Y1345691D03*
Y1350683D03*
X1283464Y1362595D03*
Y1357603D03*
X1278508D03*
Y1362595D03*
X1271224D03*
Y1357603D03*
X1283464Y1381801D03*
Y1369889D03*
Y1374881D03*
X1278508Y1381801D03*
Y1369889D03*
Y1374881D03*
X1271224Y1369889D03*
Y1374881D03*
Y1381801D03*
X1283464Y1386793D03*
Y1399079D03*
Y1394087D03*
X1278508Y1386793D03*
Y1399079D03*
Y1394087D03*
X1271224D03*
Y1399079D03*
Y1386793D03*
X1283464Y1410991D03*
Y1405999D03*
X1278508Y1410991D03*
Y1405999D03*
X1271224Y1410991D03*
Y1405999D03*
X1291756Y-25143D03*
X1288503Y-25157D03*
X1291741Y-27658D03*
X1288488Y-27672D03*
X1294781Y-26463D03*
X1302649Y94017D03*
X1298640D03*
X1290640D03*
X1294640D03*
X1299760Y110445D03*
Y115401D03*
X1294768Y110445D03*
Y115401D03*
Y129574D03*
X1299760D03*
Y124618D03*
X1294768D03*
X1296331Y191941D03*
X1302831Y184619D03*
X1296198Y188727D03*
X1292955Y226141D03*
X1290155D03*
X1298025Y256535D03*
X1290052Y288190D03*
X1292852D03*
Y285690D03*
X1305078Y290755D03*
X1297078D03*
X1301078D03*
X1287552Y288190D03*
X1290052Y285690D03*
X1287552D03*
X1294425Y321425D03*
X1299959Y351454D03*
X1296783Y511956D03*
X1303520Y748403D03*
X1300516Y832047D03*
X1300504Y835985D03*
X1300204Y859088D03*
X1300097Y851193D03*
X1300091Y854824D03*
X1291955Y901295D03*
X1289547Y928047D03*
X1298090Y940852D03*
X1295453Y940953D03*
X1302988Y1345691D03*
Y1350683D03*
X1290748D03*
Y1345691D03*
X1295704Y1350683D03*
Y1345691D03*
X1302988Y1362595D03*
Y1357603D03*
X1290748Y1362595D03*
Y1357603D03*
X1295704Y1362595D03*
Y1357603D03*
X1302988Y1374881D03*
Y1381801D03*
Y1369889D03*
X1290748D03*
Y1381801D03*
Y1374881D03*
X1295704Y1381801D03*
Y1374881D03*
Y1369889D03*
X1302988Y1386793D03*
Y1399079D03*
Y1394087D03*
X1290748Y1399079D03*
Y1394087D03*
Y1386793D03*
X1295704Y1394087D03*
Y1399079D03*
Y1386793D03*
X1302988Y1410991D03*
Y1405999D03*
X1290748Y1410991D03*
Y1405999D03*
X1295704Y1410991D03*
Y1405999D03*
X1302866Y1461182D03*
Y1456451D03*
Y1465913D03*
Y1476536D03*
Y1471805D03*
Y1481267D03*
Y1491890D03*
Y1487159D03*
Y1496621D03*
Y1507245D03*
Y1502514D03*
Y1511976D03*
Y1558813D03*
Y1563544D03*
Y1578898D03*
Y1574167D03*
Y1568275D03*
Y1594253D03*
Y1589522D03*
Y1583629D03*
Y1609607D03*
Y1598984D03*
Y1604876D03*
Y1614338D03*
X1292000Y1644980D03*
X1307717Y84140D03*
Y76140D03*
Y80140D03*
X1310162Y117557D03*
X1305170D03*
X1310162Y122513D03*
Y131731D03*
X1305170Y122513D03*
Y131731D03*
X1310162Y136687D03*
X1305170D03*
X1313546Y180527D03*
X1308863Y180572D03*
Y185165D03*
X1317269Y192421D03*
X1313501Y185121D03*
X1304811Y206760D03*
X1306025Y256535D03*
X1307055Y279208D03*
X1311159Y281307D03*
X1314569Y318013D03*
X1312069D03*
X1317584Y313058D03*
X1316017Y349889D03*
X1308410Y370899D03*
X1313691Y402642D03*
X1316191D03*
X1309117Y398949D03*
X1306617Y401949D03*
X1308066Y413611D03*
X1310866D03*
X1313366D03*
X1315866D03*
X1315806Y423944D03*
X1313306D03*
X1310806D03*
X1308006D03*
X1307919Y478382D03*
X1307825Y482382D03*
X1305134Y812065D03*
X1313756Y829871D03*
X1308857Y836076D03*
X1316906Y842470D03*
Y867665D03*
Y883413D03*
Y892862D03*
X1316893Y925603D03*
X1318375Y943951D03*
X1303907Y960093D03*
X1307580Y990314D03*
X1304664Y1023462D03*
X1309937Y1037038D03*
X1319326Y1040723D03*
X1317437Y1152684D03*
X1307167Y1245696D03*
X1308276Y1276446D03*
X1315228Y1345691D03*
Y1350683D03*
X1307944D03*
Y1345691D03*
X1315228Y1362595D03*
Y1357603D03*
X1307944D03*
Y1362595D03*
X1315228Y1381801D03*
Y1369889D03*
Y1374881D03*
X1307944D03*
Y1381801D03*
Y1369889D03*
X1315228Y1399079D03*
Y1394087D03*
Y1386793D03*
X1307944D03*
Y1399079D03*
Y1394087D03*
X1315228Y1410991D03*
Y1405999D03*
X1307944Y1410991D03*
Y1405999D03*
X1311527Y1465513D03*
Y1460782D03*
Y1480867D03*
Y1476136D03*
Y1470244D03*
Y1491490D03*
Y1485598D03*
Y1496221D03*
Y1506845D03*
Y1500952D03*
Y1511576D03*
Y1516307D03*
Y1563144D03*
Y1567875D03*
Y1578498D03*
Y1572606D03*
Y1583229D03*
Y1593853D03*
Y1587960D03*
Y1609207D03*
Y1598584D03*
Y1603315D03*
Y1613938D03*
Y1618669D03*
X1312000Y1644980D03*
X1331756Y-64193D03*
X1328503Y-64207D03*
X1331741Y-66708D03*
X1328488Y-66722D03*
X1334781Y-65513D03*
X1321092Y117261D03*
X1328799Y172665D03*
Y180665D03*
X1328831Y212864D03*
Y200864D03*
Y221864D03*
Y216864D03*
X1330414Y310058D03*
X1325458D03*
X1322540Y313058D03*
X1333332D03*
X1331085Y334347D03*
X1323816D03*
Y341615D03*
X1331085Y348868D03*
X1323816D03*
X1332927Y468607D03*
X1326912Y493153D03*
X1325630Y513238D03*
X1335000Y590500D03*
Y586500D03*
Y633000D03*
Y637000D03*
Y677500D03*
Y681500D03*
Y724500D03*
Y728500D03*
X1324217Y780595D03*
X1332654Y836170D03*
X1323205Y861367D03*
X1335803Y851918D03*
Y877114D03*
X1326355Y886562D03*
X1328457Y959986D03*
X1321104Y964398D03*
X1323554Y967623D03*
X1331890Y1051919D03*
X1331359Y1098898D03*
X1334161Y1098518D03*
X1333905Y1123101D03*
X1331405D03*
X1323405D03*
X1320279Y1131935D03*
Y1134435D03*
Y1136935D03*
Y1139435D03*
X1334305Y1129301D03*
X1331805D03*
X1329305D03*
X1326805D03*
X1324305D03*
X1321805D03*
X1334305Y1125801D03*
X1331805D03*
X1323405D03*
X1320279Y1141935D03*
Y1146935D03*
Y1144435D03*
X1326269Y1152713D03*
Y1155213D03*
X1320493Y1204405D03*
X1334793Y1204617D03*
X1320493Y1206905D03*
Y1211905D03*
Y1209405D03*
X1334793Y1207117D03*
Y1209617D03*
Y1212117D03*
X1330070Y1297498D03*
X1335470D03*
X1332424Y1345691D03*
Y1350683D03*
X1327468D03*
Y1345691D03*
X1320184Y1350683D03*
Y1345691D03*
X1332424Y1362595D03*
Y1357603D03*
X1327468D03*
Y1362595D03*
X1320184D03*
Y1357603D03*
X1332424Y1381801D03*
Y1369889D03*
Y1374881D03*
X1327468Y1381801D03*
Y1369889D03*
Y1374881D03*
X1320184Y1381801D03*
Y1374881D03*
Y1369889D03*
X1332424Y1386793D03*
Y1394087D03*
Y1399079D03*
X1327468Y1386793D03*
Y1394087D03*
Y1399079D03*
X1320184D03*
Y1394087D03*
Y1386793D03*
X1332424Y1410991D03*
Y1405999D03*
X1327468Y1410991D03*
Y1405999D03*
X1320184Y1410991D03*
Y1405999D03*
X1328850Y1465513D03*
Y1460782D03*
X1320189Y1465913D03*
Y1456451D03*
Y1461182D03*
X1328850Y1476136D03*
Y1470244D03*
X1320189Y1481267D03*
X1328850Y1480867D03*
X1320189Y1471805D03*
Y1476536D03*
X1328850Y1491490D03*
Y1485598D03*
X1320189Y1496621D03*
X1328850Y1496221D03*
X1320189Y1487159D03*
Y1491890D03*
Y1502514D03*
X1328850Y1506845D03*
Y1500952D03*
Y1511576D03*
X1320189Y1511976D03*
Y1507245D03*
X1328850Y1516307D03*
X1320189Y1558813D03*
Y1563544D03*
X1328850Y1563144D03*
Y1567875D03*
X1320189Y1574167D03*
Y1578898D03*
X1328850Y1578498D03*
Y1572606D03*
X1320189Y1568275D03*
X1328850Y1583229D03*
X1320189Y1589522D03*
Y1594253D03*
X1328850Y1593853D03*
Y1587960D03*
X1320189Y1583629D03*
X1328850Y1603315D03*
X1320189Y1609607D03*
Y1604876D03*
Y1598984D03*
X1328850Y1609207D03*
Y1598584D03*
Y1613938D03*
Y1618669D03*
X1320189Y1614338D03*
X1332000Y1644980D03*
X1340320Y151540D03*
X1338288Y313058D03*
X1338378Y334347D03*
X1338275Y341603D03*
X1338378Y348830D03*
X1345451Y699032D03*
X1347136Y780040D03*
X1351550Y839320D03*
Y855068D03*
X1345252D03*
X1342103D03*
Y861367D03*
X1338953D03*
Y858218D03*
X1338952Y855067D03*
X1338953Y870814D03*
X1342103Y867665D03*
X1338953D03*
X1351550Y873964D03*
X1345252D03*
X1342103D03*
X1338952Y873965D03*
X1345252Y892862D03*
X1341820Y947407D03*
X1347380Y1057998D03*
Y1055498D03*
X1344880D03*
Y1057998D03*
X1347380Y1060498D03*
Y1062998D03*
X1344880D03*
Y1060498D03*
X1339349Y1098767D03*
X1339305Y1129301D03*
X1336805D03*
X1339305Y1125801D03*
X1336805D03*
X1343505Y1136935D03*
Y1134435D03*
Y1139435D03*
Y1131935D03*
X1349907D03*
Y1134435D03*
Y1136935D03*
Y1139435D03*
X1352407Y1131935D03*
Y1134435D03*
Y1136935D03*
Y1139435D03*
X1343505Y1146935D03*
Y1144435D03*
Y1141935D03*
X1349907D03*
Y1146935D03*
Y1144435D03*
X1352407Y1141935D03*
Y1146935D03*
Y1144435D03*
X1336669Y1152713D03*
Y1155213D03*
X1351405Y1154902D03*
Y1152402D03*
X1347423Y1204405D03*
X1337108Y1200821D03*
Y1198321D03*
X1347423Y1209405D03*
Y1211905D03*
Y1206905D03*
X1340870Y1297498D03*
X1346270D03*
X1351670D03*
X1351948Y1350683D03*
Y1345691D03*
X1339708Y1345597D03*
Y1350683D03*
X1344664Y1345597D03*
Y1350683D03*
X1351948Y1357603D03*
Y1362595D03*
X1339708D03*
Y1357603D03*
X1344664Y1362595D03*
Y1357603D03*
X1351948Y1374881D03*
Y1381801D03*
Y1369889D03*
X1339708Y1374881D03*
Y1381801D03*
Y1369889D03*
X1344664D03*
Y1374881D03*
Y1381801D03*
X1351948Y1386793D03*
Y1394087D03*
Y1399079D03*
X1339708D03*
Y1393993D03*
Y1386793D03*
X1344664Y1393993D03*
Y1399079D03*
Y1386793D03*
X1351948Y1410991D03*
Y1405999D03*
X1339708Y1410991D03*
Y1405999D03*
X1344664Y1410991D03*
Y1405999D03*
X1337512Y1461182D03*
X1346173Y1465513D03*
Y1460782D03*
X1337512Y1465913D03*
Y1456451D03*
X1346173Y1476136D03*
Y1470244D03*
X1337512Y1481267D03*
X1346173Y1480867D03*
X1337512Y1471805D03*
Y1476536D03*
X1346173Y1485598D03*
Y1491490D03*
X1337512Y1487159D03*
Y1491890D03*
Y1496621D03*
X1346173Y1496221D03*
X1337512Y1507245D03*
Y1502514D03*
X1346173Y1506845D03*
Y1500952D03*
Y1511576D03*
X1337512Y1511976D03*
X1346173Y1516307D03*
X1337512Y1558813D03*
Y1563544D03*
X1346173Y1563144D03*
X1337512Y1574167D03*
Y1578898D03*
X1346173Y1578498D03*
Y1572606D03*
X1337512Y1568275D03*
X1346173Y1567875D03*
X1337512Y1583629D03*
X1346173Y1583229D03*
X1337512Y1589522D03*
Y1594253D03*
X1346173Y1593853D03*
Y1587960D03*
X1337512Y1609607D03*
Y1604876D03*
Y1598984D03*
X1346173Y1609207D03*
Y1598584D03*
Y1603315D03*
X1337512Y1614338D03*
X1346173Y1613938D03*
Y1618669D03*
X1352000Y1644980D03*
X1355900Y146461D03*
X1354802Y152367D03*
X1355255Y561032D03*
Y607532D03*
Y652032D03*
X1364148Y836170D03*
X1354699Y855068D03*
X1357849Y861367D03*
X1354699D03*
X1357849Y858218D03*
X1357850Y855067D03*
X1360999Y851918D03*
Y877114D03*
X1357850Y873965D03*
X1354699Y873964D03*
X1357849Y870814D03*
Y867665D03*
X1354699D03*
X1363173Y994483D03*
X1363905Y1000855D03*
X1366493Y1000828D03*
X1367884Y1018825D03*
X1357265Y1022766D03*
X1364237Y1043140D03*
X1357265Y1030266D03*
X1363941Y1047047D03*
X1366289Y1098518D03*
X1361037Y1098428D03*
X1355533Y1123101D03*
X1363533D03*
X1366033D03*
X1366433Y1129301D03*
X1355533Y1125801D03*
X1363933D03*
X1366433D03*
X1353933Y1129301D03*
X1356433D03*
X1358933D03*
X1361433D03*
X1363933D03*
X1357397Y1155213D03*
Y1152713D03*
X1366797D03*
Y1155213D03*
X1361723Y1204617D03*
X1364038Y1198321D03*
Y1200821D03*
X1361723Y1212117D03*
Y1209617D03*
Y1207117D03*
X1357070Y1297498D03*
X1356904Y1345691D03*
Y1350683D03*
Y1357603D03*
Y1362595D03*
Y1381801D03*
Y1369889D03*
Y1374881D03*
Y1386793D03*
Y1394087D03*
Y1399079D03*
Y1410991D03*
Y1405999D03*
X1354834Y1465913D03*
Y1456451D03*
Y1461182D03*
X1363496Y1465513D03*
Y1460782D03*
X1354834Y1481267D03*
X1363496Y1476136D03*
Y1470244D03*
Y1480867D03*
X1354834Y1471805D03*
Y1476536D03*
Y1487159D03*
Y1496621D03*
X1363496Y1485598D03*
Y1491490D03*
Y1496221D03*
X1354834Y1491890D03*
Y1502514D03*
Y1511976D03*
X1363496Y1511576D03*
Y1506845D03*
Y1500952D03*
X1354834Y1507245D03*
X1363496Y1516307D03*
X1354834Y1558813D03*
Y1563544D03*
X1363496Y1563144D03*
Y1572606D03*
X1354834Y1568275D03*
Y1574167D03*
Y1578898D03*
X1363496Y1567875D03*
Y1578498D03*
X1354834Y1583629D03*
Y1589522D03*
Y1594253D03*
X1363496Y1583229D03*
Y1593853D03*
Y1587960D03*
X1354834Y1609607D03*
Y1604876D03*
Y1598984D03*
X1363496Y1609207D03*
Y1598584D03*
Y1603315D03*
X1354834Y1614338D03*
X1363496Y1613938D03*
Y1618669D03*
X1376262Y113394D03*
X1378911Y110784D03*
X1378505Y133298D03*
X1380652Y134579D03*
X1378227Y252371D03*
X1383556Y558338D03*
X1383184Y587653D03*
X1383425Y593575D03*
X1383556Y604838D03*
X1381118Y634033D03*
X1383425Y640075D03*
X1381244Y673623D03*
X1383425Y684140D03*
X1381932Y722547D03*
X1383425Y731575D03*
X1383046Y829871D03*
X1379896Y842470D03*
Y858218D03*
X1370447Y867665D03*
Y886562D03*
X1371379Y986717D03*
X1370384Y1004680D03*
X1376601Y1030218D03*
X1374451Y1090568D03*
Y1093068D03*
X1371477Y1098767D03*
X1375633Y1136935D03*
Y1134435D03*
Y1139435D03*
Y1131935D03*
X1383366D03*
Y1134435D03*
Y1136935D03*
Y1139435D03*
X1368933Y1125801D03*
X1371433D03*
X1368933Y1129301D03*
X1371433D03*
X1383024Y1152684D03*
X1376861D03*
X1375633Y1146935D03*
Y1144435D03*
Y1141935D03*
X1383366D03*
Y1146935D03*
Y1144435D03*
X1377390Y1244055D03*
Y1250760D03*
Y1254164D03*
X1372300Y1422900D03*
X1372157Y1461183D03*
Y1456452D03*
Y1465914D03*
Y1471806D03*
Y1476537D03*
Y1481268D03*
Y1487160D03*
Y1491891D03*
Y1496622D03*
Y1502515D03*
Y1507246D03*
Y1511977D03*
Y1558813D03*
Y1563544D03*
Y1568275D03*
Y1574167D03*
Y1578898D03*
Y1583629D03*
Y1589522D03*
Y1594253D03*
Y1604876D03*
Y1598984D03*
Y1609607D03*
Y1614338D03*
X1372000Y1644980D03*
X1391497Y109172D03*
X1394497D03*
X1393504Y106495D03*
X1397248Y116497D03*
X1386505Y133298D03*
X1397248Y130670D03*
Y123584D03*
X1393238Y146012D03*
X1395144Y141228D03*
X1397248Y137757D03*
X1398032Y150847D03*
X1400000Y247292D03*
X1392709Y253198D03*
X1391086Y577192D03*
X1400912Y581222D03*
Y591215D03*
X1391587Y627817D03*
X1388414Y675000D03*
X1388241Y722000D03*
X1396916Y862829D03*
X1395561Y876204D03*
X1396163Y868597D03*
X1398247Y926261D03*
X1390322Y1057998D03*
Y1055498D03*
X1392822D03*
Y1057998D03*
X1390322Y1060498D03*
Y1062998D03*
X1392822D03*
Y1060498D03*
X1399748Y1098518D03*
X1394496Y1098428D03*
X1388992Y1123101D03*
X1396992D03*
X1399492D03*
X1385866Y1131935D03*
Y1134435D03*
Y1136935D03*
Y1139435D03*
X1388992Y1125801D03*
X1397392D03*
X1399892D03*
X1387392Y1129301D03*
X1389892D03*
X1392392D03*
X1394892D03*
X1397392D03*
X1399892D03*
X1391856Y1155213D03*
Y1152713D03*
X1385866Y1141935D03*
Y1146935D03*
Y1144435D03*
X1393695Y1204405D03*
Y1206905D03*
Y1211905D03*
Y1209405D03*
X1385992Y1285466D03*
X1390492D03*
X1392000Y1644980D03*
X1409248Y109410D03*
Y102323D03*
X1404548Y116497D03*
X1402048D03*
X1404548Y109410D03*
X1409248Y116496D03*
X1402048Y130670D03*
Y123584D03*
X1404548Y123583D03*
X1409248Y130670D03*
Y123583D03*
X1404548Y130670D03*
X1409248Y137756D03*
X1402048Y137757D03*
X1408666Y324733D03*
X1411950Y448466D03*
X1408103Y555194D03*
X1410903D03*
X1408103Y563194D03*
X1410903D03*
X1408103Y571194D03*
X1410903D03*
X1406512Y581222D03*
X1403712D03*
Y591215D03*
X1406512D03*
X1405514Y611091D03*
X1405000Y656000D03*
Y699000D03*
X1404689Y910897D03*
X1413575Y915186D03*
X1413322Y958908D03*
X1404317Y989436D03*
X1411038Y985379D03*
X1404936Y1098767D03*
X1415494Y1139435D03*
Y1136935D03*
Y1134435D03*
Y1131935D03*
X1409092Y1136935D03*
Y1134435D03*
Y1139435D03*
Y1131935D03*
X1402392Y1125801D03*
X1404892D03*
X1402392Y1129301D03*
X1404892D03*
X1409092Y1141935D03*
X1416736Y1152713D03*
Y1155213D03*
X1402256D03*
Y1152713D03*
X1415494Y1144435D03*
Y1146935D03*
Y1141935D03*
X1409092Y1146935D03*
Y1144435D03*
X1407995Y1204617D03*
X1410310Y1200821D03*
Y1198321D03*
X1407995Y1207117D03*
Y1209617D03*
Y1212117D03*
X1415903Y1282590D03*
X1404019Y1285290D03*
X1414346Y1303020D03*
X1412000Y1644980D03*
X1417710Y82984D03*
Y75184D03*
Y77784D03*
Y80384D03*
X1420264Y92849D03*
X1417710Y85584D03*
X1427224Y103037D03*
X1427358Y116496D03*
Y109410D03*
Y130670D03*
Y123583D03*
X1423515Y137756D03*
X1429539Y293796D03*
X1432039D03*
X1431019Y434508D03*
X1427019D03*
X1424196Y446352D03*
X1428782Y445874D03*
X1417856Y455466D03*
X1433310Y504699D03*
X1430810D03*
X1433012Y516979D03*
X1430512D03*
X1427233Y628183D03*
X1424389Y627948D03*
X1426000Y709000D03*
Y713000D03*
Y757000D03*
Y753000D03*
X1422813Y910065D03*
X1424126Y900295D03*
X1427553Y939200D03*
X1427473Y965621D03*
X1420740Y1004766D03*
Y1000766D03*
Y1016266D03*
Y1030766D03*
X1420107Y1052514D03*
X1431876Y1098518D03*
X1426624Y1098428D03*
X1421120Y1123101D03*
X1429120D03*
X1431620D03*
X1422020Y1129301D03*
X1424520D03*
X1427020D03*
X1429520D03*
X1432020D03*
X1417994Y1139435D03*
Y1136935D03*
Y1134435D03*
Y1131935D03*
X1421120Y1125801D03*
X1429520D03*
X1432020D03*
X1419520Y1129301D03*
X1432384Y1155213D03*
Y1152713D03*
X1422984D03*
Y1155213D03*
X1417994Y1144435D03*
Y1146935D03*
Y1141935D03*
X1420625Y1204405D03*
Y1206905D03*
Y1209405D03*
X1425652Y1297411D03*
X1433386Y1343309D03*
X1428840Y1407740D03*
X1423065Y1508327D03*
X1432499Y1512175D03*
X1424245Y1543338D03*
X1425558Y1537432D03*
X1425260Y1558072D03*
X1433558Y1555366D03*
X1423701Y1563978D03*
X1432000Y1644980D03*
X1444641Y94017D03*
X1448641D03*
X1440641D03*
X1449761Y115401D03*
Y110445D03*
X1444769D03*
Y115401D03*
X1449761Y124618D03*
X1444769D03*
Y129574D03*
X1449761D03*
X1442682Y151540D03*
X1446332Y191941D03*
X1446199Y188727D03*
X1442956Y226141D03*
X1440156D03*
X1448026Y256535D03*
X1440053Y285690D03*
X1437553D03*
X1440053Y288190D03*
X1442853D03*
Y285690D03*
X1447079Y290755D03*
X1437553Y288190D03*
X1437758Y362584D03*
X1435019Y434508D03*
X1437757Y447201D03*
X1437879Y444269D03*
X1435810Y504699D03*
X1447036Y519518D03*
X1435512Y516979D03*
X1444536Y519518D03*
X1439536D03*
X1442036D03*
X1435241Y593796D03*
X1440930Y636005D03*
Y633205D03*
Y638805D03*
X1437784Y683532D03*
X1436567Y727532D03*
X1443000Y798500D03*
Y794500D03*
Y842500D03*
Y838500D03*
X1438188Y867633D03*
X1437703Y880067D03*
X1449072Y892581D03*
X1435288Y897500D03*
X1444453Y938806D03*
X1439449Y979009D03*
X1440610Y1021567D03*
X1435266Y1031522D03*
X1437064Y1098767D03*
X1441220Y1131935D03*
Y1139435D03*
Y1134435D03*
Y1136935D03*
X1434520Y1125801D03*
X1437020D03*
X1434520Y1129301D03*
X1437020D03*
X1441220Y1141935D03*
Y1144435D03*
Y1146935D03*
X1442448Y1152684D03*
X1434925Y1204617D03*
X1437240Y1200821D03*
Y1198321D03*
X1434925Y1207117D03*
Y1209617D03*
Y1212117D03*
X1436408Y1303462D03*
X1444438Y1308312D03*
X1439482D03*
X1441286Y1335776D03*
X1457718Y84140D03*
Y76140D03*
Y80140D03*
X1452650Y94017D03*
X1460163Y117557D03*
X1455171D03*
Y122513D03*
X1460163Y131731D03*
Y122513D03*
X1455171Y131731D03*
X1458262Y146461D03*
X1460163Y136687D03*
X1455171D03*
X1457164Y152367D03*
X1463547Y180527D03*
X1458864Y180572D03*
Y185165D03*
X1463502Y185121D03*
X1452832Y184619D03*
X1454812Y206760D03*
X1456026Y256535D03*
X1457056Y279208D03*
X1461160Y281307D03*
X1455079Y290755D03*
X1451079D03*
X1458982Y356861D03*
X1453000Y633450D03*
Y636250D03*
Y639050D03*
X1453032Y769032D03*
X1453775Y813032D03*
X1461241Y867475D03*
X1462694Y874859D03*
Y877859D03*
X1460472Y885985D03*
X1459420Y899226D03*
X1451005Y931848D03*
X1462819Y949996D03*
X1462000Y960378D03*
X1460655Y964253D03*
X1466076Y979746D03*
X1462388Y1006560D03*
X1455939Y1018368D03*
X1465503Y1030233D03*
X1460592Y1345691D03*
Y1350683D03*
X1465548Y1345691D03*
Y1350683D03*
X1460592Y1357603D03*
Y1362595D03*
X1465548Y1357603D03*
Y1362595D03*
X1460592Y1381801D03*
Y1374881D03*
Y1369889D03*
X1465548Y1381801D03*
Y1374881D03*
Y1369889D03*
X1460592Y1386793D03*
X1465548D03*
X1452000Y1644980D03*
X1480460Y60922D03*
X1475296Y55513D03*
X1471093Y117261D03*
X1478624Y113394D03*
X1481273Y110784D03*
X1481368Y130898D03*
X1478800Y180665D03*
Y172665D03*
X1467270Y192421D03*
X1478832Y200864D03*
Y212864D03*
Y216864D03*
Y221864D03*
X1480589Y252371D03*
X1473900Y433100D03*
X1478710Y685630D03*
X1473525Y710052D03*
X1474425Y716075D03*
X1479962Y727500D03*
X1471415Y748629D03*
X1474425Y760075D03*
X1473634Y864337D03*
X1481454Y911570D03*
X1474075Y920575D03*
X1474349Y949394D03*
X1468500Y974181D03*
X1479096Y997860D03*
X1471096D03*
X1475096D03*
X1467096D03*
X1471854Y1035088D03*
X1479624Y1035102D03*
X1468371Y1030701D03*
X1480193Y1102091D03*
X1474384D03*
X1480193Y1114691D03*
X1474384D03*
X1480193Y1127291D03*
X1474384D03*
X1480193Y1139891D03*
X1474384D03*
X1480193Y1152491D03*
X1474384D03*
X1480193Y1165091D03*
X1474384D03*
X1480193Y1177691D03*
X1474384D03*
X1480675Y1202103D03*
X1477788Y1350683D03*
Y1345691D03*
X1472832Y1350683D03*
Y1345691D03*
X1477788Y1357603D03*
Y1362595D03*
X1472832Y1357603D03*
Y1362595D03*
X1477788Y1381801D03*
Y1369795D03*
Y1374881D03*
X1472832Y1381801D03*
Y1369795D03*
Y1374881D03*
X1477788Y1386793D03*
Y1399079D03*
Y1393993D03*
X1472832Y1386793D03*
Y1393993D03*
Y1399079D03*
X1477788Y1405999D03*
Y1410991D03*
X1472832Y1405999D03*
Y1410991D03*
X1476094Y1465913D03*
Y1461182D03*
Y1456451D03*
Y1471805D03*
Y1481267D03*
Y1476536D03*
Y1491890D03*
Y1487159D03*
Y1496621D03*
Y1502514D03*
Y1511976D03*
Y1507245D03*
Y1563544D03*
Y1558813D03*
Y1568275D03*
Y1578898D03*
Y1574167D03*
Y1583629D03*
Y1594253D03*
Y1589522D03*
Y1609607D03*
Y1598984D03*
Y1604876D03*
Y1614338D03*
X1472000Y1644980D03*
X1493859Y109172D03*
X1496859D03*
X1495866Y106495D03*
X1488867Y133298D03*
X1495600Y146012D03*
X1497506Y141228D03*
X1483014Y134579D03*
X1495071Y253198D03*
X1486360Y358700D03*
Y354200D03*
X1496473Y769000D03*
X1491062Y793003D03*
X1491425Y801575D03*
X1496845Y813000D03*
X1491425Y845575D03*
X1489650Y836985D03*
X1489805Y866386D03*
X1497488Y873839D03*
X1491414Y875383D03*
X1494000Y884000D03*
X1498084Y894825D03*
X1492101Y894860D03*
X1496383Y898023D03*
X1496500Y919000D03*
X1496000Y922000D03*
X1487075Y920925D03*
X1485100Y943900D03*
X1496425Y943075D03*
X1496072Y950044D03*
X1482591Y961909D03*
X1486500Y947000D03*
X1485226Y973886D03*
X1492560Y974654D03*
X1495339Y1009354D03*
X1491839D03*
X1486030D03*
X1491096Y997860D03*
X1483096D03*
X1495096D03*
X1487096D03*
X1495339Y1021954D03*
X1491839D03*
X1486030D03*
X1483693Y1102091D03*
Y1114691D03*
Y1127291D03*
Y1139891D03*
Y1152491D03*
Y1165091D03*
Y1177691D03*
X1498197Y1209607D03*
X1492471Y1215195D03*
X1484055Y1223749D03*
X1497312Y1350683D03*
Y1345691D03*
X1485072D03*
Y1350683D03*
X1490028Y1345691D03*
Y1350683D03*
X1497312Y1357603D03*
Y1362595D03*
X1485072D03*
Y1357603D03*
X1490028D03*
Y1362595D03*
X1485072Y1369889D03*
Y1374881D03*
Y1381801D03*
X1490028Y1369889D03*
Y1374881D03*
Y1381801D03*
X1497312D03*
Y1374881D03*
Y1369889D03*
Y1386793D03*
Y1394087D03*
Y1399079D03*
X1485072Y1394087D03*
Y1399079D03*
Y1386793D03*
X1490028Y1399079D03*
Y1394087D03*
Y1386793D03*
X1497312Y1405999D03*
Y1410991D03*
X1485072Y1405999D03*
Y1410991D03*
X1490028Y1405999D03*
Y1410991D03*
X1484755Y1465513D03*
Y1460782D03*
X1493417Y1465913D03*
Y1456451D03*
Y1461182D03*
Y1471805D03*
Y1476536D03*
Y1481267D03*
X1484755Y1476136D03*
Y1470244D03*
Y1480867D03*
Y1496221D03*
X1493417Y1487159D03*
Y1491890D03*
Y1496621D03*
X1484755Y1491490D03*
Y1485598D03*
Y1506845D03*
Y1500952D03*
Y1511576D03*
X1493417Y1507245D03*
Y1502514D03*
Y1511976D03*
X1484755Y1516307D03*
Y1563144D03*
X1493417Y1558813D03*
Y1563544D03*
Y1578898D03*
X1484755Y1567875D03*
Y1578498D03*
Y1572606D03*
X1493417Y1568275D03*
Y1574167D03*
X1484755Y1583229D03*
Y1593853D03*
Y1587960D03*
X1493417Y1583629D03*
Y1589522D03*
Y1594253D03*
X1484755Y1609207D03*
Y1598584D03*
Y1603315D03*
X1493417Y1609607D03*
Y1604876D03*
Y1598984D03*
X1484755Y1613938D03*
Y1618669D03*
X1493417Y1614338D03*
X1492000Y1644980D03*
X1511610Y116496D03*
Y109410D03*
Y102323D03*
X1499610Y116497D03*
X1506910D03*
X1504410D03*
X1506910Y109410D03*
X1511610Y123583D03*
X1499610Y130670D03*
Y123584D03*
X1506910Y130670D03*
X1504410D03*
Y123584D03*
X1506910Y123583D03*
X1511610Y130670D03*
Y137756D03*
X1499610Y137757D03*
X1504410D03*
X1500394Y150847D03*
X1502362Y247292D03*
X1501807Y323766D03*
X1507864Y450750D03*
X1511963Y536382D03*
X1510280Y899732D03*
X1514354Y938811D03*
X1510500Y931500D03*
X1513955Y950396D03*
X1505888Y965964D03*
X1514000Y968739D03*
X1510740Y973740D03*
X1507096Y997860D03*
X1503096D03*
X1511096D03*
X1499096D03*
X1505130Y1105091D03*
Y1117691D03*
Y1130291D03*
Y1142891D03*
Y1155491D03*
Y1168091D03*
Y1180691D03*
X1509552Y1350683D03*
Y1345691D03*
X1514508Y1350683D03*
Y1345691D03*
X1502268Y1350683D03*
Y1345691D03*
X1509552Y1362595D03*
Y1357603D03*
X1514508D03*
Y1362595D03*
X1502268Y1357603D03*
Y1362595D03*
X1509552Y1374881D03*
Y1369889D03*
Y1381801D03*
X1514508Y1374881D03*
Y1369889D03*
Y1381801D03*
X1502268D03*
Y1374881D03*
Y1369889D03*
X1509552Y1394087D03*
Y1399079D03*
Y1386793D03*
X1514508Y1394087D03*
Y1399079D03*
Y1386793D03*
X1502268D03*
Y1399079D03*
Y1394087D03*
X1509552Y1405999D03*
Y1410991D03*
X1514508Y1405999D03*
Y1410991D03*
X1502268Y1405999D03*
Y1410991D03*
X1502078Y1465513D03*
Y1460782D03*
X1510740Y1465913D03*
Y1456451D03*
Y1461182D03*
X1502078Y1470244D03*
Y1480867D03*
X1510740Y1471805D03*
Y1476536D03*
Y1481267D03*
X1502078Y1476136D03*
Y1491490D03*
Y1485598D03*
Y1496221D03*
X1510740Y1487159D03*
Y1491890D03*
Y1496621D03*
Y1507245D03*
Y1502514D03*
Y1511976D03*
X1502078Y1506845D03*
Y1500952D03*
Y1511576D03*
Y1516307D03*
X1510740Y1563544D03*
X1502078Y1563144D03*
X1510740Y1558813D03*
Y1578898D03*
X1502078Y1567875D03*
Y1578498D03*
Y1572606D03*
X1510740Y1568275D03*
Y1574167D03*
X1502078Y1583229D03*
Y1593853D03*
Y1587960D03*
X1510740Y1583629D03*
Y1589522D03*
Y1594253D03*
X1502078Y1609207D03*
Y1598584D03*
Y1603315D03*
X1510740Y1609607D03*
Y1604876D03*
Y1598984D03*
X1502078Y1613938D03*
Y1618669D03*
X1510740Y1614338D03*
X1512000Y1644980D03*
X1520072Y82984D03*
Y75184D03*
Y77784D03*
Y80384D03*
X1522626Y92849D03*
X1520072Y85584D03*
X1529586Y103037D03*
X1529720Y116496D03*
Y109410D03*
Y130670D03*
Y123583D03*
X1526311Y137756D03*
X1528635Y555234D03*
X1528350Y562003D03*
X1519156Y596095D03*
X1516869Y594668D03*
X1518354Y592354D03*
X1518415Y589556D03*
X1519153Y599588D03*
X1516930Y597580D03*
X1519185Y615600D03*
X1519153Y607588D03*
X1523646Y634946D03*
X1519063Y876339D03*
X1517344Y896999D03*
X1515743Y888133D03*
X1517344Y903179D03*
X1517153Y908367D03*
X1523000Y923740D03*
X1526611Y921442D03*
X1525740Y928740D03*
X1528087Y936394D03*
X1524500Y949500D03*
X1530174Y956986D03*
X1525522Y971075D03*
X1523966Y980281D03*
X1515096Y997860D03*
X1531096D03*
X1519096D03*
X1523096D03*
X1516776Y1024954D03*
Y1012354D03*
X1526748Y1345691D03*
Y1350683D03*
X1521792Y1345691D03*
Y1350683D03*
X1526748Y1357603D03*
Y1362595D03*
X1521792Y1357603D03*
Y1362595D03*
X1526748Y1369889D03*
Y1374881D03*
Y1381801D03*
X1521792Y1374881D03*
Y1381801D03*
Y1369889D03*
X1526748Y1386793D03*
Y1399079D03*
Y1394087D03*
X1521792Y1386793D03*
Y1394087D03*
Y1399079D03*
X1526748Y1405999D03*
Y1410991D03*
X1521792Y1405999D03*
Y1410991D03*
X1519401Y1465513D03*
Y1460782D03*
X1528062Y1465913D03*
Y1456451D03*
Y1461182D03*
Y1481267D03*
X1519401Y1476136D03*
Y1470244D03*
Y1480867D03*
X1528062Y1471805D03*
Y1476536D03*
X1519401Y1491490D03*
Y1485598D03*
Y1496221D03*
X1528062Y1487159D03*
Y1491890D03*
Y1496621D03*
X1519401Y1506845D03*
Y1500952D03*
Y1511576D03*
X1528062Y1507245D03*
Y1502514D03*
Y1511976D03*
X1519401Y1516307D03*
Y1563144D03*
X1528062Y1558813D03*
Y1563544D03*
Y1578898D03*
X1519401Y1567875D03*
Y1578498D03*
Y1572606D03*
X1528062Y1568275D03*
Y1574167D03*
X1519401Y1587960D03*
X1528062Y1583629D03*
Y1589522D03*
Y1594253D03*
X1519401Y1583229D03*
Y1593853D03*
Y1609207D03*
Y1598584D03*
Y1603315D03*
X1528062Y1609607D03*
Y1604876D03*
Y1598984D03*
X1519401Y1613938D03*
Y1618669D03*
X1528062Y1614338D03*
X1547003Y94017D03*
X1543003D03*
X1547131Y110445D03*
Y115401D03*
Y129574D03*
Y124618D03*
X1545044Y151540D03*
X1548561Y188727D03*
X1542518Y226141D03*
X1545318D03*
X1531901Y293796D03*
X1539915Y288190D03*
X1542415Y285690D03*
X1539915D03*
X1542415Y288190D03*
X1545215D03*
Y285690D03*
X1534401Y293796D03*
X1541283Y354553D03*
X1546272Y1350683D03*
Y1345691D03*
X1534032Y1350683D03*
Y1345691D03*
X1538988D03*
Y1350683D03*
X1546272Y1357603D03*
Y1362595D03*
X1534032Y1357603D03*
Y1362595D03*
X1538988D03*
Y1357603D03*
X1546272Y1374881D03*
Y1369889D03*
Y1381801D03*
X1534032Y1369889D03*
Y1381801D03*
Y1374881D03*
X1538988Y1369889D03*
Y1381801D03*
Y1374881D03*
X1546272Y1386793D03*
Y1394087D03*
Y1399079D03*
X1534032Y1394087D03*
Y1399079D03*
Y1386793D03*
X1538988Y1394087D03*
Y1399079D03*
Y1386793D03*
X1546272Y1405999D03*
Y1410991D03*
X1534032Y1405999D03*
Y1410991D03*
X1538988Y1405999D03*
Y1410991D03*
X1545385Y1461183D03*
X1536724Y1465513D03*
Y1460782D03*
X1545385Y1465914D03*
Y1456452D03*
X1536724Y1476136D03*
Y1470244D03*
Y1480867D03*
X1545385Y1476537D03*
Y1471806D03*
Y1481268D03*
X1536724Y1491490D03*
Y1485598D03*
Y1496221D03*
X1545385Y1491891D03*
Y1487160D03*
Y1496622D03*
X1536724Y1506845D03*
Y1500952D03*
Y1511576D03*
X1545385Y1507246D03*
Y1502515D03*
Y1511977D03*
X1536724Y1516307D03*
X1545385Y1563544D03*
Y1558813D03*
X1536724Y1563144D03*
Y1567875D03*
X1545385Y1568275D03*
X1536724Y1578498D03*
Y1572606D03*
X1545385Y1578898D03*
Y1574167D03*
Y1594253D03*
Y1589522D03*
X1536724Y1583229D03*
X1545385Y1583629D03*
X1536724Y1593853D03*
Y1587960D03*
Y1609207D03*
Y1598584D03*
Y1603315D03*
X1545385Y1609607D03*
Y1598984D03*
Y1604876D03*
Y1614338D03*
X1536724Y1613938D03*
Y1618669D03*
X1532000Y1644980D03*
X1560080Y84140D03*
Y76140D03*
Y80140D03*
X1555012Y94017D03*
X1551003D03*
X1562525Y117557D03*
X1557533D03*
X1552123Y115401D03*
Y110445D03*
X1562525Y122513D03*
X1552123Y129574D03*
Y124618D03*
X1557533Y131731D03*
Y122513D03*
X1562525Y131731D03*
X1560624Y146461D03*
X1557533Y136687D03*
X1562525D03*
X1559526Y152367D03*
X1561226Y180572D03*
X1548694Y191941D03*
X1555194Y184619D03*
X1561226Y185165D03*
X1557174Y206760D03*
X1550388Y256535D03*
X1558388D03*
X1559418Y279208D03*
X1563522Y281307D03*
X1549441Y290755D03*
X1553441D03*
X1557441D03*
X1554403Y352363D03*
X1563248Y389154D03*
X1548629D03*
Y403327D03*
Y410413D03*
X1561778Y396240D03*
X1548629D03*
Y417500D03*
Y424587D03*
Y438760D03*
Y431673D03*
Y445847D03*
Y467539D03*
Y474626D03*
Y488799D03*
Y481713D03*
Y495886D03*
Y511673D03*
Y518760D03*
X1562089Y516841D03*
X1548629Y540020D03*
Y525847D03*
Y532933D03*
Y547106D03*
X1556914Y552872D03*
X1557036Y550123D03*
X1556359Y562443D03*
X1558668Y572334D03*
X1558127Y560675D03*
X1556900Y574102D03*
X1547910Y602197D03*
X1548374Y595108D03*
X1561535Y653161D03*
X1565132Y677843D03*
X1547813Y906581D03*
X1551099Y959096D03*
X1558512Y1345691D03*
Y1350683D03*
X1563468D03*
Y1345691D03*
X1551228Y1350683D03*
Y1345691D03*
X1563468Y1362595D03*
X1551228Y1357603D03*
Y1362595D03*
X1558512D03*
Y1357603D03*
X1563468D03*
X1558512Y1374881D03*
Y1369889D03*
Y1381801D03*
X1563468Y1374881D03*
Y1369889D03*
Y1381801D03*
X1551228Y1369889D03*
Y1381801D03*
Y1374881D03*
X1558512Y1399079D03*
Y1394087D03*
Y1386793D03*
X1563468Y1399079D03*
Y1394087D03*
Y1386793D03*
X1551228D03*
Y1394087D03*
Y1399079D03*
X1558512Y1405999D03*
Y1410991D03*
X1563468Y1405999D03*
Y1410991D03*
X1551228Y1405999D03*
Y1410991D03*
X1552000Y1644980D03*
X1576256Y-25273D03*
X1573003Y-25287D03*
X1576241Y-27788D03*
X1572988Y-27802D03*
X1579281Y-26693D03*
X1573455Y117261D03*
X1565909Y180527D03*
X1569632Y192421D03*
X1565864Y185121D03*
X1571625Y333549D03*
X1579340Y396240D03*
Y403327D03*
Y410413D03*
X1566555Y414823D03*
X1565863Y422864D03*
X1579340Y417500D03*
Y424586D03*
X1565933Y429832D03*
X1565538Y436447D03*
X1579340Y431673D03*
Y438760D03*
X1567573Y447953D03*
X1579340Y445847D03*
X1566740Y467539D03*
X1565482Y472772D03*
X1579340Y474626D03*
Y488799D03*
X1566216Y487711D03*
X1566329Y479104D03*
X1579340Y481712D03*
Y495886D03*
X1566740D03*
X1579340Y518760D03*
X1565050Y511673D03*
X1579340Y540020D03*
Y532933D03*
Y525846D03*
X1574222Y629872D03*
X1569926Y668885D03*
X1575950Y662981D03*
X1570331Y691851D03*
X1575942Y705043D03*
X1575708Y1345597D03*
X1570752Y1350683D03*
Y1345597D03*
X1575708Y1350683D03*
X1570752Y1357603D03*
Y1362595D03*
X1575708D03*
Y1357603D03*
Y1381801D03*
Y1374881D03*
Y1369889D03*
X1570752D03*
Y1381801D03*
Y1374881D03*
X1575708Y1386793D03*
Y1399079D03*
Y1393993D03*
X1570752Y1386793D03*
Y1393993D03*
Y1399079D03*
X1575708Y1405999D03*
Y1410991D03*
X1570752Y1405999D03*
Y1410991D03*
X1572000Y1644980D03*
X1586256Y-64207D03*
X1583003D03*
X1586241Y-66722D03*
X1582988D03*
X1589281Y-65613D03*
X1582822Y60922D03*
X1580327Y57448D03*
X1580986Y113394D03*
X1583635Y110784D03*
X1591229Y133298D03*
X1583229D03*
X1585376Y134579D03*
X1581162Y180665D03*
Y172665D03*
X1581194Y212864D03*
Y200864D03*
Y221864D03*
Y216864D03*
X1582951Y252371D03*
X1586640Y389153D03*
X1581840D03*
Y403326D03*
Y410413D03*
X1586640D03*
X1581840Y396240D03*
X1586640D03*
Y403326D03*
Y417499D03*
X1581840D03*
Y424586D03*
X1586640D03*
X1581840Y438760D03*
X1586640D03*
Y431673D03*
X1581840D03*
X1586640Y467539D03*
X1581840D03*
Y474626D03*
X1586640D03*
X1581840Y488799D03*
X1586640D03*
X1581840Y481712D03*
X1586640D03*
X1581840Y518760D03*
Y511673D03*
X1586640D03*
Y518760D03*
Y525846D03*
Y532933D03*
X1581840D03*
Y525846D03*
X1595185Y543925D03*
X1595760Y555000D03*
X1583720Y560500D03*
X1587948Y1350683D03*
Y1345691D03*
X1582992D03*
Y1350683D03*
X1587948Y1362595D03*
Y1357603D03*
X1582992Y1362595D03*
Y1357603D03*
Y1369889D03*
Y1381801D03*
Y1374881D03*
X1587948Y1369889D03*
Y1381801D03*
Y1374881D03*
X1582992Y1399079D03*
Y1394087D03*
Y1386793D03*
X1587948Y1399079D03*
Y1394087D03*
Y1386793D03*
X1582992Y1405999D03*
Y1410991D03*
X1587948Y1405999D03*
Y1410991D03*
X1592020Y1433061D03*
X1591610Y1469940D03*
X1591586Y1505130D03*
X1609272Y109410D03*
X1601972Y116497D03*
X1609272D03*
X1606772D03*
X1596221Y109172D03*
X1599221D03*
X1598228Y106495D03*
X1601972Y123584D03*
Y130670D03*
X1606772Y123584D03*
X1609272Y123583D03*
Y130670D03*
X1606772D03*
Y137757D03*
X1597962Y146012D03*
X1599868Y141228D03*
X1601972Y137757D03*
X1602756Y150847D03*
X1604724Y247292D03*
X1597433Y253198D03*
X1608240Y329000D03*
X1603664Y342596D03*
X1598223Y351003D03*
X1599127Y375587D03*
X1596714Y383003D03*
X1614338Y636842D03*
X1610620Y1345691D03*
Y1350683D03*
Y1357603D03*
Y1362595D03*
Y1381801D03*
Y1374881D03*
Y1369889D03*
Y1386793D03*
X1597225Y1437014D03*
X1603363Y1460570D03*
X1597457Y1452556D03*
X1598500Y1472500D03*
X1606745Y1474242D03*
X1602580Y1483108D03*
X1598000Y1486000D03*
X1604000Y1516000D03*
X1600700Y1534300D03*
X1622434Y82984D03*
Y80384D03*
Y75184D03*
Y77784D03*
X1624988Y92849D03*
X1622434Y85584D03*
X1613972Y116496D03*
Y102323D03*
Y109410D03*
Y130670D03*
Y123583D03*
Y137756D03*
X1625952Y431029D03*
X1626260Y427017D03*
X1625018Y435029D03*
X1625938Y449873D03*
X1625565Y472579D03*
Y479666D03*
Y486752D03*
Y493839D03*
Y523800D03*
Y516713D03*
Y537973D03*
Y530886D03*
Y566752D03*
Y588013D03*
Y573839D03*
Y580926D03*
Y602186D03*
Y595099D03*
Y609272D03*
Y616359D03*
X1620244Y638125D03*
X1617843Y665140D03*
X1613110Y678462D03*
X1624148Y708258D03*
X1627455Y759489D03*
X1619612Y783152D03*
X1620359Y774830D03*
X1619569Y796035D03*
X1620755Y787530D03*
X1613235Y808466D03*
X1620479Y815730D03*
X1620072Y801630D03*
X1616255Y824405D03*
X1619859Y839519D03*
X1615576Y1345691D03*
Y1350683D03*
X1622860D03*
Y1345691D03*
X1627816Y1350683D03*
Y1345691D03*
X1615576Y1357603D03*
Y1362595D03*
X1622860Y1357603D03*
Y1362595D03*
X1627816Y1357603D03*
Y1362595D03*
X1622860Y1381801D03*
Y1369795D03*
Y1374881D03*
X1627816Y1381801D03*
Y1369795D03*
Y1374881D03*
X1615576Y1381801D03*
Y1374881D03*
Y1369889D03*
Y1386793D03*
X1622860D03*
Y1393993D03*
Y1399079D03*
X1627816Y1386793D03*
Y1399079D03*
Y1393993D03*
X1622860Y1405999D03*
Y1410991D03*
X1627816Y1405999D03*
Y1410991D03*
X1618800Y1528558D03*
X1614200Y1519500D03*
X1614360Y1542860D03*
X1618600Y1532000D03*
X1631948Y103037D03*
X1632082Y116496D03*
Y109410D03*
Y130670D03*
Y123583D03*
X1628673Y137756D03*
X1644880Y226141D03*
X1644777Y288190D03*
X1642277Y285690D03*
X1644777D03*
X1642277Y288190D03*
X1636763Y293796D03*
X1634263D03*
X1635987Y335616D03*
X1630703Y350655D03*
X1636468Y345595D03*
X1636271Y410394D03*
Y403307D03*
X1637665Y458406D03*
Y451319D03*
X1637489Y462264D03*
X1632865Y465492D03*
X1637665D03*
Y472579D03*
X1632865D03*
X1630365D03*
Y479666D03*
X1632865D03*
X1637665Y479665D03*
Y486752D03*
X1630365D03*
X1632865D03*
X1630365Y493839D03*
X1637665D03*
X1632865Y509626D03*
Y516713D03*
X1630365D03*
Y523800D03*
X1632865D03*
X1637665Y523799D03*
Y516713D03*
Y509626D03*
X1630365Y530886D03*
X1637665D03*
X1632865D03*
X1637665Y537973D03*
X1630365D03*
X1637665Y559665D03*
Y566752D03*
X1630365D03*
X1632865D03*
Y559665D03*
Y573839D03*
X1630365Y580926D03*
X1632865D03*
X1637665D03*
Y588012D03*
X1630365Y588013D03*
X1632865Y588012D03*
X1637665Y573839D03*
X1630365D03*
X1632865Y602185D03*
X1630365Y602186D03*
X1637665Y602185D03*
Y595099D03*
X1632865D03*
X1630365D03*
Y616359D03*
X1632865Y609272D03*
X1630365D03*
X1637665Y616358D03*
Y609272D03*
X1637526Y699930D03*
X1637472Y717830D03*
X1631031Y732430D03*
X1628813Y727045D03*
X1631187Y750630D03*
X1629969Y740826D03*
X1644304Y891353D03*
X1640056Y1345691D03*
Y1350683D03*
X1635100Y1345691D03*
Y1350683D03*
X1640056Y1357603D03*
Y1362595D03*
X1635100D03*
Y1357603D03*
X1640056Y1369889D03*
Y1374881D03*
Y1381801D03*
X1635100Y1369889D03*
Y1374881D03*
Y1381801D03*
X1640056Y1399079D03*
Y1394087D03*
Y1386793D03*
X1635100Y1394087D03*
Y1399079D03*
Y1386793D03*
Y1405999D03*
Y1410991D03*
X1640056Y1405999D03*
Y1410991D03*
X1649365Y94017D03*
X1657374D03*
X1653365D03*
X1645365D03*
X1659895Y117557D03*
X1654485Y110445D03*
Y115401D03*
X1649493Y110445D03*
Y115401D03*
X1659895Y122513D03*
Y131731D03*
X1654485Y124618D03*
Y129574D03*
X1649493Y124618D03*
Y129574D03*
X1659895Y136687D03*
X1647406Y151540D03*
X1651056Y191941D03*
X1657556Y184619D03*
X1650923Y188727D03*
X1659536Y206760D03*
X1647680Y226141D03*
X1660750Y256535D03*
X1652750D03*
X1647577Y285690D03*
Y288190D03*
X1655803Y290755D03*
X1651803D03*
X1659803D03*
X1645685Y390500D03*
X1655335Y381500D03*
X1653507Y470136D03*
X1655776Y465492D03*
X1655742Y460250D03*
X1655776Y472579D03*
Y486752D03*
Y479665D03*
Y493839D03*
Y509626D03*
Y516713D03*
X1652236Y537973D03*
X1654716Y525483D03*
X1654637Y532756D03*
X1655776Y559665D03*
Y566752D03*
X1655626Y579978D03*
X1655776Y573839D03*
X1655840Y608117D03*
X1654572Y771702D03*
X1645128Y929263D03*
X1645342Y962120D03*
X1657091Y990823D03*
X1649571Y983857D03*
X1647340Y1350683D03*
Y1345691D03*
X1652296Y1350683D03*
Y1345691D03*
X1659580Y1350683D03*
Y1345691D03*
X1647340Y1357603D03*
Y1362595D03*
X1652296Y1357603D03*
Y1362595D03*
X1659580D03*
Y1357603D03*
X1647340Y1381801D03*
Y1374881D03*
Y1369889D03*
X1652296Y1381801D03*
Y1374881D03*
Y1369889D03*
X1659580Y1374881D03*
Y1369889D03*
Y1381801D03*
X1647340Y1386793D03*
Y1394087D03*
Y1399079D03*
X1652296Y1386793D03*
Y1399079D03*
Y1394087D03*
X1659580D03*
Y1399079D03*
Y1386793D03*
X1647340Y1405999D03*
Y1410991D03*
X1652296Y1405999D03*
Y1410991D03*
X1659580Y1405999D03*
Y1410991D03*
X1657983Y1460782D03*
X1649322Y1456451D03*
Y1465913D03*
X1657983Y1465513D03*
X1649322Y1461182D03*
Y1476536D03*
X1657983Y1476136D03*
Y1470244D03*
X1649322Y1471805D03*
Y1481267D03*
X1657983Y1480867D03*
X1649322Y1487159D03*
Y1496621D03*
X1657983Y1496221D03*
X1649322Y1491890D03*
X1657983Y1491490D03*
Y1485598D03*
Y1500952D03*
X1649322Y1502514D03*
X1657983Y1511576D03*
X1649322Y1511976D03*
Y1507245D03*
X1657983Y1506845D03*
Y1516307D03*
X1649322Y1558813D03*
Y1563544D03*
X1657983Y1563144D03*
Y1572606D03*
X1649322Y1574167D03*
Y1568275D03*
X1657983Y1567875D03*
X1649322Y1578898D03*
X1657983Y1578498D03*
X1649322Y1583629D03*
X1657983Y1583229D03*
X1649322Y1594253D03*
X1657983Y1593853D03*
Y1587960D03*
X1649322Y1589522D03*
Y1609607D03*
X1657983Y1609207D03*
X1649322Y1598984D03*
X1657983Y1598584D03*
Y1603315D03*
X1649322Y1604876D03*
Y1614338D03*
X1657983Y1613938D03*
Y1618669D03*
X1652000Y1644980D03*
X1662442Y84140D03*
Y76140D03*
Y80140D03*
X1675817Y117261D03*
X1664887Y117557D03*
Y122513D03*
Y131731D03*
X1662986Y146461D03*
X1664887Y136687D03*
X1661888Y152367D03*
X1663588Y180572D03*
X1668271Y180527D03*
X1671994Y192421D03*
X1663588Y185165D03*
X1668226Y185121D03*
X1661780Y279208D03*
X1665884Y281307D03*
X1669767Y445908D03*
X1673717Y445787D03*
X1664536Y1350683D03*
Y1345691D03*
X1671820D03*
Y1350683D03*
X1676776Y1345691D03*
Y1350683D03*
X1664536Y1357603D03*
Y1362595D03*
X1671820Y1357603D03*
Y1362595D03*
X1676776Y1357603D03*
Y1362595D03*
X1664536Y1374881D03*
Y1369889D03*
Y1381801D03*
X1671820Y1374881D03*
Y1381801D03*
Y1369889D03*
X1676776D03*
Y1374881D03*
Y1381801D03*
X1664536Y1394087D03*
Y1399079D03*
Y1386793D03*
X1671820D03*
Y1394087D03*
Y1399079D03*
X1676776Y1386793D03*
Y1399079D03*
Y1394087D03*
X1664536Y1405999D03*
Y1410991D03*
X1671820Y1405999D03*
Y1410991D03*
X1676776Y1405999D03*
Y1410991D03*
X1666645Y1465913D03*
Y1456451D03*
Y1461182D03*
X1675306Y1465513D03*
Y1460782D03*
X1666645Y1471805D03*
Y1476536D03*
Y1481267D03*
X1675306Y1476136D03*
Y1470244D03*
Y1480867D03*
X1666645Y1487159D03*
Y1491890D03*
Y1496621D03*
X1675306Y1491490D03*
Y1485598D03*
Y1496221D03*
Y1511576D03*
X1666645Y1511976D03*
Y1507245D03*
Y1502514D03*
X1675306Y1506845D03*
Y1500952D03*
Y1516307D03*
X1666645Y1558813D03*
Y1563544D03*
X1675306Y1563144D03*
Y1578498D03*
Y1572606D03*
X1666645Y1568275D03*
X1675306Y1567875D03*
X1666645Y1574167D03*
Y1578898D03*
Y1583629D03*
X1675306Y1583229D03*
X1666645Y1589522D03*
Y1594253D03*
X1675306Y1593853D03*
Y1587960D03*
X1666645Y1604876D03*
Y1598984D03*
X1675306Y1609207D03*
Y1598584D03*
Y1603315D03*
X1666645Y1609607D03*
Y1614338D03*
X1675306Y1613938D03*
Y1618669D03*
X1672000Y1644980D03*
X1685184Y60922D03*
X1680020Y55513D03*
X1683348Y113394D03*
X1685997Y110784D03*
X1686171Y130898D03*
X1693591Y133298D03*
X1687738Y134579D03*
X1683524Y172665D03*
Y180665D03*
X1683556Y200864D03*
Y212864D03*
Y221864D03*
Y216864D03*
X1685313Y252371D03*
X1687164Y336324D03*
X1678072Y342319D03*
X1691743Y353506D03*
X1680518Y385912D03*
Y393924D03*
Y389912D03*
Y409924D03*
Y405924D03*
Y401924D03*
X1677933Y418838D03*
X1689016Y1345691D03*
Y1350683D03*
X1684060D03*
Y1345691D03*
X1689016Y1362595D03*
Y1357603D03*
X1684060D03*
Y1362595D03*
X1689016Y1369889D03*
Y1381801D03*
Y1374881D03*
X1684060Y1369889D03*
Y1381801D03*
Y1374881D03*
X1689016Y1394087D03*
Y1399079D03*
Y1386793D03*
X1684060Y1394087D03*
Y1399079D03*
Y1386793D03*
X1689016Y1405999D03*
Y1410991D03*
X1684060Y1405999D03*
Y1410991D03*
X1683968Y1465913D03*
Y1456451D03*
Y1461182D03*
X1692629Y1465513D03*
Y1460782D03*
X1683968Y1471805D03*
Y1476536D03*
Y1481267D03*
X1692629Y1476136D03*
Y1470244D03*
Y1480867D03*
X1683968Y1487159D03*
Y1491890D03*
Y1496621D03*
X1692629Y1491490D03*
Y1485598D03*
Y1496221D03*
X1683968Y1502514D03*
Y1511976D03*
X1692629Y1506845D03*
Y1500952D03*
Y1511576D03*
X1683968Y1507245D03*
X1692629Y1516307D03*
X1683968Y1558813D03*
Y1563544D03*
X1692629Y1563144D03*
Y1572606D03*
X1683968Y1568275D03*
Y1574167D03*
Y1578898D03*
X1692629Y1567875D03*
Y1578498D03*
X1683968Y1583629D03*
Y1589522D03*
Y1594253D03*
X1692629Y1583229D03*
Y1593853D03*
Y1587960D03*
X1683968Y1598984D03*
X1692629Y1609207D03*
Y1598584D03*
Y1603315D03*
X1683968Y1609607D03*
Y1604876D03*
Y1614338D03*
X1692629Y1613938D03*
Y1618669D03*
X1692000Y1644980D03*
X1698583Y109172D03*
X1701583D03*
X1700590Y106495D03*
X1709134Y116497D03*
X1704334D03*
X1709134Y123584D03*
Y130670D03*
X1704334Y123584D03*
Y130670D03*
X1700324Y146012D03*
X1702230Y141228D03*
X1709134Y137757D03*
X1704334D03*
X1705118Y150847D03*
X1707086Y247292D03*
X1699795Y253198D03*
X1701495Y289735D03*
X1695142Y303839D03*
X1708889Y1189221D03*
X1696300Y1350683D03*
Y1345691D03*
X1701256Y1350683D03*
Y1345691D03*
X1708540D03*
Y1350683D03*
X1696300Y1357603D03*
Y1362595D03*
X1701256Y1357603D03*
Y1362595D03*
X1708540D03*
Y1357603D03*
X1696300Y1374881D03*
Y1369889D03*
Y1381801D03*
X1701256Y1369889D03*
Y1381801D03*
Y1374881D03*
X1708540D03*
Y1369889D03*
Y1381801D03*
X1696300Y1386793D03*
Y1394087D03*
Y1399079D03*
X1701256Y1386793D03*
Y1394087D03*
Y1399079D03*
X1708540D03*
Y1394087D03*
Y1386793D03*
X1696300Y1405999D03*
Y1410991D03*
X1701256Y1405999D03*
Y1410991D03*
X1708540Y1405999D03*
Y1410991D03*
X1701290Y1465913D03*
Y1456451D03*
Y1461182D03*
Y1471805D03*
Y1476536D03*
Y1481267D03*
Y1487159D03*
Y1491890D03*
Y1496621D03*
Y1507245D03*
Y1502514D03*
Y1511976D03*
Y1558813D03*
Y1563544D03*
Y1568275D03*
Y1574167D03*
Y1578898D03*
Y1583629D03*
Y1589522D03*
Y1594253D03*
Y1609607D03*
Y1604876D03*
Y1598984D03*
Y1614338D03*
X1724796Y82984D03*
Y77784D03*
Y80384D03*
Y75184D03*
Y85584D03*
X1716334Y116496D03*
Y109410D03*
Y102323D03*
X1711634Y116497D03*
Y109410D03*
X1716334Y130670D03*
Y123583D03*
X1711634D03*
Y130670D03*
X1716334Y137756D03*
X1720960Y1148000D03*
X1723796Y1160168D03*
X1725660Y1193019D03*
X1721660D03*
X1711783Y1193848D03*
X1713496Y1350683D03*
Y1345691D03*
X1720780Y1350683D03*
Y1345597D03*
X1725736Y1350683D03*
Y1345597D03*
X1713496Y1357603D03*
Y1362595D03*
X1720780Y1357603D03*
Y1362595D03*
X1725736Y1357603D03*
Y1362595D03*
X1713496Y1374881D03*
Y1369889D03*
Y1381801D03*
X1720780Y1369889D03*
Y1381801D03*
Y1374881D03*
X1725736Y1381801D03*
Y1374881D03*
Y1369889D03*
X1713496Y1399079D03*
Y1394087D03*
Y1386793D03*
X1720780D03*
Y1393993D03*
Y1399079D03*
X1725736Y1386793D03*
Y1399079D03*
Y1393993D03*
X1713496Y1405999D03*
Y1410991D03*
X1720780Y1405999D03*
Y1410991D03*
X1725736Y1405999D03*
Y1410991D03*
X1709952Y1465513D03*
Y1460782D03*
X1718613Y1465914D03*
Y1456452D03*
Y1461183D03*
Y1476537D03*
Y1471806D03*
Y1481268D03*
X1709952Y1476136D03*
Y1470244D03*
Y1480867D03*
Y1491490D03*
Y1485598D03*
Y1496221D03*
X1718613Y1491891D03*
Y1487160D03*
Y1496622D03*
Y1502515D03*
Y1511977D03*
X1709952Y1506845D03*
Y1500952D03*
Y1511576D03*
X1718613Y1507246D03*
X1709952Y1516307D03*
Y1563144D03*
X1718613Y1563544D03*
Y1558813D03*
X1709952Y1567875D03*
X1718613Y1568275D03*
X1709952Y1578498D03*
Y1572606D03*
X1718613Y1578898D03*
Y1574167D03*
Y1589522D03*
X1709952Y1583229D03*
X1718613Y1583629D03*
X1709952Y1593853D03*
Y1587960D03*
X1718613Y1594253D03*
Y1609607D03*
Y1598984D03*
Y1604876D03*
X1709952Y1609207D03*
Y1598584D03*
Y1603315D03*
Y1618669D03*
X1718613Y1614338D03*
X1709952Y1613938D03*
X1712000Y1644980D03*
X1727350Y92849D03*
X1734310Y103037D03*
X1734444Y116496D03*
Y109410D03*
Y130670D03*
Y123583D03*
X1730647Y137756D03*
X1739125Y293796D03*
X1736625D03*
X1737703Y472189D03*
X1728038Y491870D03*
X1730538D03*
X1730675Y1132361D03*
X1726963Y1132319D03*
X1739917Y1146937D03*
X1729207Y1159455D03*
X1737393Y1162817D03*
X1733660Y1193019D03*
X1729660D03*
X1737660D03*
X1733695Y1212164D03*
X1735989Y1214458D03*
X1731619Y1210089D03*
X1740785Y1219254D03*
X1737976Y1350683D03*
Y1345691D03*
X1733020D03*
Y1350683D03*
X1737976Y1362595D03*
Y1357603D03*
X1733020Y1362595D03*
Y1357603D03*
X1737976Y1369889D03*
Y1374881D03*
X1733020Y1369889D03*
Y1381801D03*
Y1374881D03*
X1737976Y1381801D03*
Y1399079D03*
Y1394087D03*
Y1386793D03*
X1733020Y1399079D03*
Y1394087D03*
Y1386793D03*
X1737976Y1405999D03*
Y1410991D03*
X1733020Y1405999D03*
Y1410991D03*
X1732000Y1644980D03*
X1755727Y94017D03*
X1747727D03*
X1751727D03*
X1751855Y110445D03*
Y115401D03*
X1756847D03*
Y110445D03*
X1751855Y129574D03*
Y124618D03*
X1756847D03*
Y129574D03*
X1753418Y191941D03*
X1753285Y188727D03*
X1747242Y226141D03*
X1750042D03*
X1755112Y256535D03*
X1749939Y288190D03*
X1747139D03*
X1744639D03*
X1749939Y285690D03*
X1744639D03*
X1747139D03*
X1758165Y290755D03*
X1754165D03*
X1744524Y370010D03*
X1753474Y542699D03*
X1757402Y825111D03*
Y820155D03*
X1744937Y912517D03*
X1747937D03*
X1750751Y910785D03*
X1748081Y984379D03*
X1756192Y996132D03*
X1743224Y1119055D03*
X1752000Y1644980D03*
X1764804Y84140D03*
Y76140D03*
Y80140D03*
X1759736Y94017D03*
X1767249Y117557D03*
X1762257D03*
Y122513D03*
Y131731D03*
X1767249Y122513D03*
Y131731D03*
X1762257Y136687D03*
X1767249D03*
X1765950Y180572D03*
X1770633Y180527D03*
X1774356Y192421D03*
X1759918Y184619D03*
X1770588Y185121D03*
X1765950Y185165D03*
X1761898Y206760D03*
X1763112Y256535D03*
X1764142Y279208D03*
X1768246Y281307D03*
X1762165Y290755D03*
X1765497Y370899D03*
X1766204Y398949D03*
X1770778Y402642D03*
X1773278D03*
X1763704Y401949D03*
X1767953Y413611D03*
X1770453D03*
X1772953D03*
X1772893Y423944D03*
X1770393D03*
X1767893D03*
X1765093D03*
X1765153Y413611D03*
X1764912Y482382D03*
X1765006Y478382D03*
X1761953Y706827D03*
Y865160D03*
X1772599Y993053D03*
X1762898Y992883D03*
X1764744Y1101930D03*
Y1097879D03*
X1766899Y1121122D03*
X1769499D03*
X1772099D03*
X1774799D03*
X1766999Y1130822D03*
X1772199D03*
X1769599D03*
X1774339Y1437975D03*
X1774216Y1470165D03*
X1772000Y1644980D03*
X1788884Y59871D03*
X1782382Y55513D03*
X1778179Y117261D03*
X1785886Y172665D03*
Y180665D03*
X1785918Y200864D03*
Y212864D03*
Y216864D03*
Y221864D03*
X1790014Y468607D03*
X1784602Y564092D03*
X1782600Y874500D03*
X1774899Y1130822D03*
Y1139822D03*
X1777399D03*
Y1147822D03*
X1774899D03*
X1785961Y1224892D03*
X1791099Y1260421D03*
X1779868Y1446668D03*
X1786564Y1478858D03*
X1777131Y1604357D03*
X1791570Y74535D03*
X1793149Y662810D03*
X1798705Y718793D03*
X1805013Y1091877D03*
X1792847Y1099210D03*
X1799012Y1095893D03*
X1805013Y1096470D03*
X1792863Y1103246D03*
X1801147Y1208555D03*
X1802844Y1227695D03*
X1793976Y1440762D03*
X1807270Y1468535D03*
X1793879Y1472952D03*
X1792000Y1644980D03*
X1816322Y977215D03*
X1823074Y992833D03*
X1812296Y1075688D03*
X1809696Y1091832D03*
X1809651Y1096426D03*
X1823028Y1124289D03*
X1817728D03*
X1815128D03*
X1820328D03*
X1822928Y1114589D03*
X1820228D03*
X1815028D03*
X1817628D03*
X1815865Y1133356D03*
X1809897Y1237285D03*
Y1230385D03*
Y1232885D03*
Y1239785D03*
Y1244185D03*
Y1246685D03*
X1807393Y1436345D03*
X1812000Y1644980D03*
X1831511Y978888D03*
X1831914Y992877D03*
X1824706Y1081145D03*
Y1089145D03*
X1837933Y1636171D03*
X1832000Y1644980D03*
G54D36*
X141337Y1228542D03*
X141336Y1247242D03*
Y1239762D03*
X161909Y1129429D03*
X160039Y1228543D03*
X169389Y1121948D03*
X167519Y1198621D03*
Y1213582D03*
X174999Y1228543D03*
X182480D03*
X167519D03*
X189960D03*
X197440D03*
X210531Y1211712D03*
X212401Y1228543D03*
X204921D03*
X213969Y1453293D03*
Y1464293D03*
X218011Y1211712D03*
X227362Y1228543D03*
X219881D03*
X227249Y1464293D03*
Y1453293D03*
X294685Y1127558D03*
Y1135039D03*
Y1194881D03*
Y1202362D03*
X290944Y1191141D03*
X294685Y1209842D03*
X302165Y1108858D03*
X298425Y1112598D03*
X309645D03*
Y1120078D03*
X305905Y1116338D03*
X298425Y1120078D03*
X305905Y1123818D03*
X309645Y1135039D03*
Y1127558D03*
X311515Y1136909D03*
X304035Y1140649D03*
X305905Y1131299D03*
X296555Y1151869D03*
X304035Y1155610D03*
Y1148129D03*
X296555Y1144389D03*
X311515D03*
Y1151869D03*
X296555Y1159350D03*
Y1166830D03*
X304035Y1170570D03*
X300295D03*
X311515Y1159350D03*
X300295Y1185531D03*
Y1178051D03*
X296555Y1174310D03*
X298425Y1187401D03*
X304035Y1185531D03*
Y1178051D03*
Y1193011D03*
X302165Y1198621D03*
X305905Y1206102D03*
X302165Y1213582D03*
Y1206102D03*
X298425Y1221062D03*
Y1217322D03*
X317125Y1116338D03*
Y1123818D03*
X313385D03*
Y1116338D03*
X315255Y1136909D03*
X313384Y1131299D03*
X315255Y1144389D03*
Y1151869D03*
Y1159350D03*
Y1166830D03*
Y1181791D03*
Y1189271D03*
Y1174310D03*
X313385Y1198621D03*
Y1206102D03*
X320866Y1217322D03*
X317125Y1221062D03*
X313385Y1213582D03*
X324606Y1209842D03*
Y1217322D03*
X320866Y1221062D03*
X324606D03*
X320866Y1236023D03*
Y1224803D03*
X324606Y1232283D03*
Y1236023D03*
Y1224803D03*
Y1243503D03*
X598424Y1228542D03*
X598423Y1239762D03*
Y1247242D03*
X618996Y1129429D03*
X617126Y1228543D03*
X626476Y1121948D03*
X624606Y1198621D03*
Y1213582D03*
X632086Y1228543D03*
X624606D03*
X639567D03*
X647047D03*
X667618Y1211712D03*
X654527Y1228543D03*
X662008D03*
X669488D03*
X675098Y1211712D03*
X676968Y1228543D03*
X684449D03*
X729331Y1250984D03*
X721850D03*
Y1254724D03*
X729331D03*
X748031Y1194881D03*
X744291Y1254724D03*
Y1250984D03*
X736811Y1254724D03*
Y1250984D03*
X762992Y1116338D03*
X766732Y1120078D03*
X762992Y1123818D03*
X766732Y1112598D03*
X759252Y1108858D03*
X755512Y1120078D03*
X761122Y1140649D03*
X762992Y1131299D03*
X766732Y1135039D03*
Y1127558D03*
X751772D03*
Y1135039D03*
X753642Y1144389D03*
X761122Y1148129D03*
Y1155610D03*
X753642Y1151869D03*
X757382Y1170570D03*
X761122D03*
X753642Y1166830D03*
Y1159350D03*
Y1181791D03*
Y1174310D03*
X757382Y1178051D03*
Y1185531D03*
X761122Y1178051D03*
Y1185531D03*
X753642Y1189271D03*
X759252Y1191141D03*
X762992D03*
X755512Y1194881D03*
X759252Y1198621D03*
X751772Y1202362D03*
X755512Y1221062D03*
Y1217322D03*
X759252Y1213582D03*
X762992Y1206102D03*
X759252D03*
X751772Y1209842D03*
X770472Y1123818D03*
X774212D03*
X770472Y1116338D03*
X774212D03*
X770471Y1131299D03*
X770472Y1138779D03*
X772342Y1151869D03*
Y1144389D03*
X768602Y1151869D03*
Y1144389D03*
X772342Y1166830D03*
X768602Y1159350D03*
X772342D03*
Y1174310D03*
Y1181791D03*
Y1196751D03*
X770472Y1198621D03*
X781693Y1217322D03*
X777953D03*
X774212Y1221062D03*
X781693Y1209842D03*
X770472Y1213582D03*
Y1206102D03*
X781693Y1224803D03*
X777953D03*
X781693Y1232283D03*
X777953Y1236023D03*
X781693D03*
Y1243503D03*
X1055510Y1228542D03*
X1055509Y1239762D03*
Y1247242D03*
X1074212Y1228543D03*
X1083562Y1121948D03*
X1076082Y1129429D03*
X1081692Y1198621D03*
Y1213582D03*
Y1228543D03*
X1089172D03*
X1104133D03*
X1096653D03*
X1124704Y1211712D03*
X1119094Y1228543D03*
X1111613D03*
X1132184Y1211712D03*
X1126574Y1228543D03*
X1134054D03*
X1141535D03*
X1203247Y1193011D03*
X1216338Y1108858D03*
X1212598Y1120078D03*
X1220078Y1116338D03*
Y1123818D03*
X1218208Y1140649D03*
X1208858Y1127558D03*
X1220078Y1131299D03*
X1208858Y1135039D03*
X1210728Y1151869D03*
X1218208Y1155610D03*
Y1148129D03*
X1210728Y1144389D03*
Y1159350D03*
Y1166830D03*
X1218208Y1170570D03*
X1214468D03*
X1210728Y1181791D03*
Y1189271D03*
X1218208Y1185531D03*
Y1178051D03*
X1214468Y1185531D03*
Y1178051D03*
X1210728Y1174310D03*
X1212598Y1194881D03*
X1218208Y1193011D03*
X1214468D03*
X1216338Y1198621D03*
X1208858Y1202362D03*
X1220078Y1206102D03*
X1216338D03*
X1212598Y1221062D03*
Y1217322D03*
X1216338Y1213582D03*
X1208858Y1209842D03*
X1223818Y1112598D03*
Y1120078D03*
X1227558Y1116338D03*
X1231298D03*
X1227558Y1123818D03*
X1231298D03*
X1229428Y1136909D03*
X1223818Y1127558D03*
X1227557Y1131299D03*
X1223818Y1135039D03*
X1225688Y1144389D03*
Y1151869D03*
X1229428Y1144389D03*
Y1151869D03*
Y1159350D03*
X1225688D03*
X1229428Y1166830D03*
Y1181791D03*
Y1189271D03*
Y1174310D03*
Y1196751D03*
X1227558Y1198621D03*
Y1206102D03*
X1235039Y1217322D03*
X1231298Y1221062D03*
X1227558Y1213582D03*
X1235039Y1221062D03*
Y1224803D03*
Y1236023D03*
X1238779Y1217322D03*
Y1209842D03*
Y1221062D03*
Y1224803D03*
Y1232283D03*
Y1236023D03*
Y1243503D03*
X1514468Y1166829D03*
Y1174309D03*
Y1181790D03*
X1512597Y1228542D03*
X1512596Y1239762D03*
Y1247242D03*
X1540649Y1121948D03*
X1533169Y1129429D03*
X1538779Y1198621D03*
Y1213582D03*
X1531299Y1228543D03*
X1538779D03*
X1546259D03*
X1561220D03*
X1553740D03*
X1576181D03*
X1568700D03*
X1589271Y1211712D03*
X1581791D03*
X1583661Y1228543D03*
X1591141D03*
X1598622D03*
X1636023Y1254724D03*
Y1250984D03*
X1643504D03*
Y1254724D03*
X1660334Y1204232D03*
Y1200491D03*
Y1193011D03*
Y1196751D03*
Y1207972D03*
X1650984Y1250984D03*
Y1254724D03*
X1658464D03*
Y1250984D03*
X1673425Y1108858D03*
X1669685Y1112598D03*
Y1120078D03*
X1675295Y1140649D03*
X1665945Y1127558D03*
Y1135039D03*
X1667815Y1151869D03*
X1675295Y1155610D03*
Y1148129D03*
X1667815Y1144389D03*
Y1159350D03*
Y1166830D03*
X1675295Y1170570D03*
X1671555D03*
Y1185531D03*
Y1178051D03*
X1667815Y1174310D03*
Y1181791D03*
Y1189271D03*
X1675295Y1185531D03*
Y1178051D03*
X1669685Y1194881D03*
X1675295Y1193011D03*
X1671555D03*
X1665945Y1202362D03*
X1673425Y1198621D03*
X1669685Y1221062D03*
Y1217322D03*
X1673425Y1213582D03*
X1665945Y1209842D03*
X1673425Y1206102D03*
X1677165Y1116338D03*
X1680905Y1112598D03*
X1677165Y1123818D03*
X1680905Y1120078D03*
X1684645Y1116338D03*
X1688385D03*
X1684645Y1123818D03*
X1688385D03*
X1686515Y1136909D03*
X1682775D03*
X1680905Y1127558D03*
X1677165Y1131299D03*
X1684644D03*
X1680905Y1135039D03*
X1682775Y1144389D03*
Y1151869D03*
X1686515Y1144389D03*
Y1151869D03*
Y1159350D03*
X1682775D03*
X1686515Y1166830D03*
Y1174310D03*
Y1181791D03*
Y1189271D03*
X1684645Y1198621D03*
X1692126Y1217322D03*
X1688385Y1221062D03*
X1684645Y1213582D03*
Y1206102D03*
X1677165D03*
X1692126Y1224803D03*
Y1236023D03*
X1695866Y1217322D03*
Y1209842D03*
Y1232283D03*
Y1236023D03*
Y1224803D03*
Y1243503D03*
G54D27*
X73872Y1348187D03*
X81752D03*
X73872Y1360099D03*
X81752D03*
X73872Y1384297D03*
Y1372385D03*
X81752Y1384297D03*
Y1372385D03*
X86112Y1348187D03*
X98352D03*
X93992D03*
X86112Y1360099D03*
X98352D03*
X93992D03*
X86112Y1384297D03*
Y1372385D03*
X98352Y1384297D03*
Y1372385D03*
X93992D03*
Y1384297D03*
X86112Y1396583D03*
X93992D03*
X98352D03*
X86112Y1408495D03*
X93992D03*
X98352D03*
X110592Y1348187D03*
X106232D03*
X110592Y1360099D03*
X106232D03*
X110592Y1384297D03*
X106232D03*
Y1372385D03*
X110592D03*
Y1396583D03*
X106232D03*
X110592Y1408495D03*
X106232D03*
X118472Y1348187D03*
X122832D03*
X130712D03*
X118472Y1360099D03*
X122832D03*
X130712D03*
X118472Y1384297D03*
Y1372385D03*
X122832Y1384297D03*
Y1372385D03*
X130712Y1384297D03*
Y1372385D03*
X118472Y1396583D03*
X122832D03*
X130712D03*
X118472Y1408495D03*
X122832D03*
X130712D03*
X146948Y1080806D03*
Y1103247D03*
X143208D03*
X146948Y1133169D03*
Y1140649D03*
X139468Y1136909D03*
X143208Y1125688D03*
Y1133169D03*
Y1140649D03*
X146948Y1125688D03*
X143208Y1144389D03*
Y1151870D03*
X146948Y1144389D03*
Y1151870D03*
X140707Y1170569D03*
X143208Y1159350D03*
X146948D03*
X148818Y1183661D03*
X140707Y1178050D03*
X145078Y1187401D03*
Y1183661D03*
X148818Y1187401D03*
X146947Y1174310D03*
X141337Y1191142D03*
X145078Y1194881D03*
Y1202362D03*
X148818Y1194881D03*
Y1202362D03*
X141337Y1198622D03*
Y1206103D03*
X145078Y1209842D03*
Y1217322D03*
X148818Y1209842D03*
Y1217322D03*
X141337Y1213583D03*
Y1221063D03*
X148818Y1224803D03*
X145078Y1232283D03*
Y1236023D03*
X148818Y1232283D03*
Y1236023D03*
X145078Y1224803D03*
X148818Y1254724D03*
X135072Y1348187D03*
X142952D03*
X147312D03*
X135072Y1360099D03*
X147312D03*
X142952D03*
X135072Y1384297D03*
Y1372385D03*
X147312Y1384297D03*
Y1372385D03*
X142952Y1384297D03*
Y1372385D03*
X135072Y1396583D03*
X147312D03*
X142952D03*
X135072Y1408495D03*
X147312D03*
X142952D03*
X150688Y1077066D03*
X158169Y1106988D03*
X165649D03*
X161909D03*
X158169Y1118208D03*
Y1121948D03*
X154429D03*
X150689D03*
X165649Y1114468D03*
X161909D03*
X158169Y1133169D03*
X161909Y1140649D03*
X158169Y1125688D03*
X154429Y1129429D03*
X150689D03*
Y1136909D03*
X154429Y1140649D03*
X150689D03*
X165649D03*
Y1129429D03*
Y1136909D03*
X158169Y1140649D03*
X150689Y1151870D03*
X158169Y1155610D03*
X154429D03*
X150689D03*
X161909Y1144389D03*
Y1148129D03*
Y1151870D03*
Y1155610D03*
X150689Y1144389D03*
Y1148129D03*
Y1159350D03*
X158169Y1166830D03*
X150688D03*
X154429Y1170570D03*
X150688D03*
X161909Y1159350D03*
X160039Y1187401D03*
X156299Y1183661D03*
X152559D03*
X161909Y1174310D03*
Y1178051D03*
X165649Y1181791D03*
X161909D03*
X158169Y1174310D03*
X154429D03*
X150688Y1178051D03*
Y1174310D03*
X156299Y1179921D03*
X160039Y1183661D03*
X163779D03*
X156299Y1198621D03*
X152559D03*
X163779D03*
X160039D03*
X152559Y1191141D03*
X156299D03*
X160039D03*
X163779D03*
X160039Y1206102D03*
X156299D03*
X152559D03*
X163779D03*
X156299Y1213582D03*
X152559D03*
X160039Y1221062D03*
X156299D03*
X152559D03*
X163779D03*
X152559Y1228543D03*
X160039Y1224803D03*
X152559D03*
X156299Y1232283D03*
Y1236023D03*
X163779D03*
Y1232283D03*
X160039Y1239763D03*
X152559D03*
Y1243503D03*
X160039D03*
X163779Y1239763D03*
X152559Y1258465D03*
X160039D03*
X159552Y1348187D03*
X155192D03*
X159552Y1360099D03*
X155192D03*
X159552Y1372385D03*
Y1384297D03*
X155192D03*
Y1372385D03*
X159552Y1396583D03*
X155192D03*
X159552Y1408495D03*
X155192D03*
X174998Y1071455D03*
X182479D03*
X178740Y1090157D03*
X174999D03*
X171259D03*
X182480D03*
X178740Y1093897D03*
Y1097637D03*
X174999Y1101377D03*
X169389Y1106988D03*
X171259Y1093897D03*
X174999Y1105117D03*
X182480Y1101377D03*
Y1105117D03*
X174999Y1108858D03*
X178740D03*
X176870Y1114468D03*
Y1118208D03*
Y1121948D03*
X178740Y1112598D03*
X173129Y1110728D03*
X169389D03*
X180610Y1114468D03*
Y1118208D03*
Y1121948D03*
X182480Y1112598D03*
Y1108858D03*
X180610Y1136909D03*
X173129Y1133169D03*
X169389D03*
X176870Y1140649D03*
Y1125688D03*
Y1129429D03*
Y1133169D03*
Y1136909D03*
X173129Y1140649D03*
X169389D03*
X180610D03*
Y1125688D03*
Y1129429D03*
Y1133169D03*
Y1148129D03*
X173129Y1144389D03*
X169389D03*
X173129Y1148129D03*
Y1155610D03*
Y1151870D03*
X180610Y1155610D03*
Y1151870D03*
Y1144389D03*
X176870Y1170570D03*
X173129Y1159350D03*
Y1166830D03*
Y1170570D03*
X180610Y1166830D03*
Y1159350D03*
Y1174310D03*
Y1181791D03*
X173129Y1174310D03*
Y1178051D03*
Y1181791D03*
X171259Y1187401D03*
X174999D03*
X180610Y1178051D03*
X167519Y1183661D03*
X178740Y1187401D03*
X182480D03*
X176870Y1185531D03*
X173129D03*
X171259Y1202362D03*
Y1194881D03*
X174999Y1202362D03*
Y1194881D03*
X167519Y1191141D03*
X178740D03*
Y1194881D03*
Y1198621D03*
Y1202362D03*
X182480Y1191141D03*
Y1198621D03*
Y1202362D03*
X171259Y1209842D03*
X174999Y1217322D03*
X171259Y1221062D03*
X174999D03*
X171259Y1217322D03*
X167519Y1206102D03*
X178740D03*
Y1209842D03*
Y1213582D03*
Y1221062D03*
X182480D03*
X178740Y1217322D03*
X182480Y1206102D03*
Y1209842D03*
Y1213582D03*
Y1217322D03*
X178740Y1228543D03*
X171259Y1224803D03*
Y1228543D03*
X178740Y1224803D03*
Y1232283D03*
Y1236023D03*
X171259Y1232283D03*
X174999Y1224803D03*
X171259Y1236023D03*
X182480Y1224803D03*
X167519D03*
X182480Y1243503D03*
X171259Y1250984D03*
X174999Y1247243D03*
Y1239763D03*
X171259D03*
X167519D03*
Y1243503D03*
X175000Y1258465D03*
X182480D03*
X167519D03*
X167432Y1348187D03*
X171792D03*
X179672D03*
X167432Y1360099D03*
X171792D03*
X179672D03*
X167432Y1384297D03*
Y1372385D03*
X171792Y1384297D03*
Y1372385D03*
X179672Y1384297D03*
Y1372385D03*
X171792Y1396583D03*
X179672D03*
X167432D03*
Y1408495D03*
X171792D03*
X179672D03*
X197439Y1071455D03*
X189959D03*
X193700Y1090157D03*
X189960D03*
X186220D03*
X197440D03*
X193700Y1093897D03*
X189960Y1101377D03*
X186220Y1097637D03*
X189960Y1105117D03*
X186220Y1093897D03*
X193700Y1097637D03*
X197440Y1101377D03*
Y1105117D03*
X189960Y1093897D03*
X195570Y1121948D03*
X191830Y1118208D03*
X188090D03*
X184350D03*
X191830Y1121948D03*
X188090D03*
X184350D03*
X195570Y1118208D03*
X186220Y1108858D03*
X189960D03*
X193700D03*
X197440D03*
X191830Y1125688D03*
X188090D03*
X184350D03*
X188090Y1129429D03*
X184350D03*
X188090Y1133169D03*
X184350D03*
X188090Y1136909D03*
Y1140649D03*
X184350D03*
X195570Y1133169D03*
Y1129429D03*
Y1125688D03*
Y1136909D03*
X188090Y1144389D03*
Y1151870D03*
X191830Y1155610D03*
Y1148129D03*
X195570Y1151869D03*
Y1144389D03*
X188090Y1159350D03*
Y1170570D03*
X191830Y1166830D03*
X195570Y1159350D03*
Y1170570D03*
X188090Y1185531D03*
X195570Y1189271D03*
X191830Y1181791D03*
Y1174310D03*
X195570Y1185531D03*
Y1178051D03*
X188090Y1196751D03*
Y1200491D03*
Y1204232D03*
X191830D03*
Y1196751D03*
Y1200491D03*
X184350Y1193011D03*
Y1196751D03*
X195570Y1200491D03*
Y1196751D03*
Y1193011D03*
Y1204232D03*
X186220Y1198621D03*
X193700Y1209842D03*
X191830Y1207972D03*
X189960Y1209842D03*
X195570Y1207972D03*
X193700Y1213582D03*
X191830Y1219192D03*
X186220Y1221062D03*
X189960D03*
X193700D03*
X197440D03*
X186220Y1206102D03*
Y1209842D03*
Y1213582D03*
X197440Y1209842D03*
X186220Y1224803D03*
X193700Y1228543D03*
X197440Y1224803D03*
X193700Y1232283D03*
X186220D03*
X189960Y1224803D03*
X193700Y1236023D03*
X186220D03*
Y1228543D03*
X193700Y1224803D03*
X197440Y1239763D03*
Y1243503D03*
X193700Y1239763D03*
X186220D03*
X189960Y1243503D03*
Y1258465D03*
X197441D03*
X184032Y1348187D03*
X191912D03*
X196272D03*
X184032Y1360099D03*
X196272D03*
X191912D03*
X184032Y1384297D03*
Y1372385D03*
X196272Y1384297D03*
Y1372385D03*
X191912Y1384297D03*
Y1372385D03*
X184032Y1396583D03*
X191912D03*
X196272D03*
X184032Y1408495D03*
X191912D03*
X196272D03*
X204920Y1071455D03*
X212400D03*
X204921Y1090157D03*
X212401D03*
X208661D03*
X201181D03*
X204921Y1101377D03*
X208661Y1097637D03*
X201181D03*
X204921Y1105117D03*
X212401Y1101377D03*
Y1105117D03*
X201181Y1093897D03*
X208661D03*
X199311Y1118208D03*
Y1121948D03*
X206791Y1118208D03*
X203051D03*
Y1121948D03*
X206791D03*
X210531Y1118208D03*
X214271Y1110728D03*
X210531Y1121948D03*
X214271Y1118208D03*
Y1121948D03*
X201181Y1108858D03*
X204921D03*
X208661D03*
X212401D03*
X199311Y1140649D03*
X203051D03*
X206791D03*
X199311Y1125688D03*
X203051D03*
X206791D03*
Y1133169D03*
X203051D03*
X199311D03*
X210531D03*
Y1140649D03*
X214271D03*
Y1125688D03*
X210531D03*
X214271Y1133169D03*
X203051Y1148129D03*
X199311D03*
X206791D03*
X214271D03*
X210531D03*
X199311Y1155610D03*
X206791D03*
X214271D03*
X206791Y1166830D03*
X203051Y1159350D03*
X199311Y1166830D03*
X203051Y1170570D03*
X214271Y1166830D03*
X210531Y1159350D03*
Y1170570D03*
X206791Y1181791D03*
X203051D03*
X199311D03*
X206791Y1189271D03*
X203051D03*
X199311D03*
X214271Y1181791D03*
X210531D03*
X214271Y1189271D03*
X210531D03*
X199311Y1174310D03*
X206791D03*
X214271D03*
X206791Y1196751D03*
X203051D03*
X199311D03*
Y1204232D03*
X203051D03*
X206791D03*
X214271Y1196751D03*
X210531D03*
Y1204232D03*
X214271D03*
X206791Y1207972D03*
X203051D03*
X199311D03*
X210531D03*
X214271D03*
X212401Y1221062D03*
X208661D03*
X204921D03*
X201181D03*
Y1224803D03*
X208661Y1228543D03*
X212401Y1224803D03*
X208661Y1232283D03*
X201181D03*
X204921Y1224803D03*
X201181Y1236023D03*
X208661D03*
Y1224803D03*
X201181Y1228543D03*
X212401Y1243503D03*
X208661Y1239763D03*
X204921Y1243503D03*
X212401Y1258465D03*
X204921D03*
X204152Y1348187D03*
Y1360099D03*
Y1384297D03*
Y1372385D03*
Y1396583D03*
Y1408495D03*
X219880Y1071455D03*
X227361D03*
X227362Y1090157D03*
X223622D03*
X219881D03*
X231102D03*
X216141D03*
X223622Y1093897D03*
X231102D03*
Y1097637D03*
X227362Y1101377D03*
Y1105117D03*
X219881Y1101377D03*
Y1105117D03*
X223622Y1097637D03*
X216141D03*
Y1093897D03*
X225492Y1118208D03*
Y1121948D03*
X218011Y1118208D03*
X221751D03*
X218011Y1121948D03*
X221751D03*
X229232D03*
Y1118208D03*
Y1114468D03*
X216141Y1108858D03*
X219881D03*
X223622D03*
X227362D03*
X231102D03*
X225492Y1133169D03*
Y1140649D03*
Y1125688D03*
X218011Y1140649D03*
X221751D03*
X218011Y1125688D03*
X221751D03*
Y1133169D03*
X218011D03*
X229330Y1132677D03*
X229232Y1140649D03*
Y1125688D03*
X225492Y1148129D03*
X221751D03*
X218011D03*
X229232D03*
X221751Y1155610D03*
X229232D03*
X225492Y1170570D03*
Y1159350D03*
X218011Y1170570D03*
X221752Y1166830D03*
X218011Y1159350D03*
X229232Y1166830D03*
X225492Y1181791D03*
Y1189271D03*
X221751Y1181791D03*
X218011D03*
X221751Y1189271D03*
X218011D03*
X229232Y1181791D03*
Y1189271D03*
X221751Y1174310D03*
X229232D03*
X218011Y1204232D03*
X229232Y1196751D03*
Y1204232D03*
X225492Y1196751D03*
Y1204232D03*
X221751D03*
Y1196751D03*
X218011D03*
X225492Y1207972D03*
X221751D03*
X218011D03*
X229232D03*
X231102Y1221062D03*
X227362D03*
X219881Y1217322D03*
X223622Y1221062D03*
X219881D03*
X216141D03*
X227362Y1224803D03*
X223622Y1232283D03*
X219881Y1224803D03*
X223622Y1236023D03*
X231102Y1232283D03*
Y1236023D03*
X216141Y1232283D03*
Y1236023D03*
Y1224803D03*
X223622D03*
Y1228543D03*
X216141D03*
X223622Y1239763D03*
X231102D03*
X227362Y1243503D03*
X219881D03*
X216141Y1239763D03*
X219882Y1258465D03*
X227363D03*
X246062Y1075196D03*
X234841Y1071454D03*
X242321Y1071455D03*
X238582Y1075196D03*
X234842Y1090157D03*
X246062D03*
Y1078936D03*
X238582Y1090157D03*
X242322Y1086417D03*
X234842Y1082677D03*
Y1086417D03*
X242322Y1090157D03*
X246062Y1097637D03*
Y1093897D03*
X242322Y1105117D03*
X234842Y1101377D03*
X238582Y1093897D03*
X242322Y1101377D03*
X234842Y1105117D03*
X236712Y1121948D03*
X240452D03*
X244192D03*
X234842Y1108858D03*
X238582D03*
X242322D03*
X246062D03*
X236712Y1133464D03*
X240452Y1133169D03*
X236712Y1140649D03*
X240452D03*
X236712Y1125688D03*
X240452D03*
X244192Y1133169D03*
Y1140649D03*
Y1125688D03*
X236712Y1148129D03*
X240452D03*
X244192D03*
X240452Y1155610D03*
Y1166830D03*
X236712Y1170570D03*
Y1159350D03*
X244192Y1170570D03*
Y1159350D03*
X240452Y1181791D03*
X236712D03*
Y1189271D03*
X240452D03*
X244192Y1181791D03*
Y1189271D03*
X240452Y1174310D03*
Y1204232D03*
X236712D03*
Y1196751D03*
X240452D03*
X244192Y1204232D03*
Y1196751D03*
X240452Y1207972D03*
Y1211712D03*
X242322Y1221062D03*
X244192Y1211712D03*
Y1207972D03*
X236712D03*
X234842Y1221062D03*
X238582D03*
X246062Y1232283D03*
Y1236023D03*
X238582Y1232283D03*
X234842Y1228543D03*
Y1224803D03*
X238582Y1236023D03*
X242322Y1228543D03*
Y1224803D03*
X246062Y1239763D03*
X238582D03*
X234842Y1258465D03*
X242322D03*
X239383Y1348187D03*
X247263D03*
Y1360099D03*
X239383D03*
X247263Y1384297D03*
Y1372385D03*
X239383Y1384297D03*
Y1372385D03*
X253543Y1075196D03*
X261023D03*
X249802Y1071455D03*
X257282D03*
X253543Y1090157D03*
X249803D03*
Y1086417D03*
X253543Y1078936D03*
X257283Y1090157D03*
Y1086417D03*
X261023Y1090157D03*
Y1078936D03*
X249803Y1105117D03*
X253543Y1093897D03*
Y1097637D03*
X257283Y1105117D03*
X261023Y1093897D03*
Y1097637D03*
X255413Y1121948D03*
X251673D03*
X247933D03*
X262893D03*
X259153D03*
X249803Y1108858D03*
X253543D03*
X257283D03*
X261023D03*
X247933Y1133169D03*
X251673D03*
X255413D03*
X247933Y1140649D03*
X251673D03*
X255413D03*
X247933Y1125688D03*
X251673D03*
X255413D03*
X259153Y1133169D03*
X262893D03*
Y1140649D03*
X259153Y1125688D03*
X262893D03*
X259153Y1140649D03*
Y1148129D03*
X262893D03*
Y1155610D03*
X247933Y1148129D03*
X251673D03*
X255413D03*
X247933Y1155610D03*
X255413D03*
X262893Y1166830D03*
X251673Y1170570D03*
X255413Y1166830D03*
X247933D03*
X251673Y1159350D03*
X259153D03*
Y1170570D03*
X247933Y1181791D03*
X251673D03*
X255413D03*
X247933Y1189271D03*
X251673D03*
X255413D03*
X262893D03*
Y1174310D03*
X259153Y1181791D03*
X262893D03*
X259153Y1189271D03*
X255413Y1174310D03*
X247933D03*
Y1204232D03*
X255413D03*
X251673D03*
X247933Y1196751D03*
X251673D03*
X255413D03*
X259153Y1204232D03*
X262893D03*
X259153Y1196751D03*
X262893D03*
X247933Y1207972D03*
X251673D03*
X255413Y1211712D03*
Y1207972D03*
X262893D03*
X259153D03*
X262893Y1211712D03*
X259153D03*
X249803Y1228543D03*
X257283D03*
X249803Y1224803D03*
X253543Y1236023D03*
X257283Y1224803D03*
X261023Y1236023D03*
X253543Y1232283D03*
X261023D03*
X257283Y1239763D03*
X249803Y1258465D03*
X257283D03*
X263863Y1348187D03*
X259503D03*
X251623D03*
X263863Y1360099D03*
X259503D03*
X251623D03*
X263863Y1384297D03*
Y1372385D03*
X259503Y1384297D03*
Y1372385D03*
X251623D03*
Y1384297D03*
X263863Y1396583D03*
X259503D03*
X251623D03*
X263863Y1408495D03*
X259503D03*
X251623D03*
X279723Y1071455D03*
X264762D03*
X272243D03*
X268503Y1075196D03*
X275984D03*
X279724Y1090157D03*
X272244Y1082677D03*
X275984Y1090157D03*
X272244Y1086417D03*
X268503Y1078936D03*
Y1090157D03*
X264763Y1086417D03*
X272244Y1090157D03*
X264763D03*
X268503Y1093897D03*
Y1097637D03*
X272244Y1105117D03*
X279724D03*
X275984Y1093897D03*
X264763Y1105117D03*
X274114Y1118208D03*
X270373D03*
X266633Y1121948D03*
X270373D03*
X277854Y1118208D03*
X264763Y1108858D03*
X268503D03*
X272244D03*
X275984D03*
X279724D03*
X274114Y1125688D03*
X270373Y1136909D03*
X266633Y1133169D03*
X270373D03*
X266633Y1140649D03*
X270373Y1125688D03*
Y1129429D03*
X266633Y1125688D03*
X270373Y1140649D03*
X277854Y1136909D03*
Y1140649D03*
X274114Y1155610D03*
Y1151869D03*
Y1148129D03*
X266633D03*
X270373Y1144389D03*
Y1148129D03*
Y1151869D03*
X277854Y1144389D03*
Y1148129D03*
Y1151870D03*
X270373Y1155610D03*
X274114Y1166830D03*
Y1159350D03*
Y1170570D03*
X266633Y1181791D03*
X270373Y1189271D03*
X277854Y1178051D03*
Y1189271D03*
Y1185531D03*
X270373Y1174310D03*
X277854Y1181791D03*
X274114D03*
Y1174310D03*
X266633Y1189271D03*
X270373Y1178051D03*
Y1185531D03*
X274114Y1196751D03*
X270393Y1196732D03*
X270373Y1204232D03*
X266633D03*
X270373Y1200491D03*
X266633Y1196751D03*
X270373Y1193011D03*
X277854D03*
X274114Y1207972D03*
X270373Y1211712D03*
X266633Y1207972D03*
Y1211712D03*
X270373Y1207972D03*
X277854Y1211712D03*
X279724Y1221062D03*
X275984D03*
X272244D03*
X268503D03*
X279724Y1224803D03*
X272244D03*
X268503Y1236023D03*
Y1232283D03*
X272244Y1228543D03*
X264763Y1224803D03*
X275984Y1232283D03*
Y1236023D03*
X264763Y1228543D03*
X279724D03*
X268503Y1239763D03*
X279724Y1258465D03*
X264763D03*
X272244D03*
X276103Y1348187D03*
X271743D03*
X276103Y1360099D03*
X271743D03*
X276103Y1384297D03*
Y1372385D03*
X271743Y1384297D03*
Y1372385D03*
X276103Y1396583D03*
X271743D03*
Y1408495D03*
X276103D03*
X294684Y1071455D03*
X290944Y1075196D03*
X287203Y1071455D03*
X283464Y1075196D03*
X287204Y1090157D03*
X283464Y1078936D03*
Y1090157D03*
X290943D03*
X290944Y1093897D03*
X287204Y1101377D03*
Y1105117D03*
X294685D03*
X294684Y1120078D03*
Y1112598D03*
X283464Y1108858D03*
X287204D03*
X290944D03*
X294685D03*
X290944Y1112598D03*
Y1116338D03*
Y1120078D03*
Y1123818D03*
X281594Y1140649D03*
Y1136909D03*
X290944Y1127558D03*
Y1131299D03*
Y1135039D03*
Y1138779D03*
X281594Y1148129D03*
Y1155610D03*
Y1151869D03*
X285334D03*
X289074D03*
Y1155610D03*
X292814Y1151869D03*
Y1144389D03*
X281594Y1159350D03*
X289074Y1166830D03*
Y1170570D03*
Y1159350D03*
X281594Y1170570D03*
Y1166830D03*
X292814Y1159350D03*
Y1166830D03*
Y1181791D03*
X285334Y1185531D03*
X289074Y1174310D03*
Y1178051D03*
Y1185531D03*
X281594Y1189271D03*
Y1185531D03*
X285334Y1181791D03*
X281594Y1178051D03*
Y1174310D03*
X292814D03*
Y1189271D03*
X281594Y1196751D03*
Y1204232D03*
Y1193011D03*
X285334D03*
X290944Y1194881D03*
Y1198621D03*
Y1202362D03*
X294685Y1221062D03*
Y1217322D03*
X290944Y1221062D03*
X287204D03*
X283464D03*
X290944Y1206102D03*
Y1209842D03*
Y1213582D03*
Y1217322D03*
X294685Y1228543D03*
Y1224803D03*
X290944Y1232283D03*
Y1236023D03*
X283464Y1232283D03*
X287204Y1228543D03*
X283464Y1236023D03*
X287204Y1224803D03*
X283464Y1239763D03*
X290944D03*
X294685Y1254724D03*
Y1250984D03*
X290944Y1247243D03*
Y1243503D03*
X294685Y1258465D03*
X287204D03*
X288343Y1348187D03*
X296223D03*
X283983D03*
X288343Y1360099D03*
X296223D03*
X283983D03*
X288343Y1384297D03*
Y1372385D03*
X296223Y1384297D03*
Y1372385D03*
X283983D03*
Y1384297D03*
X288343Y1396583D03*
X296223D03*
X283983D03*
X288343Y1408495D03*
X296223D03*
X283983D03*
X309645Y1071455D03*
X302165D03*
X298425Y1075196D03*
X305906D03*
X298424Y1090157D03*
X298426Y1078936D03*
X305906D03*
X302165Y1105117D03*
X309645D03*
X298425Y1093897D03*
X305905D03*
X302165Y1123818D03*
X305904Y1108857D03*
X302165Y1116338D03*
X298425Y1108858D03*
X300295Y1140649D03*
X302165Y1131299D03*
X300295Y1148129D03*
Y1159350D03*
Y1166830D03*
X311515D03*
X307775Y1170570D03*
X300295Y1181791D03*
Y1174310D03*
Y1189271D03*
X311515Y1174310D03*
X307775Y1178051D03*
X311515Y1181791D03*
X307775Y1185531D03*
X311515Y1189271D03*
X298425Y1202362D03*
Y1194881D03*
X309645Y1198621D03*
X307775Y1193011D03*
X311515Y1196751D03*
X305905Y1198621D03*
X309645Y1202362D03*
X298425Y1209842D03*
X302165Y1221062D03*
X309645Y1217322D03*
Y1209842D03*
X305905Y1213582D03*
X309645D03*
Y1206102D03*
Y1221062D03*
X305905D03*
X298425Y1236023D03*
Y1232283D03*
X302165Y1228543D03*
Y1224803D03*
X305905Y1232283D03*
X309645Y1228543D03*
Y1224803D03*
X305905Y1236023D03*
X298425Y1239763D03*
X309645D03*
Y1254724D03*
X298425Y1247243D03*
X309645Y1250984D03*
X298425Y1243503D03*
X305905D03*
Y1247243D03*
X302165Y1254724D03*
Y1250984D03*
X309645Y1258465D03*
X302165D03*
X308463Y1348187D03*
X300583D03*
X308463Y1360099D03*
X300583D03*
X308463Y1372385D03*
X300583D03*
Y1384297D03*
X308463D03*
Y1396583D03*
X300583D03*
X308463Y1408495D03*
X300583D03*
X317125Y1071455D03*
X320866Y1075196D03*
X313386D03*
X320866Y1078936D03*
X313384Y1090157D03*
X313386Y1078936D03*
X328347Y1082677D03*
Y1090158D03*
X324606Y1078936D03*
X313385Y1093897D03*
X328347Y1101378D03*
Y1116339D03*
Y1123819D03*
Y1108859D03*
X313385Y1108858D03*
X328347Y1131300D03*
X318996Y1140649D03*
Y1155610D03*
Y1148129D03*
X322736Y1170570D03*
X318996D03*
Y1185531D03*
Y1178051D03*
X322736D03*
Y1185531D03*
X328347Y1198621D03*
X322736Y1193011D03*
X320866Y1202362D03*
X318996Y1193011D03*
X326416D03*
X324606Y1202362D03*
X328347Y1206102D03*
Y1221062D03*
Y1213582D03*
X320866Y1209842D03*
X313385Y1221062D03*
X320866Y1206102D03*
Y1232283D03*
X313385D03*
X317125Y1228543D03*
Y1224803D03*
X313385Y1236023D03*
X328347Y1228543D03*
Y1239762D03*
Y1247243D03*
X324606Y1250984D03*
X317125Y1254724D03*
X324606Y1239763D03*
X313385Y1247243D03*
X317125Y1250984D03*
X320866Y1239763D03*
X313385Y1243503D03*
X317125Y1258465D03*
X320703Y1348187D03*
X312823D03*
X325063D03*
X320703Y1360099D03*
X312823D03*
X325063D03*
X320703Y1372385D03*
Y1384297D03*
X312823Y1372385D03*
Y1384297D03*
X325063Y1372385D03*
Y1384297D03*
Y1396583D03*
X320703D03*
X312823D03*
X320703Y1408495D03*
X312823D03*
X325063D03*
X318448Y1750941D03*
Y1760941D03*
X318348Y1796941D03*
Y1806941D03*
X337303Y1348187D03*
X332943D03*
Y1360099D03*
X337303D03*
X332943Y1384297D03*
Y1372385D03*
X337303D03*
Y1384297D03*
X332943Y1396583D03*
X337303D03*
X332943Y1408495D03*
X337303D03*
X349543Y1348187D03*
X357423D03*
X345183D03*
X349543Y1360099D03*
X357423D03*
X345183D03*
Y1372385D03*
Y1384297D03*
X349543D03*
Y1372385D03*
X357423D03*
Y1384297D03*
X345183Y1396583D03*
X349543D03*
X357423D03*
X345183Y1408495D03*
X349543D03*
X357423D03*
X369663Y1348187D03*
X361783D03*
X369663Y1360099D03*
X361783D03*
X369663Y1372385D03*
Y1384297D03*
X361783D03*
Y1372385D03*
X369663Y1396583D03*
X361783D03*
X369663Y1408495D03*
X361783D03*
X458282Y1348187D03*
X446042D03*
X458282Y1360099D03*
X446042D03*
X458282Y1372385D03*
X446042D03*
X458282Y1384297D03*
X446042D03*
X458282Y1396583D03*
Y1408495D03*
X470522Y1348187D03*
Y1360099D03*
Y1384297D03*
Y1372385D03*
Y1396583D03*
Y1408495D03*
X482762Y1348187D03*
Y1360099D03*
Y1384297D03*
Y1372385D03*
Y1396583D03*
Y1408495D03*
X507242Y1348187D03*
X495002D03*
X507242Y1360099D03*
X495002D03*
Y1384297D03*
X507242D03*
X495002Y1372385D03*
X507242D03*
Y1396583D03*
X495002D03*
X507242Y1408495D03*
X495002D03*
X519482Y1348187D03*
Y1360099D03*
Y1384297D03*
Y1372385D03*
Y1396583D03*
Y1408495D03*
X531722Y1348187D03*
Y1360099D03*
Y1384297D03*
Y1372385D03*
Y1396583D03*
Y1408495D03*
X556202Y1348187D03*
X543962D03*
X556202Y1360099D03*
X543962D03*
Y1372385D03*
Y1384297D03*
X556202D03*
Y1372385D03*
Y1396583D03*
X543962D03*
X556202Y1408495D03*
X543962D03*
X568442Y1348187D03*
Y1360099D03*
Y1384297D03*
Y1372385D03*
Y1396583D03*
Y1408495D03*
X604035Y1080806D03*
Y1103247D03*
X600295D03*
Y1125688D03*
Y1133169D03*
Y1140649D03*
X604035Y1125688D03*
Y1133169D03*
Y1140649D03*
X600295Y1144389D03*
Y1151870D03*
X604035Y1144389D03*
Y1151870D03*
X600295Y1159350D03*
X604035D03*
X597795Y1170570D03*
X604034Y1174310D03*
X597795Y1178050D03*
X602165Y1183661D03*
Y1187401D03*
Y1202362D03*
Y1194881D03*
X598424Y1198622D03*
Y1191142D03*
X602165Y1217322D03*
Y1209842D03*
X598424Y1221063D03*
Y1213583D03*
Y1206103D03*
X602165Y1224803D03*
Y1236023D03*
Y1232283D03*
Y1239763D03*
X605386Y1728583D03*
Y1738583D03*
X605312Y1774624D03*
Y1784624D03*
X607775Y1077066D03*
X615256Y1106988D03*
X618996D03*
X615256Y1118208D03*
Y1121948D03*
X611516D03*
X607776D03*
X618996Y1114468D03*
X615256Y1125688D03*
X611516Y1129429D03*
X607776D03*
Y1136909D03*
X615256Y1140649D03*
X611516D03*
X607776D03*
X618996D03*
Y1144389D03*
Y1148129D03*
Y1151870D03*
Y1155610D03*
X607776Y1144389D03*
Y1148129D03*
Y1151870D03*
X615256Y1155610D03*
X611516D03*
X607776D03*
Y1159350D03*
X615256Y1166830D03*
X607775D03*
X611516Y1170570D03*
X607775D03*
X618996Y1159350D03*
Y1174310D03*
Y1178051D03*
X607775Y1174310D03*
Y1178051D03*
X611516Y1174310D03*
X615256D03*
X613386Y1183661D03*
X617126Y1187401D03*
Y1183661D03*
X613386Y1179921D03*
X620866Y1183661D03*
X609646D03*
X605905D03*
Y1187401D03*
X620866D03*
X613386Y1198621D03*
X609646Y1191141D03*
X613386D03*
X617126Y1198621D03*
X620866D03*
X617126Y1191141D03*
X620866D03*
X605905Y1202362D03*
Y1194881D03*
X609646Y1198621D03*
X620866Y1202362D03*
Y1194881D03*
X613386Y1221062D03*
X609646D03*
Y1213582D03*
X613386D03*
X620866Y1206102D03*
X617126D03*
X620866Y1221062D03*
X617126D03*
X613386Y1206102D03*
X605905Y1217322D03*
Y1209842D03*
X609646Y1206102D03*
X620866Y1209842D03*
Y1217322D03*
X605905Y1224803D03*
Y1232283D03*
Y1236023D03*
X620866D03*
Y1232283D03*
X617126Y1224803D03*
X609646D03*
Y1228543D03*
X613386Y1232283D03*
Y1236023D03*
X620866Y1228543D03*
Y1224803D03*
X613386Y1228543D03*
Y1224803D03*
X617126Y1243503D03*
Y1239763D03*
X620866D03*
X609646Y1243503D03*
Y1239763D03*
X605905D03*
X617126Y1258465D03*
X609646D03*
X632085Y1071455D03*
X626476Y1092027D03*
X635827Y1090157D03*
X628346D03*
X632086D03*
X630216Y1099507D03*
X626476Y1106988D03*
X622736D03*
X626476Y1095767D03*
X630216Y1103247D03*
X635827Y1093897D03*
X632086Y1101377D03*
Y1105117D03*
X628346Y1093897D03*
X635827Y1097637D03*
X633957Y1110728D03*
X630216D03*
X626476D03*
X622736Y1114468D03*
X630216Y1118208D03*
X626476D03*
X633957Y1114468D03*
Y1118208D03*
Y1121948D03*
X635827Y1108858D03*
X632086D03*
X633957Y1140649D03*
Y1125688D03*
Y1129429D03*
Y1133169D03*
Y1136909D03*
X630216Y1140649D03*
X626476D03*
X622736D03*
Y1129429D03*
X630216Y1144389D03*
X626476D03*
X630216Y1148129D03*
Y1155610D03*
Y1151870D03*
Y1159350D03*
Y1166830D03*
Y1170570D03*
X633957D03*
Y1185531D03*
X628346Y1183661D03*
X630216Y1174310D03*
Y1178051D03*
Y1181791D03*
X632086Y1187401D03*
X628346D03*
X624606Y1183661D03*
X635827Y1187401D03*
X624606D03*
Y1191141D03*
X632086Y1202362D03*
X628346D03*
X632086Y1194881D03*
X628346D03*
X635827Y1191141D03*
Y1194881D03*
Y1198621D03*
Y1202362D03*
X628346Y1191141D03*
X624606Y1194881D03*
X632086Y1191141D03*
X628346Y1198621D03*
X624606Y1202362D03*
X632086Y1198621D03*
X624606Y1206102D03*
X628346Y1209842D03*
Y1217322D03*
Y1221062D03*
X632086D03*
Y1217322D03*
X635827Y1221062D03*
Y1206102D03*
Y1209842D03*
Y1213582D03*
Y1217322D03*
X628346Y1206102D03*
X632086D03*
X624606Y1217322D03*
X628346Y1213582D03*
X632086D03*
X624606Y1209842D03*
X632086Y1224803D03*
X624606D03*
X628346Y1236023D03*
Y1232283D03*
X635827Y1236023D03*
Y1232283D03*
X628346Y1224803D03*
Y1228543D03*
X635827D03*
Y1224803D03*
X632086Y1247243D03*
Y1239763D03*
X628346D03*
Y1250984D03*
X624606Y1243503D03*
Y1239763D03*
X632086Y1254724D03*
X635827Y1243503D03*
X632086Y1250984D03*
X635827Y1247243D03*
X628346Y1243503D03*
Y1247243D03*
X632087Y1258465D03*
X624606D03*
X631928Y1396583D03*
Y1408495D03*
X647046Y1071455D03*
X639566D03*
X643307Y1090157D03*
X639567D03*
X650787D03*
X647047D03*
X639567Y1101377D03*
Y1105117D03*
X647047D03*
Y1101377D03*
X650787Y1097637D03*
X643307D03*
Y1093897D03*
X650787D03*
X647047D03*
X637697Y1114468D03*
X648917Y1118208D03*
X645177D03*
X641437D03*
X637697D03*
X648917Y1121948D03*
X645177D03*
X641437D03*
X637697D03*
Y1110728D03*
X652657Y1118208D03*
Y1121948D03*
X650787Y1108858D03*
X647047D03*
X643307D03*
X639567D03*
X641437Y1133169D03*
X637697D03*
X645177Y1136909D03*
X637697D03*
X645177Y1140649D03*
X641437D03*
X652657Y1133169D03*
Y1129429D03*
Y1125688D03*
Y1136909D03*
X637697Y1140649D03*
X648917Y1125688D03*
X645177D03*
X641437D03*
X637697D03*
X645177Y1129429D03*
X641437D03*
X637697D03*
X645177Y1133169D03*
X637697Y1155610D03*
Y1151870D03*
X645177Y1144389D03*
X637697D03*
Y1148129D03*
X645177Y1151870D03*
X648917Y1155610D03*
Y1148129D03*
X652657Y1151869D03*
Y1144389D03*
X645177Y1170570D03*
X637697Y1166830D03*
X645177Y1159350D03*
X637697D03*
X648917Y1166830D03*
X652657Y1159350D03*
Y1170570D03*
X637697Y1189271D03*
X645177Y1185531D03*
X637697D03*
Y1178051D03*
Y1174310D03*
Y1181791D03*
X652657Y1189271D03*
X648917Y1181791D03*
Y1174310D03*
X652657Y1185531D03*
Y1178051D03*
Y1193011D03*
Y1204232D03*
X637697Y1193011D03*
X645177Y1196751D03*
Y1200491D03*
X641437D03*
Y1204232D03*
X645177D03*
X648917D03*
Y1196751D03*
Y1200491D03*
X641437Y1193011D03*
Y1196751D03*
X652657Y1200491D03*
Y1196751D03*
Y1211712D03*
X648917Y1219192D03*
X641437D03*
Y1211712D03*
X645177D03*
X648917D03*
Y1207972D03*
X645177D03*
X641437D03*
X652657D03*
X639567Y1221062D03*
X647047D03*
X643307D03*
X650787D03*
X639567Y1224803D03*
X643307Y1236023D03*
Y1232283D03*
X650787Y1236023D03*
X647047Y1224803D03*
X650787Y1232283D03*
X643307Y1224803D03*
Y1228543D03*
X650787D03*
Y1224803D03*
X639567Y1243503D03*
X647047D03*
X650787Y1239763D03*
X643307D03*
X639567Y1250984D03*
Y1254724D03*
X650787Y1247243D03*
Y1243503D03*
X647047Y1254724D03*
Y1250984D03*
X643307Y1247243D03*
Y1243503D03*
X647047Y1258465D03*
X639567D03*
X644168Y1384297D03*
Y1372385D03*
Y1396583D03*
Y1408495D03*
X669487Y1071455D03*
X662007D03*
X654526D03*
X669488Y1090157D03*
X665748D03*
X654527D03*
X658268D03*
X662008D03*
Y1101377D03*
X665748Y1093897D03*
X658268D03*
X654527Y1105117D03*
Y1101377D03*
X662008Y1105117D03*
X658268Y1097637D03*
X669488Y1101377D03*
Y1105117D03*
X665748Y1097637D03*
X656398Y1118208D03*
Y1121948D03*
X663878Y1118208D03*
X660138D03*
Y1121948D03*
X663878D03*
X667618Y1118208D03*
Y1121948D03*
X669488Y1108858D03*
X665748D03*
X662008D03*
X658268D03*
X654527D03*
X656398Y1140649D03*
X660138D03*
X663878D03*
X656398Y1125688D03*
X660138D03*
X663878D03*
Y1133169D03*
X660138D03*
X656398D03*
X667618D03*
Y1140649D03*
Y1125688D03*
Y1148129D03*
X660138D03*
X656398D03*
X663878D03*
X656398Y1155610D03*
X663878D03*
Y1166830D03*
X660138Y1159350D03*
X656398Y1166830D03*
X660138Y1170570D03*
X667618Y1159350D03*
Y1170570D03*
X663878Y1181791D03*
X660138D03*
X656398D03*
X663878Y1189271D03*
X660138D03*
X656398D03*
X667618Y1181791D03*
Y1189271D03*
X656398Y1174310D03*
X663878D03*
Y1196751D03*
X660138D03*
X656398D03*
Y1204232D03*
X660138D03*
X663878D03*
X667618Y1196751D03*
Y1204232D03*
X663878Y1207972D03*
X660138D03*
X656398D03*
X667618D03*
X654527Y1221062D03*
X658268D03*
X662008D03*
X665748D03*
X669488D03*
X654527Y1224803D03*
X658268Y1236023D03*
Y1232283D03*
X662008Y1224803D03*
X665748Y1236023D03*
Y1232283D03*
X669488Y1224803D03*
X654527Y1239763D03*
Y1243503D03*
X665748Y1239763D03*
X669488Y1243503D03*
X662008D03*
X654527Y1254724D03*
Y1250984D03*
X662008Y1258465D03*
X669488D03*
X654528D03*
X668648Y1348187D03*
X656408D03*
X668648Y1360099D03*
X656408D03*
Y1384297D03*
Y1372385D03*
X668648D03*
Y1384297D03*
Y1396583D03*
X656408D03*
X668648Y1408495D03*
X656408D03*
X684448Y1071455D03*
X676967D03*
X680709Y1090157D03*
X676968D03*
X684449D03*
X673228D03*
X676968Y1105117D03*
X684449Y1101377D03*
Y1105117D03*
X680709Y1093897D03*
X676968Y1101377D03*
X680709Y1097637D03*
X673228D03*
Y1093897D03*
X682579Y1118208D03*
Y1121948D03*
X671358Y1118208D03*
X675098D03*
X678838D03*
X675098Y1121948D03*
X678838D03*
X671358D03*
X684449Y1108858D03*
X680709D03*
X676968D03*
X673228D03*
X682579Y1133169D03*
Y1140649D03*
Y1125688D03*
X671358Y1140649D03*
X675098D03*
X678838D03*
X675098Y1125688D03*
X671358D03*
X678838D03*
Y1133169D03*
X675098D03*
X671358D03*
X682579Y1148129D03*
X678838D03*
X675098D03*
X671358D03*
Y1155610D03*
X678838D03*
X682579Y1170570D03*
Y1159350D03*
X675098Y1170570D03*
X678839Y1166830D03*
X671358D03*
X675098Y1159350D03*
Y1181791D03*
X671358D03*
X678838Y1189271D03*
X675098D03*
X671358D03*
X682579Y1181791D03*
Y1189271D03*
X678838Y1181791D03*
X671358Y1174310D03*
X678838D03*
X682579Y1196751D03*
Y1204232D03*
X678838D03*
Y1196751D03*
X675098D03*
X671358D03*
Y1204232D03*
X675098D03*
X682579Y1207972D03*
X678838Y1219192D03*
Y1207972D03*
X675098D03*
X671358D03*
X673228Y1221062D03*
X676968D03*
X680709D03*
X684449D03*
X673228Y1236023D03*
Y1232283D03*
X676968Y1224803D03*
X680709Y1236023D03*
Y1232283D03*
X684449Y1224803D03*
X673228Y1239763D03*
X680709D03*
X676968Y1243503D03*
X684449D03*
X684450Y1258465D03*
X676969D03*
X680888Y1348187D03*
Y1360099D03*
Y1372385D03*
Y1384297D03*
Y1396583D03*
Y1408495D03*
X695669Y1075196D03*
X699408Y1071455D03*
X691928Y1071454D03*
X688189Y1090157D03*
X691929Y1082677D03*
Y1086417D03*
X695669Y1090157D03*
X699409D03*
Y1086417D03*
X691929Y1090157D03*
X688189Y1097637D03*
X695669Y1093897D03*
X688189D03*
X699409Y1105117D03*
X691929Y1101377D03*
X699409D03*
X691929Y1105117D03*
X693799Y1121948D03*
X697539D03*
X701279D03*
X686319D03*
Y1118208D03*
Y1114468D03*
X699409Y1108858D03*
X695669D03*
X691929D03*
X688189D03*
X693799Y1133464D03*
X697539Y1133169D03*
X686417Y1132677D03*
X693799Y1140649D03*
X697539D03*
X693799Y1125688D03*
X697539D03*
X701279D03*
Y1140649D03*
Y1133169D03*
X686319Y1140649D03*
Y1125688D03*
X697539Y1148129D03*
X701279D03*
X693799D03*
X697539Y1155610D03*
X686319Y1148129D03*
Y1155610D03*
X697539Y1166830D03*
X693799Y1170570D03*
Y1159350D03*
X701279D03*
Y1170570D03*
X686319Y1166830D03*
X693799Y1181791D03*
Y1189271D03*
X697539D03*
X701279D03*
Y1181791D03*
X697539D03*
Y1174310D03*
X686319Y1181791D03*
Y1189271D03*
Y1174310D03*
X697539Y1204232D03*
X693799D03*
Y1196751D03*
X697539D03*
X701279D03*
Y1204232D03*
X686319Y1196751D03*
Y1204232D03*
X693799Y1207972D03*
X697539D03*
Y1211712D03*
X701279Y1207972D03*
Y1211712D03*
X686319Y1207972D03*
X695669Y1221062D03*
X699409D03*
X691929D03*
X688189D03*
Y1236023D03*
Y1232283D03*
X691929Y1224803D03*
Y1228543D03*
X699409Y1224803D03*
Y1228543D03*
X695669Y1236023D03*
Y1232283D03*
X688189Y1239763D03*
X695669D03*
X699409Y1258465D03*
X691929D03*
X693128Y1348187D03*
Y1360099D03*
Y1372385D03*
Y1384297D03*
Y1396583D03*
Y1408495D03*
X703149Y1075196D03*
X718110D03*
X710630D03*
X714369Y1071455D03*
X706889D03*
X710630Y1078936D03*
X706890Y1086417D03*
Y1090157D03*
X718110Y1078936D03*
X714370Y1086417D03*
Y1090157D03*
X710630D03*
X718110D03*
X703149Y1078936D03*
Y1090157D03*
X706890Y1105117D03*
X714370D03*
X710630Y1097637D03*
Y1093897D03*
X718110Y1097637D03*
Y1093897D03*
X703149D03*
Y1097637D03*
X716240Y1121948D03*
X705020D03*
X708760D03*
X712500D03*
X718110Y1108858D03*
X714370D03*
X710630D03*
X706890D03*
X703149D03*
X716240Y1140649D03*
Y1125688D03*
Y1133169D03*
X712500Y1125688D03*
X708760D03*
X705020D03*
X712500Y1140649D03*
X708760D03*
X705020D03*
X712500Y1133169D03*
X708760D03*
X705020D03*
X716240Y1148129D03*
X712500D03*
X708760D03*
X705020D03*
X712500Y1155610D03*
X705020D03*
X716240Y1170570D03*
Y1159350D03*
X708760D03*
X705020Y1166830D03*
X712500D03*
X708760Y1170570D03*
X716240Y1189271D03*
Y1181791D03*
X712500Y1189271D03*
X708760D03*
X705020D03*
X712500Y1181791D03*
X708760D03*
X705020D03*
Y1174310D03*
X712500D03*
X716240Y1196751D03*
Y1204232D03*
X712500Y1196751D03*
X708760D03*
X705020D03*
X708760Y1204232D03*
X712500D03*
X705020D03*
X716240Y1211712D03*
Y1207972D03*
X712500D03*
Y1211712D03*
X708760Y1207972D03*
X705020D03*
X703149Y1221062D03*
X706890D03*
X710630D03*
X714370D03*
X718110D03*
X703149Y1236023D03*
Y1232283D03*
X710630Y1236023D03*
X718110D03*
Y1232283D03*
X710630D03*
X714370Y1224803D03*
Y1228543D03*
X706890Y1224803D03*
Y1228543D03*
X703149Y1239763D03*
X714370D03*
X718110Y1243503D03*
Y1247243D03*
X714370Y1258465D03*
X706890D03*
X705368Y1348187D03*
X717608D03*
X705368Y1360099D03*
X717608D03*
X705368Y1372385D03*
Y1384297D03*
X717608Y1372385D03*
Y1384297D03*
Y1396583D03*
X705368D03*
X717608Y1408495D03*
X705368D03*
X725590Y1075196D03*
X733071D03*
X729330Y1071455D03*
X721849D03*
X729331Y1086417D03*
Y1082677D03*
X733071Y1090157D03*
X729331D03*
X725590D03*
X721850D03*
X725590Y1078936D03*
X721850Y1086417D03*
X725590Y1097637D03*
X721850Y1105117D03*
X725590Y1093897D03*
X729331Y1105117D03*
X733071Y1093897D03*
X734941Y1118208D03*
X727460Y1121948D03*
X719980D03*
X723720D03*
X727460Y1118208D03*
X731201D03*
X733071Y1108858D03*
X729331D03*
X725590D03*
X721850D03*
X734941Y1140649D03*
Y1136909D03*
X727460Y1140649D03*
X723720Y1125688D03*
X719980D03*
X727460Y1129429D03*
Y1125688D03*
X723720Y1140649D03*
X719980D03*
X727460Y1133169D03*
X723720D03*
X719980D03*
X727460Y1136909D03*
X731201Y1125688D03*
X727460Y1151869D03*
Y1148129D03*
Y1144389D03*
X723720Y1148129D03*
X719980D03*
X731201D03*
Y1151869D03*
Y1155610D03*
X734941Y1151870D03*
Y1148129D03*
Y1144389D03*
X719980Y1155610D03*
X727460D03*
X731201Y1170570D03*
X719980Y1166830D03*
X731201Y1159350D03*
Y1166830D03*
X727460Y1185531D03*
X734941Y1181791D03*
Y1185531D03*
Y1189271D03*
Y1178051D03*
X727460Y1189271D03*
X723720Y1181791D03*
X719980D03*
Y1174310D03*
X727460Y1178051D03*
X723720Y1189271D03*
X719980D03*
X731201Y1174310D03*
Y1181791D03*
X727460Y1174310D03*
X719980Y1204232D03*
X727460D03*
X727480Y1196732D03*
X731201Y1196751D03*
X734941Y1193011D03*
X727460D03*
X723720Y1196751D03*
X719980D03*
X727460Y1200491D03*
X723720Y1204232D03*
X734941Y1211712D03*
X727460Y1207972D03*
X723720Y1211712D03*
Y1207972D03*
X719980Y1211712D03*
Y1207972D03*
X727460Y1211712D03*
X731201Y1207972D03*
X733071Y1221062D03*
X721850D03*
X725590D03*
X729331D03*
Y1224803D03*
Y1228543D03*
X733071Y1236023D03*
Y1232283D03*
X725590Y1236023D03*
Y1232283D03*
X721850Y1224803D03*
Y1228543D03*
X725590Y1239763D03*
X733071Y1247243D03*
X725590Y1243503D03*
X733071D03*
X725590Y1247243D03*
X729331Y1258465D03*
X721850D03*
X729848Y1348187D03*
Y1360099D03*
Y1372385D03*
Y1384297D03*
Y1396489D03*
Y1408401D03*
X740551Y1075196D03*
X748031D03*
X744290Y1071455D03*
X736810D03*
X748030Y1090157D03*
X744291D03*
X740551Y1078936D03*
Y1090157D03*
X736811D03*
X744291Y1101377D03*
X748031Y1093897D03*
X744291Y1105117D03*
X736811D03*
X748031Y1123818D03*
Y1120078D03*
Y1116338D03*
Y1112598D03*
Y1108858D03*
X744291D03*
X740551D03*
X736811D03*
X738681Y1136909D03*
Y1140649D03*
X748031Y1138779D03*
Y1135039D03*
Y1131299D03*
Y1127558D03*
X738681Y1155610D03*
Y1148129D03*
X749901Y1144389D03*
Y1151869D03*
X746161Y1155610D03*
Y1151869D03*
X742421D03*
X738681D03*
Y1166830D03*
X746161Y1170570D03*
Y1166830D03*
X738681Y1159350D03*
X749901Y1166830D03*
Y1159350D03*
X738681Y1170570D03*
X746161Y1159350D03*
X749901Y1181791D03*
Y1174310D03*
X738681D03*
Y1178051D03*
X742421Y1181791D03*
X738681Y1185531D03*
Y1189271D03*
X746161Y1185531D03*
Y1178051D03*
Y1174310D03*
X742421Y1185531D03*
X748031Y1191141D03*
X738681Y1204232D03*
Y1193011D03*
Y1196751D03*
X742421Y1193011D03*
X748031Y1202362D03*
Y1198621D03*
X736811Y1221062D03*
X740551D03*
X748031D03*
X744291D03*
X748031Y1217322D03*
Y1213582D03*
Y1209842D03*
Y1206102D03*
X736811Y1224803D03*
Y1228543D03*
X748031Y1236023D03*
Y1232283D03*
X740551Y1236023D03*
X744291Y1228543D03*
X740551Y1232283D03*
X744291Y1224803D03*
X748031Y1239763D03*
X740551D03*
Y1243503D03*
Y1247243D03*
X744291Y1258465D03*
X736811D03*
X742088Y1348187D03*
Y1360099D03*
Y1384297D03*
Y1372385D03*
Y1396489D03*
Y1408401D03*
X755512Y1075196D03*
X762993D03*
X766732Y1071455D03*
X759252D03*
X751771D03*
X755511Y1090157D03*
X762993Y1078936D03*
X755513D03*
X751772Y1105117D03*
X762992Y1093897D03*
X759252Y1105117D03*
X766732D03*
X755512Y1093897D03*
X762991Y1108857D03*
X755512Y1108858D03*
X751772D03*
X759252Y1116338D03*
Y1123818D03*
X751771Y1112598D03*
Y1120078D03*
X757382Y1140649D03*
X759252Y1131299D03*
X757382Y1148129D03*
X764862Y1170570D03*
X757382Y1166830D03*
Y1159350D03*
Y1174310D03*
Y1181791D03*
X764862Y1185531D03*
Y1178051D03*
X755512Y1187401D03*
X764862Y1189271D03*
X766732Y1194881D03*
X751772D03*
X755512Y1202362D03*
X766732D03*
Y1198621D03*
X762992D03*
X766732Y1221062D03*
Y1217322D03*
X762992Y1221062D03*
X759252D03*
X762992Y1213582D03*
X766732D03*
Y1209842D03*
X755512D03*
X766732Y1206102D03*
X751772Y1221062D03*
Y1217322D03*
X759252Y1224803D03*
Y1228543D03*
X755512Y1232283D03*
Y1236023D03*
X766732Y1224803D03*
Y1228543D03*
X762992Y1232283D03*
Y1236023D03*
X751772Y1224803D03*
Y1228543D03*
X755512Y1239763D03*
X766732D03*
Y1258465D03*
X759252D03*
X751772D03*
X766568Y1348187D03*
X754328D03*
X766568Y1360099D03*
X754328D03*
Y1372385D03*
Y1384297D03*
X766568Y1372385D03*
Y1384297D03*
X777953Y1075196D03*
X770473D03*
X774212Y1071455D03*
X777953Y1078936D03*
X781693D03*
X770473D03*
X770471Y1090157D03*
X770472Y1093897D03*
Y1108858D03*
X776083Y1140649D03*
Y1148129D03*
Y1155610D03*
Y1170570D03*
X768602Y1166830D03*
X779823Y1170570D03*
X776083Y1178051D03*
Y1185531D03*
X779823D03*
Y1178051D03*
X768602Y1181791D03*
Y1174310D03*
X772342Y1189271D03*
X783503Y1193011D03*
X776083D03*
X779823D03*
X781693Y1202362D03*
X777953D03*
X770472Y1221062D03*
X777953Y1209842D03*
X774212Y1224803D03*
Y1228543D03*
X770472Y1236023D03*
Y1232283D03*
X777953D03*
X781693Y1250984D03*
X774212Y1258465D03*
X778808Y1348187D03*
Y1360099D03*
X785434Y1090158D03*
Y1082677D03*
Y1101378D03*
Y1123819D03*
Y1116339D03*
Y1108859D03*
Y1131300D03*
Y1198621D03*
Y1221062D03*
Y1213582D03*
Y1206102D03*
Y1228543D03*
Y1247243D03*
Y1239762D03*
X892183Y1728286D03*
Y1738286D03*
X891761Y1775438D03*
Y1785438D03*
X1057381Y1103247D03*
Y1140649D03*
Y1133169D03*
Y1125688D03*
Y1151870D03*
Y1144389D03*
X1054881Y1170570D03*
X1057381Y1159350D03*
X1054881Y1178050D03*
X1059251Y1187401D03*
Y1183661D03*
Y1194881D03*
Y1202362D03*
X1055510Y1198622D03*
Y1191142D03*
X1059251Y1209842D03*
Y1217322D03*
X1055510Y1221063D03*
Y1213583D03*
Y1206103D03*
X1059251Y1232283D03*
Y1236023D03*
Y1224803D03*
X1052473Y1348187D03*
Y1360099D03*
Y1384297D03*
Y1372385D03*
X1064861Y1077066D03*
X1061121Y1080806D03*
X1072342Y1106988D03*
X1061121Y1103247D03*
X1072342Y1121948D03*
Y1118208D03*
X1064862Y1121948D03*
X1068602D03*
X1072342Y1140649D03*
Y1125688D03*
X1061121D03*
Y1140649D03*
X1064862D03*
X1068602D03*
X1064862Y1136909D03*
X1061121Y1133169D03*
X1064862Y1129429D03*
X1068602D03*
X1072342Y1155610D03*
X1064862D03*
X1068602D03*
X1061121Y1151870D03*
X1064862D03*
Y1148129D03*
X1061121Y1144389D03*
X1064862D03*
X1072342Y1166830D03*
X1064861Y1170570D03*
X1068602D03*
X1064861Y1166830D03*
X1061121Y1159350D03*
X1064862D03*
X1072342Y1181791D03*
Y1174310D03*
X1061120Y1181791D03*
X1064861D03*
X1068602D03*
Y1174310D03*
X1064861Y1178051D03*
X1061120Y1174310D03*
X1064861D03*
X1074212Y1187401D03*
X1062991D03*
Y1183661D03*
X1066732D03*
X1070472D03*
X1074212D03*
Y1191141D03*
Y1198621D03*
X1070472Y1191141D03*
X1066732D03*
X1070472Y1198621D03*
X1066732D03*
X1062991Y1194881D03*
Y1202362D03*
X1074212Y1206102D03*
X1066732D03*
X1070472D03*
Y1213582D03*
X1066732D03*
X1062991Y1209842D03*
Y1217322D03*
X1074212Y1221062D03*
X1066732D03*
X1070472D03*
Y1236023D03*
Y1232283D03*
X1066732Y1228543D03*
Y1224803D03*
X1074212D03*
X1062991Y1236023D03*
Y1232283D03*
Y1224803D03*
X1066732Y1239763D03*
Y1243503D03*
X1074212Y1239763D03*
Y1243503D03*
Y1258465D03*
X1066732D03*
X1072593Y1348187D03*
X1064713D03*
X1060353D03*
X1072593Y1360099D03*
X1064713D03*
X1060353D03*
X1072593Y1384297D03*
Y1372385D03*
X1064713D03*
Y1384297D03*
X1060353D03*
Y1372385D03*
X1072593Y1396583D03*
X1064713D03*
X1072593Y1408495D03*
X1064713D03*
X1089171Y1071455D03*
X1083562Y1092027D03*
X1089172Y1090157D03*
X1083562Y1095767D03*
X1087302Y1106988D03*
X1079822D03*
X1083562D03*
X1076082D03*
X1089172Y1101377D03*
Y1105117D03*
X1083562Y1118208D03*
X1087302D03*
X1079822Y1114468D03*
X1083562Y1110728D03*
X1087302D03*
X1091043D03*
Y1121948D03*
Y1118208D03*
Y1114468D03*
X1076082D03*
X1089172Y1108858D03*
X1091043Y1125688D03*
Y1140649D03*
X1079822Y1129429D03*
Y1140649D03*
X1083562D03*
X1087302D03*
X1091043Y1136909D03*
Y1133169D03*
Y1129429D03*
X1076082Y1140649D03*
X1087302Y1151870D03*
Y1155610D03*
Y1148129D03*
X1083562Y1144389D03*
X1087302D03*
X1076082Y1155610D03*
Y1151870D03*
Y1148129D03*
Y1144389D03*
X1087302Y1170570D03*
Y1166830D03*
Y1159350D03*
X1091043Y1170570D03*
X1076082Y1159350D03*
X1081692Y1179921D03*
X1083562Y1181791D03*
X1087302D03*
Y1178051D03*
Y1174310D03*
X1076082Y1181791D03*
Y1178051D03*
Y1174310D03*
X1077952Y1183661D03*
X1081692D03*
X1085432D03*
X1089172Y1187401D03*
X1085432D03*
X1091043Y1185531D03*
X1077952Y1191141D03*
Y1198621D03*
X1081692Y1191141D03*
X1085432Y1194881D03*
X1089172D03*
X1085432Y1202362D03*
X1089172D03*
X1077952Y1206102D03*
X1081692D03*
X1085432Y1209842D03*
X1077952Y1221062D03*
X1089172Y1217322D03*
Y1221062D03*
X1085432D03*
Y1217322D03*
X1077952Y1232283D03*
Y1236023D03*
X1085432Y1232283D03*
Y1236023D03*
X1081692Y1224803D03*
X1089172D03*
X1085432D03*
Y1228543D03*
X1077952Y1239763D03*
X1081692D03*
Y1243503D03*
X1085432Y1250984D03*
Y1239763D03*
X1089172D03*
Y1247243D03*
X1089173Y1258465D03*
X1081692D03*
X1089193Y1348187D03*
X1084833D03*
X1076953D03*
X1089193Y1360099D03*
X1084833D03*
X1076953D03*
X1089193Y1384297D03*
Y1372385D03*
X1084833Y1384297D03*
Y1372385D03*
X1076953Y1384297D03*
Y1372385D03*
X1089193Y1396583D03*
X1084833D03*
X1076953D03*
X1089193Y1408495D03*
X1084833D03*
X1076953D03*
X1104132Y1071455D03*
X1096652D03*
X1092913Y1090157D03*
X1104133D03*
X1107873D03*
X1100393D03*
X1096653D03*
X1104133Y1093897D03*
X1092913D03*
Y1097637D03*
X1107873Y1093897D03*
Y1097637D03*
X1104133Y1101377D03*
X1100393Y1097637D03*
Y1093897D03*
X1096653Y1101377D03*
X1104133Y1105117D03*
X1096653D03*
X1094783Y1110728D03*
Y1121948D03*
X1098523D03*
X1102263D03*
X1106003D03*
X1094783Y1118208D03*
X1098523D03*
X1102263D03*
X1106003D03*
X1094783Y1114468D03*
X1107873Y1108858D03*
X1104133D03*
X1100393D03*
X1096653D03*
X1092913D03*
X1098523Y1140649D03*
X1102263D03*
X1094783Y1136909D03*
X1102263D03*
X1094783Y1133169D03*
X1098523D03*
X1102263D03*
X1094783Y1129429D03*
X1098523D03*
X1102263D03*
X1094783Y1125688D03*
X1098523D03*
X1102263D03*
X1106003D03*
X1094783Y1140649D03*
Y1151870D03*
Y1155610D03*
X1102263Y1151870D03*
X1094783Y1148129D03*
Y1144389D03*
X1102263D03*
X1106003Y1148129D03*
Y1155610D03*
X1102263Y1170570D03*
X1094783Y1159350D03*
X1102263D03*
X1094783Y1166830D03*
X1106003D03*
X1094783Y1181791D03*
X1102263Y1185531D03*
X1094783Y1174310D03*
Y1178051D03*
X1106003Y1181791D03*
Y1174310D03*
X1092913Y1187401D03*
X1098523Y1196751D03*
Y1193011D03*
X1106003Y1200491D03*
Y1196751D03*
Y1204232D03*
X1102263D03*
X1098523D03*
Y1200491D03*
X1102263D03*
Y1196751D03*
X1092913Y1191141D03*
Y1194881D03*
Y1198621D03*
Y1202362D03*
X1098523Y1207972D03*
X1102263D03*
X1106003D03*
Y1211712D03*
X1102263D03*
X1098523D03*
Y1219192D03*
X1106003D03*
X1092913Y1206102D03*
Y1209842D03*
Y1213582D03*
Y1217322D03*
X1107873Y1221062D03*
X1104133D03*
X1100393D03*
X1096653D03*
X1092913D03*
Y1232283D03*
Y1236023D03*
X1107873Y1232283D03*
X1104133Y1224803D03*
X1107873Y1236023D03*
X1100393Y1232283D03*
Y1236023D03*
X1096653Y1224803D03*
X1100393Y1228543D03*
X1092913Y1224803D03*
X1107873D03*
X1100393D03*
X1107873Y1228543D03*
X1092913D03*
X1100393Y1239763D03*
X1107873D03*
X1104133Y1243503D03*
X1096653D03*
X1104133Y1258465D03*
X1096653D03*
X1101433Y1348187D03*
X1097073D03*
X1101433Y1360099D03*
X1097073D03*
X1101433Y1384297D03*
Y1372385D03*
X1097073D03*
Y1384297D03*
X1101433Y1396583D03*
X1097073D03*
X1101433Y1408495D03*
X1097073D03*
X1119093Y1071455D03*
X1111612D03*
X1115354Y1090157D03*
X1119094D03*
X1122834D03*
X1111613D03*
X1122834Y1093897D03*
X1115354D03*
X1122834Y1097637D03*
X1115354D03*
X1119094Y1101377D03*
X1111613D03*
X1119094Y1105117D03*
X1111613D03*
X1117224Y1121948D03*
Y1118208D03*
X1120964D03*
X1109743Y1121948D03*
X1113484D03*
X1109743Y1118208D03*
X1113484D03*
X1124704Y1121948D03*
Y1118208D03*
X1120964Y1121948D03*
X1122834Y1108858D03*
X1119094D03*
X1115354D03*
X1111613D03*
X1109743Y1136909D03*
X1124704Y1125688D03*
Y1140649D03*
Y1133169D03*
X1113484D03*
X1117224D03*
X1120964D03*
X1109743Y1125688D03*
X1120964D03*
X1117224D03*
X1113484D03*
X1120964Y1140649D03*
X1117224D03*
X1113484D03*
X1109743Y1129429D03*
Y1133169D03*
X1113484Y1155610D03*
X1109743Y1144389D03*
X1120964Y1155610D03*
X1109743Y1151869D03*
X1120964Y1148129D03*
X1113484D03*
X1117224D03*
X1124704D03*
X1117224Y1170570D03*
X1109743D03*
X1113484Y1166830D03*
X1117224Y1159350D03*
X1120964Y1166830D03*
X1109743Y1159350D03*
X1124704Y1170570D03*
Y1159350D03*
X1109743Y1189271D03*
X1113484D03*
X1117224D03*
X1120964D03*
X1113484Y1181791D03*
X1117224D03*
X1120964D03*
X1124704Y1189271D03*
Y1181791D03*
X1109743Y1178051D03*
X1120964Y1174310D03*
X1109743Y1185531D03*
X1113484Y1174310D03*
X1124704Y1204232D03*
Y1196751D03*
X1120964Y1204232D03*
X1117224D03*
X1113484D03*
X1109743D03*
Y1193011D03*
Y1196751D03*
Y1200491D03*
X1113484Y1196751D03*
X1117224D03*
X1120964D03*
X1113484Y1207972D03*
X1117224D03*
X1120964D03*
X1109743Y1211712D03*
Y1207972D03*
X1124704D03*
X1122834Y1221062D03*
X1119094D03*
X1115354D03*
X1111613D03*
X1122834Y1224803D03*
Y1232283D03*
Y1236023D03*
X1119094Y1224803D03*
X1115354Y1232283D03*
Y1236023D03*
X1111613Y1224803D03*
X1115354Y1228543D03*
Y1224803D03*
X1122834Y1228543D03*
X1119094Y1243503D03*
X1122834Y1239763D03*
X1111613Y1243503D03*
Y1239763D03*
X1119094Y1258465D03*
X1111614D03*
X1113673Y1348187D03*
X1121553D03*
X1109313D03*
X1113673Y1360099D03*
X1121553D03*
X1109313D03*
X1113673Y1372385D03*
Y1384297D03*
X1121553Y1372385D03*
Y1384297D03*
X1109313D03*
Y1372385D03*
X1113673Y1396583D03*
X1121553D03*
X1109313D03*
X1113673Y1408495D03*
X1121553D03*
X1109313D03*
X1134053Y1071455D03*
X1126573D03*
X1126574Y1090157D03*
X1130314D03*
X1134054D03*
X1137795D03*
X1126574Y1101377D03*
X1130314Y1097637D03*
Y1093897D03*
X1137795D03*
Y1097637D03*
X1134054Y1101377D03*
X1126574Y1105117D03*
X1134054D03*
X1139665Y1121948D03*
X1130314Y1112598D03*
X1128444Y1118208D03*
X1132184D03*
X1135924D03*
X1132184Y1121948D03*
X1135924D03*
X1128444D03*
X1139665Y1118208D03*
X1137795Y1108858D03*
X1134054D03*
X1130314D03*
X1126574D03*
X1139665Y1125688D03*
X1128444Y1140649D03*
X1132184D03*
X1135924D03*
X1132184Y1125688D03*
X1128444D03*
X1135924D03*
Y1133169D03*
X1132184D03*
X1128444D03*
X1139665D03*
Y1140649D03*
X1135924Y1148129D03*
X1132184D03*
X1128444D03*
X1139665D03*
X1128444Y1155610D03*
X1135924D03*
X1139665Y1170570D03*
Y1159350D03*
X1132184Y1170570D03*
X1135925Y1166830D03*
X1128444D03*
X1132184Y1159350D03*
X1135924Y1181791D03*
X1132184D03*
X1128444D03*
X1135924Y1189271D03*
X1132184D03*
X1128444D03*
Y1174310D03*
X1135924D03*
X1139665Y1181791D03*
Y1189271D03*
Y1196751D03*
Y1204232D03*
X1135924D03*
Y1196751D03*
X1132184D03*
X1128444D03*
Y1204232D03*
X1132184D03*
X1139665Y1207972D03*
X1134054Y1217322D03*
X1135924Y1207972D03*
X1132184D03*
X1128444D03*
X1137795Y1221062D03*
X1134054D03*
X1130314D03*
X1126574D03*
Y1224803D03*
X1137795Y1232283D03*
Y1236023D03*
X1134054Y1224803D03*
X1130314Y1232283D03*
Y1236023D03*
X1137795Y1228543D03*
Y1224803D03*
X1130314Y1228543D03*
Y1224803D03*
X1126574Y1243503D03*
X1134054D03*
X1137795Y1239763D03*
X1130314D03*
X1134055Y1258465D03*
X1126574D03*
X1138153Y1348187D03*
X1133793D03*
X1125913D03*
X1138153Y1360099D03*
X1133793D03*
X1125913D03*
X1138153Y1384297D03*
Y1372385D03*
X1133793Y1384297D03*
Y1372385D03*
X1125913Y1384297D03*
Y1372385D03*
X1138153Y1396583D03*
X1133793D03*
X1125913D03*
X1138153Y1408495D03*
X1133793D03*
X1125913D03*
X1152755Y1075196D03*
X1156494Y1071455D03*
X1149014Y1071454D03*
X1141534Y1071455D03*
X1141535Y1090157D03*
X1149015Y1082677D03*
Y1086417D03*
X1152755Y1090157D03*
X1156495D03*
Y1086417D03*
X1149015Y1090157D03*
X1145275D03*
X1141535Y1101377D03*
X1149015D03*
X1152755Y1093897D03*
X1156495Y1101377D03*
X1145275Y1093897D03*
Y1097637D03*
X1141535Y1105117D03*
X1149015D03*
X1156495D03*
X1150885Y1121948D03*
X1143405D03*
Y1118208D03*
Y1114468D03*
X1154625Y1121948D03*
X1156495Y1108858D03*
X1152755D03*
X1149015D03*
X1145275D03*
X1141535D03*
X1154625Y1125688D03*
X1150885Y1133464D03*
X1154625Y1133169D03*
X1143503Y1132677D03*
X1143405Y1140649D03*
Y1125688D03*
X1150885Y1140649D03*
X1154625D03*
X1150885Y1125688D03*
X1143405Y1148129D03*
X1150885D03*
X1154625D03*
X1143405Y1155610D03*
X1154625D03*
Y1166830D03*
X1150885Y1170570D03*
X1143405Y1166830D03*
X1150885Y1159350D03*
X1143405Y1181791D03*
X1154625D03*
X1150885D03*
Y1189271D03*
X1154625D03*
X1143405D03*
Y1174310D03*
X1154625D03*
X1150885Y1196751D03*
X1154625Y1204232D03*
X1150885D03*
X1154625Y1196751D03*
X1143405D03*
Y1204232D03*
X1150885Y1207972D03*
X1154625D03*
Y1211712D03*
X1143405Y1207972D03*
X1149015Y1221062D03*
X1156495D03*
X1152755D03*
X1145275D03*
X1141535D03*
Y1224803D03*
X1152755Y1232283D03*
Y1236023D03*
X1156495Y1228543D03*
Y1224803D03*
X1149015Y1228543D03*
Y1224803D03*
X1145275Y1232283D03*
Y1236023D03*
X1141535Y1243503D03*
X1152755Y1239763D03*
X1145275D03*
X1156495Y1258465D03*
X1149015D03*
X1141536D03*
X1150393Y1348187D03*
X1146033D03*
X1150393Y1360099D03*
X1146033D03*
X1150393Y1384297D03*
Y1372385D03*
X1146033D03*
Y1384297D03*
X1150393Y1396583D03*
X1146033D03*
X1150393Y1408495D03*
X1146033D03*
X1167716Y1075196D03*
X1160235D03*
X1171455Y1071455D03*
X1163975D03*
X1167716Y1078936D03*
X1163976Y1086417D03*
Y1090157D03*
X1171456Y1086417D03*
Y1090157D03*
X1167716D03*
X1160235Y1078936D03*
Y1090157D03*
X1167716Y1097637D03*
Y1093897D03*
X1160235D03*
Y1097637D03*
X1163976Y1105117D03*
X1171456D03*
X1169586Y1121948D03*
X1165846D03*
X1162106D03*
X1158365D03*
X1173326D03*
X1171456Y1108858D03*
X1167716D03*
X1163976D03*
X1160235D03*
X1162106Y1133169D03*
X1165846D03*
X1169586D03*
X1158365Y1140649D03*
X1162106D03*
X1165846D03*
X1169586D03*
X1158365Y1125688D03*
X1162106D03*
X1165846D03*
X1169586D03*
X1173326Y1133169D03*
Y1125688D03*
Y1140649D03*
X1158365Y1133169D03*
X1173326Y1148129D03*
X1158365D03*
X1162106D03*
X1165846D03*
X1169586D03*
X1162106Y1155610D03*
X1169586D03*
X1158365Y1170570D03*
X1165846D03*
X1169586Y1166830D03*
X1158365Y1159350D03*
X1162106Y1166830D03*
X1165846Y1159350D03*
X1173326D03*
Y1170570D03*
Y1189271D03*
X1158365Y1181791D03*
X1162106D03*
X1165846D03*
X1169586D03*
X1158365Y1189271D03*
X1162106D03*
X1165846D03*
X1169586D03*
X1173326Y1181791D03*
X1169586Y1174310D03*
X1162106D03*
Y1204232D03*
X1158365D03*
X1169586D03*
X1165846D03*
X1158365Y1196751D03*
X1162106D03*
X1165846D03*
X1169586D03*
X1173326Y1204232D03*
Y1196751D03*
X1158365Y1211712D03*
Y1207972D03*
X1173326D03*
Y1211712D03*
X1162106Y1207972D03*
X1165846D03*
X1169586Y1211712D03*
Y1207972D03*
X1171456Y1221062D03*
X1167716D03*
X1163976D03*
X1160235D03*
X1163976Y1228543D03*
Y1224803D03*
X1171456Y1228543D03*
Y1224803D03*
X1167716Y1232283D03*
Y1236023D03*
X1160235Y1232283D03*
Y1236023D03*
X1171456Y1239763D03*
X1160235D03*
X1171456Y1258465D03*
X1163976D03*
X1162633Y1348187D03*
X1170513D03*
X1158273D03*
X1162633Y1360099D03*
X1170513D03*
X1158273D03*
X1162633Y1372385D03*
Y1384297D03*
X1170513Y1372385D03*
Y1384297D03*
X1158273D03*
Y1372385D03*
X1162633Y1396583D03*
X1170513D03*
X1158273D03*
X1162633Y1408495D03*
X1170513D03*
X1158273D03*
X1175196Y1075196D03*
X1182676D03*
X1186416Y1071455D03*
X1178935D03*
X1175196Y1078936D03*
Y1090157D03*
X1178936D03*
X1182676Y1078936D03*
X1178936Y1086417D03*
X1182676Y1090157D03*
X1186417D03*
Y1086417D03*
Y1082677D03*
X1175196Y1097637D03*
Y1093897D03*
X1182676Y1097637D03*
Y1093897D03*
X1178936Y1105117D03*
X1186417D03*
X1188287Y1118208D03*
X1184546D03*
X1180806Y1121948D03*
X1177066D03*
X1184546D03*
X1186417Y1108858D03*
X1182676D03*
X1178936D03*
X1175196D03*
X1188287Y1125688D03*
X1184546Y1136909D03*
X1177066Y1133169D03*
X1180806D03*
X1184546D03*
X1177066Y1140649D03*
X1180806D03*
X1184546Y1125688D03*
Y1129429D03*
X1177066Y1125688D03*
X1180806D03*
X1184546Y1140649D03*
X1188287Y1155610D03*
Y1151869D03*
Y1148129D03*
X1177066D03*
X1180806D03*
X1184546Y1144389D03*
Y1148129D03*
Y1151869D03*
X1177066Y1155610D03*
X1184546D03*
X1177066Y1166830D03*
X1188287D03*
Y1159350D03*
Y1170570D03*
Y1181791D03*
Y1174310D03*
X1177066Y1189271D03*
X1180806D03*
X1184546Y1178051D03*
X1177066Y1174310D03*
X1184546Y1185531D03*
X1177066Y1181791D03*
X1180806D03*
X1184546Y1189271D03*
Y1174310D03*
Y1204232D03*
X1177066D03*
X1180806D03*
X1184546Y1200491D03*
X1177066Y1196751D03*
X1180806D03*
X1184546Y1193011D03*
X1188287Y1196751D03*
X1184566Y1196732D03*
X1188287Y1207972D03*
X1184546Y1211712D03*
X1177066Y1207972D03*
Y1211712D03*
X1180806Y1207972D03*
Y1211712D03*
X1184546Y1207972D03*
X1186417Y1221062D03*
X1182676D03*
X1178936D03*
X1175196D03*
Y1232283D03*
Y1236023D03*
X1178936Y1228543D03*
Y1224803D03*
X1182676Y1232283D03*
Y1236023D03*
X1186417Y1228543D03*
Y1224803D03*
X1182676Y1239763D03*
X1186417Y1258465D03*
X1178936D03*
X1182753Y1348187D03*
X1174873D03*
X1182753Y1360099D03*
X1174873D03*
X1182753Y1384297D03*
Y1372385D03*
X1174873Y1384297D03*
Y1372385D03*
X1182753Y1396583D03*
X1174873D03*
X1182753Y1408495D03*
X1174873D03*
X1179329Y1728990D03*
Y1738990D03*
X1179123Y1776014D03*
Y1786014D03*
X1190157Y1075196D03*
X1197637D03*
X1205117D03*
X1201376Y1071455D03*
X1193896D03*
X1190157Y1090157D03*
X1197637Y1078936D03*
Y1090157D03*
X1201377D03*
X1205116D03*
X1193897D03*
X1190157Y1093897D03*
X1201377Y1101377D03*
X1205117Y1093897D03*
X1201377Y1105117D03*
X1193897D03*
X1192027Y1118208D03*
X1205117Y1123818D03*
Y1120078D03*
Y1116338D03*
Y1108858D03*
X1201377D03*
X1197637D03*
X1193897D03*
X1190157D03*
X1192027Y1136909D03*
X1195767Y1140649D03*
X1192027D03*
X1195767Y1136909D03*
X1205117Y1135039D03*
Y1131299D03*
Y1127558D03*
X1195767Y1148129D03*
X1192027Y1144389D03*
X1195767Y1155610D03*
X1192027Y1148129D03*
X1195767Y1151869D03*
X1199507D03*
X1203247D03*
Y1155610D03*
X1192027Y1151870D03*
X1195767Y1170570D03*
Y1159350D03*
X1203247Y1166830D03*
Y1170570D03*
Y1159350D03*
X1195767Y1166830D03*
X1192027Y1181791D03*
X1199507Y1185531D03*
X1203247Y1174310D03*
Y1178051D03*
Y1185531D03*
X1192027Y1178051D03*
Y1189271D03*
X1195767D03*
X1192027Y1185531D03*
X1195767D03*
X1199507Y1181791D03*
X1195767Y1178051D03*
Y1174310D03*
Y1204232D03*
X1199507Y1193011D03*
X1195767Y1196751D03*
Y1193011D03*
X1192027D03*
X1205117Y1198621D03*
Y1202362D03*
X1192027Y1211712D03*
X1205117Y1206102D03*
Y1209842D03*
Y1213582D03*
Y1217322D03*
Y1221062D03*
X1201377D03*
X1197637D03*
X1193897D03*
X1190157D03*
Y1232283D03*
Y1236023D03*
X1197637Y1232283D03*
X1201377Y1228543D03*
X1197637Y1236023D03*
X1201377Y1224803D03*
X1205117Y1232283D03*
Y1236023D03*
X1193897Y1228543D03*
Y1224803D03*
X1197637Y1239763D03*
X1205117D03*
Y1243503D03*
Y1247243D03*
X1201377Y1258465D03*
X1193897D03*
X1212598Y1075196D03*
X1220079D03*
X1216338Y1071455D03*
X1208857D03*
X1220079Y1078936D03*
X1212599D03*
X1212597Y1090157D03*
X1212598Y1093897D03*
X1220078D03*
X1216338Y1105117D03*
X1208858D03*
X1212598Y1108858D03*
X1216338Y1116338D03*
Y1123818D03*
X1208857Y1112598D03*
Y1120078D03*
X1220077Y1108857D03*
X1208858Y1108858D03*
X1214468Y1140649D03*
X1206987Y1136909D03*
X1216338Y1131299D03*
X1206987Y1151869D03*
X1214468Y1148129D03*
X1206987Y1144389D03*
Y1159350D03*
X1214468D03*
X1206987Y1166830D03*
X1214468D03*
X1221948Y1170570D03*
X1206987Y1181791D03*
X1214468Y1189271D03*
X1221948Y1178051D03*
Y1185531D03*
X1206987Y1174310D03*
Y1189271D03*
X1214468Y1181791D03*
Y1174310D03*
X1208858Y1194881D03*
X1221948Y1193011D03*
X1212598Y1202362D03*
X1220078Y1198621D03*
Y1221062D03*
X1216338D03*
X1220078Y1213582D03*
X1212598Y1209842D03*
X1208858Y1221062D03*
Y1217322D03*
X1216338Y1224803D03*
Y1228543D03*
X1212598Y1232283D03*
Y1236023D03*
X1220078Y1232283D03*
Y1236023D03*
X1208858Y1224803D03*
Y1228543D03*
X1212598Y1239763D03*
Y1243503D03*
X1220078Y1247243D03*
Y1243503D03*
X1212598Y1247243D03*
X1208858Y1254724D03*
Y1250984D03*
X1216338Y1254724D03*
Y1250984D03*
Y1258465D03*
X1208858D03*
X1227559Y1075196D03*
X1235039D03*
X1231298Y1071455D03*
X1223818D03*
X1235039Y1078936D03*
X1227559D03*
X1227557Y1090157D03*
X1227558Y1093897D03*
X1223818Y1105117D03*
X1227558Y1108858D03*
X1233169Y1140649D03*
Y1155610D03*
Y1148129D03*
X1236909Y1170570D03*
X1225688Y1166830D03*
X1233169Y1170570D03*
X1236909Y1178051D03*
Y1185531D03*
X1233169D03*
Y1178051D03*
X1225688Y1174310D03*
Y1181791D03*
Y1189271D03*
X1233169Y1193011D03*
X1223818Y1194881D03*
X1236909Y1193011D03*
X1223818Y1202362D03*
Y1198621D03*
X1235039Y1202362D03*
X1223818Y1206102D03*
Y1221062D03*
Y1217322D03*
Y1213582D03*
Y1209842D03*
X1227558Y1221062D03*
X1235039Y1209842D03*
Y1206102D03*
X1223818Y1224803D03*
Y1228543D03*
X1231298Y1224803D03*
Y1228543D03*
X1227558Y1236023D03*
Y1232283D03*
X1235039D03*
X1225688Y1222932D03*
X1223818Y1239763D03*
X1227558Y1247243D03*
X1231298Y1254724D03*
X1223818D03*
Y1250984D03*
X1235039Y1239763D03*
X1227558Y1243503D03*
X1231298Y1250984D03*
Y1258465D03*
X1223818D03*
X1235966Y1348187D03*
X1228086D03*
X1235966Y1360099D03*
X1228086D03*
X1235966Y1372385D03*
Y1384297D03*
X1228086Y1372385D03*
Y1384297D03*
X1238779Y1078936D03*
X1242520Y1090158D03*
Y1082677D03*
Y1101378D03*
Y1123819D03*
Y1116339D03*
Y1108859D03*
Y1131300D03*
X1240589Y1193011D03*
X1238779Y1202362D03*
X1242520Y1198621D03*
Y1221062D03*
Y1213582D03*
Y1206102D03*
Y1228543D03*
X1238779Y1250984D03*
X1242520Y1247243D03*
Y1239762D03*
X1238779Y1239763D03*
X1252566Y1348187D03*
X1240326D03*
X1248206D03*
X1252566Y1360099D03*
X1240326D03*
X1248206D03*
X1252566Y1372385D03*
Y1384297D03*
X1240326D03*
Y1372385D03*
X1248206D03*
Y1384297D03*
X1252566Y1396583D03*
X1240326D03*
X1248206D03*
X1252566Y1408495D03*
X1240326D03*
X1248206D03*
X1264806Y1348187D03*
X1260446D03*
X1264806Y1360099D03*
X1260446D03*
X1264806Y1372385D03*
Y1384297D03*
X1260446Y1372385D03*
Y1384297D03*
X1264806Y1396583D03*
X1260446D03*
X1264806Y1408495D03*
X1260446D03*
X1284926Y1348187D03*
X1277046D03*
X1272686D03*
X1284926Y1360099D03*
X1277046D03*
X1272686D03*
X1284926Y1372385D03*
Y1384297D03*
X1277046Y1372385D03*
Y1384297D03*
X1272686D03*
Y1372385D03*
X1284926Y1396583D03*
X1277046D03*
X1272686D03*
X1284926Y1408495D03*
X1277046D03*
X1272686D03*
X1301526Y1348187D03*
X1289286D03*
X1297166D03*
X1301526Y1360099D03*
X1289286D03*
X1297166D03*
X1301526Y1372385D03*
Y1384297D03*
X1289286D03*
Y1372385D03*
X1297166Y1384297D03*
Y1372385D03*
X1301526Y1396583D03*
X1289286D03*
X1297166D03*
X1301526Y1408495D03*
X1289286D03*
X1297166D03*
X1313766Y1348187D03*
X1309406D03*
X1313766Y1360099D03*
X1309406D03*
X1313766Y1372385D03*
Y1384297D03*
X1309406Y1372385D03*
Y1384297D03*
X1313766Y1396583D03*
X1309406D03*
X1313766Y1408495D03*
X1309406D03*
X1333886Y1348187D03*
X1326006D03*
X1321646D03*
X1333886Y1360099D03*
X1326006D03*
X1321646D03*
X1333886Y1372385D03*
Y1384297D03*
X1326006Y1372385D03*
Y1384297D03*
X1321646D03*
Y1372385D03*
X1333886Y1396583D03*
X1326006D03*
X1321646D03*
X1333886Y1408495D03*
X1326006D03*
X1321646D03*
X1350486Y1348187D03*
X1338246D03*
X1346126D03*
X1350486Y1360099D03*
X1338246D03*
X1346126D03*
X1350486Y1372385D03*
Y1384297D03*
X1338246D03*
Y1372385D03*
X1346126Y1384297D03*
Y1372385D03*
X1350486Y1396583D03*
X1338246D03*
X1346126D03*
X1350486Y1408495D03*
X1338246D03*
X1346126D03*
X1358366Y1348187D03*
Y1360099D03*
Y1372385D03*
Y1384297D03*
Y1396583D03*
Y1408495D03*
X1459130Y1348187D03*
Y1360099D03*
Y1384297D03*
Y1372385D03*
X1479250Y1348187D03*
X1471370D03*
X1467010D03*
X1479250Y1360099D03*
X1471370D03*
X1467010D03*
X1479250Y1384297D03*
Y1372385D03*
X1471370D03*
Y1384297D03*
X1467010D03*
Y1372385D03*
X1479250Y1396583D03*
X1471370D03*
X1479250Y1408495D03*
X1471370D03*
X1495850Y1348187D03*
X1483610D03*
X1491490D03*
X1495850Y1360099D03*
X1483610D03*
X1491490D03*
X1483610Y1384297D03*
Y1372385D03*
X1491490Y1384297D03*
Y1372385D03*
X1495850Y1384297D03*
Y1372385D03*
Y1396583D03*
X1483610D03*
X1491490D03*
X1495850Y1408495D03*
X1483610D03*
X1491490D03*
X1514468Y1103247D03*
Y1125688D03*
Y1133169D03*
Y1140649D03*
Y1144389D03*
Y1151870D03*
Y1159350D03*
X1512597Y1198622D03*
Y1191142D03*
Y1221063D03*
Y1213583D03*
Y1206103D03*
X1508090Y1348187D03*
X1503730D03*
X1508090Y1360099D03*
X1503730D03*
X1508090Y1384297D03*
Y1372385D03*
X1503730D03*
Y1384297D03*
X1508090Y1396583D03*
X1503730D03*
X1508090Y1408495D03*
X1503730D03*
X1521948Y1077066D03*
X1518208Y1080806D03*
Y1103247D03*
X1529429Y1106988D03*
Y1118208D03*
Y1121948D03*
X1525689D03*
X1521949D03*
X1529429Y1125688D03*
X1518208D03*
X1525689Y1129429D03*
X1521949D03*
X1518208Y1133169D03*
X1521949Y1136909D03*
X1529429Y1140649D03*
X1525689D03*
X1521949D03*
X1518208D03*
X1521949Y1144389D03*
X1518208D03*
X1521949Y1148129D03*
Y1151870D03*
X1518208D03*
X1529429Y1155610D03*
X1525689D03*
X1521949D03*
Y1159350D03*
X1518208D03*
X1529429Y1166830D03*
X1521948D03*
X1525689Y1170570D03*
X1521948D03*
Y1174310D03*
X1518207D03*
X1521948Y1178051D03*
X1525689Y1174310D03*
X1529429D03*
X1527559Y1179921D03*
X1523819D03*
X1518207Y1181791D03*
X1516338Y1187401D03*
X1520078D03*
X1527559Y1183661D03*
X1523819D03*
X1520078D03*
X1516338D03*
Y1194881D03*
Y1202362D03*
X1527559Y1191141D03*
X1523819D03*
X1527559Y1198621D03*
X1523819D03*
X1520078Y1194881D03*
Y1202362D03*
X1516338Y1209842D03*
Y1217322D03*
X1523819Y1206102D03*
X1527559D03*
Y1213582D03*
X1523819D03*
X1520078Y1209842D03*
Y1217322D03*
X1523819Y1221062D03*
X1527559D03*
Y1228543D03*
X1516338Y1232283D03*
Y1236023D03*
Y1224803D03*
X1527559Y1236023D03*
Y1232283D03*
X1523819Y1228543D03*
Y1224803D03*
X1520078Y1236023D03*
Y1232283D03*
Y1224803D03*
X1527559D03*
X1516338Y1239763D03*
X1523819D03*
Y1243503D03*
X1520078Y1239763D03*
X1523819Y1258465D03*
X1528210Y1348187D03*
X1520330D03*
X1515970D03*
X1528210Y1360099D03*
X1520330D03*
X1515970D03*
X1528210Y1372385D03*
Y1384297D03*
X1520330Y1372385D03*
Y1384297D03*
X1515970D03*
Y1372385D03*
X1528210Y1396583D03*
X1520330D03*
X1515970D03*
X1528210Y1408495D03*
X1520330D03*
X1515970D03*
X1546258Y1071455D03*
X1540649Y1092027D03*
X1546259Y1090157D03*
X1544389Y1099507D03*
X1540649Y1106988D03*
X1536909D03*
X1533169D03*
X1544389D03*
X1540649Y1095767D03*
X1546259Y1101377D03*
Y1105117D03*
X1544389Y1118208D03*
X1540649D03*
X1544389Y1110728D03*
X1540649D03*
X1536909Y1114468D03*
X1533169D03*
X1544389Y1140649D03*
X1540649D03*
X1536909D03*
X1533169D03*
X1536909Y1129429D03*
X1544389Y1144389D03*
X1540649D03*
X1533169D03*
Y1148129D03*
Y1151870D03*
Y1155610D03*
X1544389Y1148129D03*
Y1155610D03*
Y1151870D03*
X1533169Y1159350D03*
X1544389D03*
Y1166830D03*
Y1170570D03*
X1535039Y1187401D03*
X1533169Y1174310D03*
Y1178051D03*
X1544389Y1174310D03*
Y1178051D03*
Y1181791D03*
X1540649D03*
X1538779Y1179921D03*
X1531299D03*
Y1187401D03*
X1546259D03*
X1542519D03*
Y1183661D03*
X1538779D03*
X1535039D03*
X1531299D03*
X1538779Y1187401D03*
X1542519Y1191141D03*
X1538779Y1202362D03*
X1535039Y1194881D03*
X1542519Y1198621D03*
X1535039Y1191141D03*
X1531299D03*
X1535039Y1198621D03*
X1531299D03*
X1538779Y1191141D03*
X1542519Y1194881D03*
X1546259D03*
X1542519Y1202362D03*
X1546259D03*
Y1198621D03*
Y1191141D03*
X1535039Y1202362D03*
X1538779Y1194881D03*
X1542519Y1213582D03*
Y1206102D03*
X1546259Y1213582D03*
X1535039Y1209842D03*
X1531299Y1206102D03*
X1535039D03*
X1538779D03*
X1542519Y1209842D03*
X1531299Y1221062D03*
X1535039D03*
X1546259Y1217322D03*
Y1221062D03*
X1542519D03*
Y1217322D03*
X1535039D03*
X1546259Y1206102D03*
X1538779Y1209842D03*
Y1217322D03*
X1535039Y1224803D03*
X1542519Y1228543D03*
X1535039D03*
X1531299Y1224803D03*
X1535039Y1232283D03*
Y1236023D03*
X1542519Y1232283D03*
Y1236023D03*
X1538779Y1224803D03*
X1546259D03*
X1542519D03*
X1535039Y1239763D03*
X1531299D03*
Y1243503D03*
X1538779Y1239763D03*
Y1243503D03*
X1542519Y1250984D03*
Y1239763D03*
X1546259D03*
Y1247243D03*
Y1250984D03*
X1542519Y1243503D03*
X1546259Y1254724D03*
X1542519Y1247243D03*
X1546260Y1258465D03*
X1538779D03*
X1531299D03*
X1544810Y1348187D03*
X1532570D03*
X1540450D03*
X1544810Y1360099D03*
X1532570D03*
X1540450D03*
X1544810Y1384297D03*
Y1372385D03*
X1532570Y1384297D03*
Y1372385D03*
X1540450Y1384297D03*
Y1372385D03*
X1544810Y1396583D03*
X1532570D03*
X1540450D03*
X1544810Y1408495D03*
X1532570D03*
X1540450D03*
X1561219Y1071455D03*
X1553739D03*
X1561220Y1090157D03*
X1557480D03*
X1553740D03*
X1550000D03*
X1561220Y1093897D03*
Y1105117D03*
X1553740D03*
X1561220Y1101377D03*
X1557480Y1097637D03*
Y1093897D03*
X1553740Y1101377D03*
X1550000Y1093897D03*
Y1097637D03*
X1551870Y1114468D03*
X1548130D03*
X1563090Y1118208D03*
X1559350D03*
X1555610D03*
X1551870D03*
X1548130D03*
X1563090Y1121948D03*
X1559350D03*
X1555610D03*
X1551870D03*
X1548130D03*
Y1110728D03*
X1561220Y1108858D03*
X1557480D03*
X1553740D03*
X1550000D03*
X1551870Y1110728D03*
X1548130Y1140649D03*
X1563090Y1125688D03*
X1559350D03*
X1555610D03*
X1551870D03*
X1548130D03*
X1559350Y1129429D03*
X1555610D03*
X1551870D03*
X1548130D03*
X1559350Y1133169D03*
X1555610D03*
X1551870D03*
X1548130D03*
X1559350Y1136909D03*
X1551870D03*
X1548130D03*
X1559350Y1140649D03*
X1555610D03*
X1551870D03*
Y1155610D03*
Y1151870D03*
X1559350Y1144389D03*
X1551870D03*
Y1148129D03*
X1559350Y1151870D03*
X1563090Y1155610D03*
Y1148129D03*
X1559350Y1170570D03*
X1551870Y1166830D03*
X1559350Y1159350D03*
X1551870D03*
X1548130Y1170570D03*
X1563090Y1166830D03*
X1551870Y1189271D03*
X1559350Y1185531D03*
X1551870D03*
Y1178051D03*
Y1174310D03*
Y1181791D03*
X1563090D03*
Y1174310D03*
X1550000Y1187401D03*
X1548130Y1185531D03*
X1551870Y1193011D03*
X1559350Y1196751D03*
Y1200491D03*
X1555610D03*
Y1204232D03*
X1559350D03*
X1563090D03*
Y1196751D03*
Y1200491D03*
X1555610Y1193011D03*
Y1196751D03*
X1550000Y1191141D03*
Y1194881D03*
Y1198621D03*
Y1202362D03*
X1555610Y1211712D03*
X1559350D03*
X1563090D03*
Y1207972D03*
X1559350D03*
X1555610D03*
X1563090Y1219192D03*
X1550000Y1221062D03*
X1553740D03*
X1557480D03*
X1561220D03*
X1550000Y1206102D03*
Y1209842D03*
Y1213582D03*
Y1217322D03*
X1553740D03*
X1550000Y1228543D03*
Y1224803D03*
X1557480Y1228543D03*
X1550000Y1232283D03*
Y1236023D03*
X1561220Y1224803D03*
X1557480Y1232283D03*
Y1236023D03*
X1553740Y1224803D03*
X1557480D03*
Y1239763D03*
X1561220Y1243503D03*
X1553740D03*
X1561220Y1250984D03*
Y1254724D03*
X1550000Y1243503D03*
X1557480Y1247243D03*
X1550000D03*
X1557480Y1243503D03*
X1553740Y1250984D03*
Y1254724D03*
X1561220Y1258465D03*
X1553740D03*
X1557050Y1348187D03*
X1552690D03*
Y1360099D03*
X1557050D03*
Y1384297D03*
Y1372385D03*
X1552690D03*
Y1384297D03*
X1557050Y1396583D03*
X1552690D03*
X1557050Y1408495D03*
X1552690D03*
X1576180Y1071455D03*
X1568699D03*
X1564960Y1090157D03*
X1572441D03*
X1576181D03*
X1568700D03*
X1576181Y1105117D03*
X1568700D03*
X1564960Y1093897D03*
Y1097637D03*
X1572441Y1093897D03*
Y1097637D03*
X1576181Y1101377D03*
X1568700D03*
X1566830Y1121948D03*
X1578051Y1118208D03*
X1574311D03*
Y1121948D03*
X1578051D03*
X1570571Y1118208D03*
X1566830D03*
X1570571Y1121948D03*
X1576181Y1108858D03*
X1572441D03*
X1568700D03*
X1564960D03*
X1566830Y1133169D03*
Y1129429D03*
X1570571Y1140649D03*
X1574311D03*
X1578051D03*
X1570571Y1125688D03*
X1574311D03*
X1578051D03*
X1566830D03*
X1578051Y1133169D03*
X1574311D03*
X1570571D03*
X1566830Y1136909D03*
X1574311Y1148129D03*
X1570571D03*
X1578051D03*
X1570571Y1155610D03*
X1566830Y1151869D03*
X1578051Y1155610D03*
X1566830Y1144389D03*
Y1159350D03*
X1578051Y1166830D03*
X1574311Y1159350D03*
X1570571Y1166830D03*
X1566830Y1170570D03*
X1574311D03*
X1578051Y1181791D03*
X1574311D03*
X1570571D03*
X1578051Y1189271D03*
X1574311D03*
X1570571D03*
X1566830D03*
Y1178051D03*
X1570571Y1174310D03*
X1566830Y1185531D03*
X1578051Y1174310D03*
X1574311Y1204232D03*
X1578051D03*
Y1196751D03*
X1574311D03*
X1570571D03*
X1566830Y1200491D03*
Y1196751D03*
Y1193011D03*
Y1204232D03*
X1570571D03*
X1566830Y1207972D03*
Y1211712D03*
X1578051Y1207972D03*
X1574311D03*
X1570571D03*
X1564960Y1221062D03*
X1568700D03*
X1572441D03*
X1576181D03*
X1564960Y1224803D03*
Y1232283D03*
Y1236023D03*
X1576181Y1224803D03*
X1572441Y1232283D03*
Y1236023D03*
X1568700Y1224803D03*
X1564960Y1228543D03*
Y1239763D03*
X1576181Y1243503D03*
X1568700D03*
Y1239763D03*
Y1254724D03*
X1564960Y1243503D03*
Y1247243D03*
X1568700Y1250984D03*
X1576181Y1258465D03*
X1568701D03*
X1564930Y1348187D03*
X1569290D03*
X1577170D03*
X1569290Y1360099D03*
X1577170D03*
X1564930D03*
X1577170Y1372385D03*
Y1384297D03*
X1569290Y1372385D03*
Y1384297D03*
X1564930D03*
Y1372385D03*
X1577170Y1396583D03*
X1569290D03*
X1564930D03*
X1577170Y1408495D03*
X1569290D03*
X1564930D03*
X1591140Y1071455D03*
X1583660D03*
X1579921Y1090157D03*
X1583661D03*
X1587401D03*
X1591141D03*
X1594882D03*
X1583661Y1105117D03*
X1591141D03*
X1579921Y1093897D03*
Y1097637D03*
X1583661Y1101377D03*
X1587401Y1097637D03*
Y1093897D03*
X1594882D03*
Y1097637D03*
X1591141Y1101377D03*
X1581791Y1121948D03*
X1585531Y1118208D03*
X1589271D03*
X1593011D03*
X1589271Y1121948D03*
X1593011D03*
X1585531D03*
X1581791Y1118208D03*
X1594882Y1108858D03*
X1591141D03*
X1587401D03*
X1583661D03*
X1579921D03*
X1587401Y1112598D03*
X1581791Y1133169D03*
Y1140649D03*
X1585531D03*
X1589271D03*
X1593011D03*
X1589271Y1125688D03*
X1585531D03*
X1581791D03*
X1593011D03*
Y1133169D03*
X1589271D03*
X1585531D03*
X1593011Y1148129D03*
X1589271D03*
X1585531D03*
X1581791D03*
X1593011Y1155610D03*
X1585531D03*
X1589271Y1170570D03*
X1593012Y1166830D03*
X1585531D03*
X1581791Y1159350D03*
X1589271D03*
X1581791Y1170570D03*
X1593011Y1181791D03*
X1589271D03*
X1585531D03*
X1581791D03*
X1593011Y1189271D03*
X1589271D03*
X1585531D03*
X1581791D03*
X1585531Y1174310D03*
X1593011D03*
Y1204232D03*
Y1196751D03*
X1589271D03*
X1585531D03*
X1581791D03*
Y1204232D03*
X1585531D03*
X1589271D03*
X1593011Y1219192D03*
X1591141Y1217322D03*
X1593011Y1207972D03*
X1589271D03*
X1585531D03*
X1581791D03*
X1591141Y1221062D03*
X1587401D03*
X1579921D03*
X1583661D03*
X1594882D03*
X1583661Y1224803D03*
X1579921Y1232283D03*
Y1236023D03*
X1594882Y1232283D03*
Y1236023D03*
X1591141Y1224803D03*
X1587401Y1232283D03*
Y1236023D03*
X1583661Y1243503D03*
X1579921Y1239763D03*
X1591141Y1243503D03*
X1594882Y1239763D03*
X1587401D03*
X1591142Y1258465D03*
X1583661D03*
X1589410Y1348187D03*
X1581530D03*
X1589410Y1360099D03*
X1581530D03*
Y1384297D03*
Y1372385D03*
X1589410Y1384297D03*
Y1372385D03*
X1581530Y1396583D03*
X1589410D03*
X1581530Y1408495D03*
X1589410D03*
X1609842Y1075196D03*
X1606101Y1071454D03*
X1598621Y1071455D03*
X1598622Y1090157D03*
X1606102Y1082677D03*
Y1086417D03*
X1609842Y1090157D03*
X1606102D03*
X1602362D03*
X1598622Y1105117D03*
X1606102D03*
X1598622Y1101377D03*
X1606102D03*
X1609842Y1093897D03*
X1602362D03*
Y1097637D03*
X1596752Y1121948D03*
X1600492Y1118208D03*
Y1114468D03*
X1611712Y1121948D03*
X1607972D03*
X1596752Y1118208D03*
X1600492Y1121948D03*
X1609842Y1108858D03*
X1606102D03*
X1602362D03*
X1598622D03*
X1607972Y1125688D03*
X1611712D03*
X1607972Y1133464D03*
X1611712Y1133169D03*
X1600590Y1132677D03*
X1596752Y1133169D03*
Y1140649D03*
X1600492D03*
Y1125688D03*
X1596752D03*
X1607972Y1140649D03*
X1611712D03*
X1600492Y1148129D03*
X1596752D03*
X1607972D03*
X1611712D03*
X1600492Y1155610D03*
X1611712D03*
X1596752Y1170570D03*
Y1159350D03*
X1611712Y1166830D03*
X1607972Y1170570D03*
X1600492Y1166830D03*
X1607972Y1159350D03*
X1600492Y1181791D03*
X1611712D03*
X1607972D03*
Y1189271D03*
X1611712D03*
X1596752Y1181791D03*
X1600492Y1189271D03*
X1596752D03*
X1600492Y1174310D03*
X1611712D03*
Y1204232D03*
X1607972D03*
Y1196751D03*
X1611712D03*
X1600492D03*
X1596752D03*
Y1204232D03*
X1600492D03*
X1606102Y1221062D03*
X1596752Y1207972D03*
X1607972D03*
X1611712D03*
Y1211712D03*
X1596752Y1219192D03*
X1600492Y1207972D03*
X1598622Y1221062D03*
X1609842D03*
X1602362D03*
X1598622Y1224803D03*
X1609842Y1232283D03*
Y1236023D03*
X1606102Y1228543D03*
Y1224803D03*
X1602362Y1232283D03*
Y1236023D03*
X1598622Y1243503D03*
X1609842Y1239763D03*
X1602362D03*
X1606102Y1258465D03*
X1598623D03*
X1609158Y1348187D03*
Y1360099D03*
Y1384297D03*
Y1372385D03*
X1624803Y1075196D03*
X1617322D03*
X1621062Y1071455D03*
X1613581D03*
X1617322Y1090157D03*
Y1078936D03*
X1613582Y1090157D03*
Y1086417D03*
X1624803Y1078936D03*
X1621063Y1086417D03*
Y1090157D03*
X1624803D03*
X1617322Y1093897D03*
Y1097637D03*
X1624803Y1093897D03*
Y1097637D03*
X1621063Y1105117D03*
X1613582D03*
Y1101377D03*
X1626673Y1121948D03*
X1622933D03*
X1619193D03*
X1615452D03*
X1624803Y1108858D03*
X1621063D03*
X1617322D03*
X1613582D03*
X1615452Y1133169D03*
X1619193D03*
X1622933D03*
X1626673D03*
X1615452Y1140649D03*
X1619193D03*
X1622933D03*
X1626673D03*
X1615452Y1125688D03*
X1619193D03*
X1622933D03*
X1626673D03*
X1615452Y1148129D03*
X1619193D03*
X1622933D03*
X1626673D03*
X1619193Y1155610D03*
X1626673D03*
X1615452Y1170570D03*
X1622933D03*
X1626673Y1166830D03*
X1615452Y1159350D03*
X1619193Y1166830D03*
X1622933Y1159350D03*
X1615452Y1181791D03*
X1619193D03*
X1622933D03*
X1626673D03*
X1615452Y1189271D03*
X1619193D03*
X1622933D03*
X1626673D03*
Y1174310D03*
X1619193D03*
Y1204232D03*
X1615452D03*
X1626673D03*
X1622933D03*
X1615452Y1196751D03*
X1619193D03*
X1622933D03*
X1626673D03*
X1617322Y1221062D03*
X1619193Y1207972D03*
X1622933D03*
X1626673Y1211712D03*
Y1207972D03*
X1615452Y1211712D03*
Y1207972D03*
X1621063Y1221062D03*
X1613582D03*
X1624803D03*
X1613582Y1228543D03*
Y1224803D03*
X1621063Y1228543D03*
Y1224803D03*
X1624803Y1232283D03*
Y1236023D03*
X1617322Y1232283D03*
Y1236023D03*
Y1239763D03*
X1621063Y1258465D03*
X1613582D03*
X1617038Y1348187D03*
X1621398D03*
X1617038Y1360099D03*
X1621398D03*
X1617038Y1384297D03*
Y1372385D03*
X1621398D03*
Y1384297D03*
Y1396583D03*
Y1408495D03*
X1639763Y1075196D03*
X1632283D03*
X1643503Y1071455D03*
X1636022D03*
X1628542D03*
X1636023Y1090157D03*
X1643504Y1082677D03*
X1636023Y1086417D03*
X1643504Y1090157D03*
Y1086417D03*
X1639763Y1090157D03*
Y1078936D03*
X1632283D03*
X1628543Y1086417D03*
Y1090157D03*
X1632283D03*
Y1093897D03*
Y1097637D03*
X1639763Y1093897D03*
Y1097637D03*
X1628543Y1105117D03*
X1636023D03*
X1643504D03*
X1641633Y1118208D03*
X1637893Y1121948D03*
X1634153D03*
X1630413D03*
X1641633D03*
X1643504Y1108858D03*
X1639763D03*
X1636023D03*
X1632283D03*
X1628543D03*
X1641633Y1136909D03*
X1630413Y1133169D03*
X1634153D03*
X1637893D03*
X1641633D03*
X1634153Y1140649D03*
X1637893D03*
X1641633Y1125688D03*
Y1129429D03*
X1630413Y1125688D03*
X1634153D03*
X1637893D03*
X1641633Y1140649D03*
X1630413D03*
Y1148129D03*
X1634153D03*
X1637893D03*
X1641633Y1144389D03*
Y1148129D03*
Y1151869D03*
X1634153Y1155610D03*
X1641633D03*
X1634153Y1166830D03*
X1630413Y1159350D03*
Y1170570D03*
X1634153Y1189271D03*
X1637893D03*
X1641633Y1178051D03*
X1634153Y1174310D03*
X1641633Y1185531D03*
X1630413Y1181791D03*
X1634153D03*
X1637893D03*
X1641633Y1189271D03*
X1630413D03*
X1641633Y1174310D03*
X1641653Y1196732D03*
X1641633Y1204232D03*
X1630413D03*
X1634153D03*
X1637893D03*
X1641633Y1200491D03*
X1630413Y1196751D03*
X1634153D03*
X1637893D03*
X1641633Y1193011D03*
Y1211712D03*
X1634153Y1207972D03*
X1630413D03*
X1634153Y1211712D03*
X1637893Y1207972D03*
Y1211712D03*
X1630413D03*
X1641633Y1207972D03*
X1628543Y1221062D03*
X1632283D03*
X1636023D03*
X1639763D03*
X1643504D03*
X1628543Y1228543D03*
Y1224803D03*
X1632283Y1232283D03*
Y1236023D03*
X1636023Y1228543D03*
Y1224803D03*
X1639763Y1232283D03*
Y1236023D03*
X1643504Y1228543D03*
Y1224803D03*
X1628543Y1239763D03*
X1639763D03*
X1632283Y1243503D03*
X1639763D03*
X1632283Y1247243D03*
X1639763D03*
X1643504Y1258465D03*
X1636023D03*
X1628543D03*
X1629278Y1348187D03*
X1641518D03*
X1633638D03*
X1629278Y1360099D03*
X1641518D03*
X1633638D03*
X1629278Y1384297D03*
Y1372385D03*
X1641518Y1384297D03*
Y1372385D03*
X1633638Y1384297D03*
Y1372385D03*
X1629278Y1396583D03*
X1641518D03*
X1633638D03*
Y1408495D03*
X1629278D03*
X1641518D03*
X1647244Y1075196D03*
X1654724D03*
X1658463Y1071455D03*
X1650983D03*
X1654724Y1078936D03*
Y1090157D03*
X1658464D03*
X1650984D03*
X1647244D03*
Y1093897D03*
X1658464Y1101377D03*
Y1105117D03*
X1650984D03*
X1645374Y1118208D03*
X1649114D03*
X1658464Y1108858D03*
X1654724D03*
X1650984D03*
X1647244D03*
X1649114Y1140649D03*
X1652854Y1136909D03*
X1645374Y1125688D03*
X1649114Y1136909D03*
X1652854Y1140649D03*
X1645374Y1155610D03*
Y1151869D03*
Y1148129D03*
X1652854D03*
X1649114Y1144389D03*
X1652854Y1155610D03*
X1649114Y1148129D03*
X1652854Y1151869D03*
X1656594D03*
X1660334D03*
Y1155610D03*
X1649114Y1151870D03*
X1645374Y1166830D03*
X1652854Y1159350D03*
X1660334Y1166830D03*
Y1170570D03*
X1645374Y1159350D03*
X1660334D03*
X1645374Y1170570D03*
X1652854D03*
Y1166830D03*
Y1185531D03*
X1656594Y1181791D03*
X1652854Y1178051D03*
Y1174310D03*
X1649114Y1181791D03*
X1656594Y1185531D03*
X1660334Y1174310D03*
Y1178051D03*
Y1185531D03*
X1645374Y1181791D03*
Y1174310D03*
X1649114Y1178051D03*
Y1189271D03*
X1652854D03*
X1649114Y1185531D03*
X1656594Y1193011D03*
X1652854Y1204232D03*
Y1196751D03*
Y1193011D03*
X1649114D03*
X1645374Y1196751D03*
X1649114Y1211712D03*
X1645374Y1207972D03*
X1660334Y1215452D03*
Y1211712D03*
X1654724Y1221062D03*
X1658464D03*
X1650984D03*
X1647244D03*
Y1232283D03*
Y1236023D03*
X1654724Y1232283D03*
X1658464Y1228543D03*
X1654724Y1236023D03*
X1658464Y1224803D03*
X1650984Y1228543D03*
Y1224803D03*
X1654724Y1239763D03*
Y1243503D03*
X1647244Y1247243D03*
X1654724D03*
X1647244Y1243503D03*
X1658464Y1258465D03*
X1650984D03*
X1645878Y1348187D03*
X1653758D03*
X1658118D03*
X1645878Y1360099D03*
X1653758D03*
X1658118D03*
X1645878Y1384297D03*
Y1372385D03*
X1653758D03*
Y1384297D03*
X1658118D03*
Y1372385D03*
X1645878Y1396583D03*
X1653758D03*
X1658118D03*
X1645878Y1408495D03*
X1653758D03*
X1658118D03*
X1662204Y1075196D03*
X1669685D03*
X1673425Y1071455D03*
X1665944D03*
X1662203Y1090157D03*
X1669686Y1078936D03*
X1669684Y1090157D03*
X1662204Y1093897D03*
X1669685D03*
X1673425Y1105117D03*
X1665945D03*
X1669685Y1108858D03*
X1673425Y1116338D03*
Y1123818D03*
X1665944Y1112598D03*
Y1120078D03*
X1665945Y1108858D03*
X1662204Y1123818D03*
Y1120078D03*
Y1116338D03*
Y1108858D03*
X1671555Y1140649D03*
X1673425Y1131299D03*
X1662204Y1135039D03*
Y1131299D03*
Y1127558D03*
Y1138779D03*
X1664074Y1151869D03*
X1671555Y1148129D03*
X1664074Y1144389D03*
Y1159350D03*
X1671555D03*
X1664074Y1166830D03*
X1671555D03*
X1664074Y1189271D03*
Y1174310D03*
X1671555Y1181791D03*
Y1174310D03*
X1664074Y1181791D03*
X1671555Y1189271D03*
X1665945Y1194881D03*
X1664074Y1204232D03*
X1669685Y1202362D03*
X1673425Y1221062D03*
X1669685Y1209842D03*
X1665945Y1221062D03*
Y1217322D03*
X1662204Y1221062D03*
Y1232283D03*
Y1236023D03*
X1673425Y1224803D03*
Y1228543D03*
X1669685Y1232283D03*
Y1236023D03*
X1665945Y1224803D03*
Y1228543D03*
X1662204Y1239763D03*
X1669685D03*
X1673425Y1258465D03*
X1665945D03*
X1665998Y1348187D03*
X1670358D03*
X1665998Y1360099D03*
X1670358D03*
X1665998Y1384297D03*
Y1372385D03*
X1670358D03*
Y1384297D03*
X1665998Y1396583D03*
X1670358D03*
X1665998Y1408495D03*
X1670358D03*
X1677166Y1075196D03*
X1684646D03*
X1692126D03*
X1688385Y1071455D03*
X1680905D03*
X1677166Y1078936D03*
X1692126D03*
X1684646D03*
X1684644Y1090157D03*
X1677165Y1093897D03*
X1684645D03*
X1680905Y1105117D03*
X1677164Y1108857D03*
X1684645Y1108858D03*
X1690256Y1140649D03*
Y1155610D03*
Y1148129D03*
X1682775Y1166830D03*
X1679035Y1170570D03*
X1690256D03*
Y1178051D03*
X1682775Y1174310D03*
X1679035Y1178051D03*
X1682775Y1181791D03*
X1679035Y1185531D03*
X1682775Y1189271D03*
X1690256Y1185531D03*
X1680905Y1194881D03*
X1690256Y1193011D03*
X1679035D03*
X1692126Y1202362D03*
X1680905D03*
Y1198621D03*
X1677165D03*
X1684645Y1221062D03*
X1692126Y1209842D03*
X1680905Y1221062D03*
Y1217322D03*
X1677165Y1221062D03*
Y1213582D03*
X1680905D03*
Y1209842D03*
Y1206102D03*
X1688385Y1224803D03*
Y1228543D03*
X1684645Y1236023D03*
Y1232283D03*
X1692126D03*
X1680905Y1224803D03*
Y1228543D03*
X1677165Y1232283D03*
Y1236023D03*
X1680905Y1239763D03*
X1688385Y1258465D03*
X1680905D03*
X1678238Y1348187D03*
X1690478D03*
X1682598D03*
X1678238Y1360099D03*
X1690478D03*
X1682598D03*
X1678238Y1372385D03*
Y1384297D03*
X1690478D03*
Y1372385D03*
X1682598Y1384297D03*
Y1372385D03*
X1678238Y1396583D03*
X1690478D03*
X1682598D03*
X1678238Y1408495D03*
X1690478D03*
X1682598D03*
X1695866Y1078936D03*
X1699607Y1090158D03*
Y1082677D03*
Y1101378D03*
Y1123819D03*
Y1116339D03*
Y1108859D03*
Y1131300D03*
X1693996Y1170570D03*
Y1178051D03*
Y1185531D03*
Y1193011D03*
X1697676D03*
X1695866Y1202362D03*
X1699607Y1198621D03*
Y1221062D03*
Y1213582D03*
Y1206102D03*
Y1228543D03*
X1695866Y1250984D03*
X1699607Y1247243D03*
Y1239762D03*
X1694838Y1348187D03*
X1702718D03*
X1707078D03*
X1702718Y1360099D03*
X1707078D03*
X1694838D03*
Y1384297D03*
Y1372385D03*
X1702718D03*
Y1384297D03*
X1707078D03*
Y1372385D03*
X1694838Y1396583D03*
X1702718D03*
X1707078D03*
X1694838Y1408495D03*
X1702718D03*
X1707078D03*
X1714958Y1348187D03*
X1719318D03*
X1714958Y1360099D03*
X1719318D03*
X1714958Y1384297D03*
Y1372385D03*
X1719318D03*
Y1384297D03*
X1714958Y1396583D03*
X1719318D03*
X1714958Y1408495D03*
X1719318D03*
X1727198Y1348187D03*
X1739438D03*
X1731558D03*
X1727198Y1360099D03*
X1739438D03*
X1731558D03*
X1739438Y1372385D03*
X1731558Y1384297D03*
Y1372385D03*
X1727198D03*
Y1384297D03*
X1739438D03*
X1727198Y1396583D03*
X1739438D03*
X1731558D03*
X1727198Y1408495D03*
X1739438D03*
X1731558D03*
G54D52*
X956448Y-30304D03*
Y-33204D03*
X953192Y-25085D03*
X956445Y-25099D03*
X950167Y-26405D03*
X953207Y-27600D03*
X956460Y-27614D03*
X978036Y-64265D03*
X975011Y-65585D03*
X978051Y-66780D03*
X981289Y-64279D03*
X981292Y-69484D03*
Y-72384D03*
X981304Y-66794D03*
X1231351Y-77080D03*
X1234592Y-79984D03*
X1234604Y-77094D03*
X1234592Y-82584D03*
Y-71970D03*
X1231336Y-74565D03*
X1234589Y-74579D03*
X1231336Y-64265D03*
X1234589D03*
X1234592Y-69470D03*
X1231351Y-66780D03*
X1234604D03*
X1228311Y-65585D03*
Y-75885D03*
X1236692Y-35515D03*
X1236707Y-38030D03*
X1233667Y-36835D03*
X1236692Y-25215D03*
X1236707Y-27730D03*
X1233667Y-26535D03*
X1239948Y-32920D03*
X1239945Y-35529D03*
X1239948Y-30420D03*
Y-40934D03*
X1239960Y-38044D03*
X1239948Y-43534D03*
X1239945Y-25215D03*
X1239960Y-27730D03*
X1487851Y-77080D03*
X1491092Y-79984D03*
X1491104Y-77094D03*
X1491092Y-82584D03*
Y-71970D03*
X1487836Y-74565D03*
X1491089Y-74579D03*
X1487836Y-64265D03*
X1491089D03*
X1491092Y-69470D03*
X1487851Y-66780D03*
X1491104D03*
X1484811Y-65585D03*
Y-75885D03*
X1526448Y-33050D03*
X1523192Y-35645D03*
X1526445Y-35659D03*
X1526448Y-30550D03*
X1523207Y-38160D03*
X1526448Y-41064D03*
X1526460Y-38174D03*
X1526448Y-43664D03*
X1520167Y-36965D03*
X1523192Y-25345D03*
X1526445D03*
X1523207Y-27860D03*
X1526460D03*
X1520167Y-26665D03*
X1742336Y-74565D03*
Y-64265D03*
X1739311Y-65585D03*
Y-75885D03*
X1742351Y-77080D03*
X1745592Y-79984D03*
X1745604Y-77094D03*
X1745592Y-82584D03*
Y-71970D03*
X1745589Y-74579D03*
Y-64265D03*
X1745592Y-69470D03*
X1742351Y-66780D03*
X1745604D03*
X1804667Y-37095D03*
Y-26795D03*
X1810948Y-33180D03*
X1807692Y-35775D03*
X1810945Y-35789D03*
X1810948Y-30680D03*
X1807707Y-38290D03*
X1810948Y-41194D03*
X1810960Y-38304D03*
X1810948Y-43794D03*
X1807692Y-25475D03*
X1810945D03*
X1807707Y-27990D03*
X1810960D03*
G54D24*
X46348Y1727941D03*
Y1737941D03*
Y1773941D03*
Y1783941D03*
X333112Y1751624D03*
Y1761624D03*
X333212Y1797624D03*
Y1807624D03*
X619861Y1751765D03*
Y1761765D03*
X619475Y1798845D03*
Y1808845D03*
X907163Y1752566D03*
Y1762566D03*
X907166Y1800435D03*
Y1810435D03*
G54D41*
X266841Y421555D03*
Y550020D03*
X295856Y421555D03*
Y550020D03*
X723927Y421555D03*
Y550020D03*
X752942Y421555D03*
Y550020D03*
X1181014Y421555D03*
Y550020D03*
X1210029Y421555D03*
Y550020D03*
X1638101Y421555D03*
Y550020D03*
X1667116Y421555D03*
Y550020D03*
G54D56*
X1236871Y1715189D03*
X1236864Y1773377D03*
X1235371Y1802909D03*
G54D57*
X1236871Y1744208D03*
%LPC*%
G75*
G54D64*
G01X-20602Y-468335D02*
Y-543335D01*
X479398D01*
Y-468335D01*
X-20602D01*
G01X-8602Y-533335D02*
Y-538335D01*
G01X-10059Y-533335D02*
X-7145D01*
G01X-2235Y-538335D02*
X-4769D01*
Y-533335D01*
X-2235D01*
G01X-3249Y-535752D02*
X-4769D01*
G01X331Y-533335D02*
Y-538335D01*
X2865D01*
G01X6698Y-538502D02*
X6571Y-538418D01*
Y-538252D01*
X6698Y-538168D01*
X6825Y-538252D01*
Y-538418D01*
X6698Y-538502D01*
G01Y-536252D02*
X6571Y-536168D01*
Y-536002D01*
X6698Y-535918D01*
X6825Y-536002D01*
Y-536168D01*
X6698Y-536252D01*
G01X11481Y-540002D02*
X10848Y-539168D01*
X10531Y-538335D01*
Y-535002D01*
X10848Y-534168D01*
X11481Y-533335D01*
G01X16898D02*
X16391Y-533502D01*
X16011Y-533918D01*
X15758Y-534418D01*
X15568Y-535085D01*
X15505Y-535835D01*
X15568Y-536585D01*
X15758Y-537252D01*
X16011Y-537752D01*
X16391Y-538168D01*
X16898Y-538335D01*
X17405Y-538168D01*
X17785Y-537752D01*
X18038Y-537252D01*
X18228Y-536585D01*
X18291Y-535835D01*
X18228Y-535085D01*
X18038Y-534418D01*
X17785Y-533918D01*
X17405Y-533502D01*
X16898Y-533335D01*
G01X20605Y-537335D02*
X20985Y-537918D01*
X21491Y-538252D01*
X22061Y-538335D01*
X22568Y-538252D01*
X23075Y-537835D01*
X23391Y-537335D01*
X23455Y-536835D01*
X23328Y-536252D01*
X22885Y-535835D01*
X22441Y-535668D01*
X21871D01*
G01X22441D02*
X22821Y-535418D01*
X23138Y-535002D01*
X23265Y-534502D01*
X23138Y-534002D01*
X22821Y-533585D01*
X22251Y-533335D01*
X21681Y-533418D01*
X21111Y-533752D01*
G01X27415Y-540002D02*
X28048Y-539168D01*
X28365Y-538335D01*
Y-535002D01*
X28048Y-534168D01*
X27415Y-533335D01*
G01X30805Y-537335D02*
X31185Y-537918D01*
X31691Y-538252D01*
X32261Y-538335D01*
X32768Y-538252D01*
X33275Y-537835D01*
X33591Y-537335D01*
X33655Y-536835D01*
X33528Y-536252D01*
X33085Y-535835D01*
X32641Y-535668D01*
X32071D01*
G01X32641D02*
X33021Y-535418D01*
X33338Y-535002D01*
X33465Y-534502D01*
X33338Y-534002D01*
X33021Y-533585D01*
X32451Y-533335D01*
X31881Y-533418D01*
X31311Y-533752D01*
G01X36095Y-534168D02*
X36475Y-533668D01*
X36918Y-533418D01*
X37425Y-533335D01*
X38058Y-533502D01*
X38501Y-533918D01*
X38628Y-534418D01*
X38565Y-534918D01*
X38311Y-535335D01*
X37045Y-536168D01*
X36475Y-536752D01*
X36095Y-537585D01*
X35968Y-538335D01*
X38628D01*
G01X42271D02*
X42398Y-537252D01*
X42588Y-536335D01*
X42841Y-535502D01*
X43158Y-534585D01*
X43665Y-533335D01*
X41131D01*
G01X46675Y-536668D02*
X48321D01*
G01X51395Y-534168D02*
X51775Y-533668D01*
X52218Y-533418D01*
X52725Y-533335D01*
X53358Y-533502D01*
X53801Y-533918D01*
X53928Y-534418D01*
X53865Y-534918D01*
X53611Y-535335D01*
X52345Y-536168D01*
X51775Y-536752D01*
X51395Y-537585D01*
X51268Y-538335D01*
X53928D01*
G01X56305Y-537335D02*
X56685Y-537918D01*
X57191Y-538252D01*
X57761Y-538335D01*
X58268Y-538252D01*
X58775Y-537835D01*
X59091Y-537335D01*
X59155Y-536835D01*
X59028Y-536252D01*
X58585Y-535835D01*
X58141Y-535668D01*
X57571D01*
G01X58141D02*
X58521Y-535418D01*
X58838Y-535002D01*
X58965Y-534502D01*
X58838Y-534002D01*
X58521Y-533585D01*
X57951Y-533335D01*
X57381Y-533418D01*
X56811Y-533752D01*
G01X63558Y-538335D02*
Y-533335D01*
X61215Y-536918D01*
X64381D01*
G01X66505Y-537585D02*
X66885Y-538002D01*
X67328Y-538252D01*
X67898Y-538335D01*
X68468Y-538168D01*
X68911Y-537835D01*
X69228Y-537252D01*
X69291Y-536585D01*
X69165Y-535918D01*
X68848Y-535502D01*
X68405Y-535168D01*
X67961Y-535085D01*
X67518Y-535168D01*
X66948Y-535502D01*
X67138Y-533335D01*
X68848D01*
G01X76895Y-538335D02*
Y-533335D01*
X79301D01*
G01X78415Y-535752D02*
X76895D01*
G01X81615Y-538335D02*
X83198Y-533335D01*
X84781Y-538335D01*
G01X84211Y-536585D02*
X82185D01*
G01X86968Y-538335D02*
X89628Y-533335D01*
G01X86968D02*
X89628Y-538335D01*
G01X93398Y-538502D02*
X93271Y-538418D01*
Y-538252D01*
X93398Y-538168D01*
X93525Y-538252D01*
Y-538418D01*
X93398Y-538502D01*
G01Y-536252D02*
X93271Y-536168D01*
Y-536002D01*
X93398Y-535918D01*
X93525Y-536002D01*
Y-536168D01*
X93398Y-536252D01*
G01X98181Y-540002D02*
X97548Y-539168D01*
X97231Y-538335D01*
Y-535002D01*
X97548Y-534168D01*
X98181Y-533335D01*
G01X103598D02*
X103091Y-533502D01*
X102711Y-533918D01*
X102458Y-534418D01*
X102268Y-535085D01*
X102205Y-535835D01*
X102268Y-536585D01*
X102458Y-537252D01*
X102711Y-537752D01*
X103091Y-538168D01*
X103598Y-538335D01*
X104105Y-538168D01*
X104485Y-537752D01*
X104738Y-537252D01*
X104928Y-536585D01*
X104991Y-535835D01*
X104928Y-535085D01*
X104738Y-534418D01*
X104485Y-533918D01*
X104105Y-533502D01*
X103598Y-533335D01*
G01X107305Y-537335D02*
X107685Y-537918D01*
X108191Y-538252D01*
X108761Y-538335D01*
X109268Y-538252D01*
X109775Y-537835D01*
X110091Y-537335D01*
X110155Y-536835D01*
X110028Y-536252D01*
X109585Y-535835D01*
X109141Y-535668D01*
X108571D01*
G01X109141D02*
X109521Y-535418D01*
X109838Y-535002D01*
X109965Y-534502D01*
X109838Y-534002D01*
X109521Y-533585D01*
X108951Y-533335D01*
X108381Y-533418D01*
X107811Y-533752D01*
G01X114115Y-540002D02*
X114748Y-539168D01*
X115065Y-538335D01*
Y-535002D01*
X114748Y-534168D01*
X114115Y-533335D01*
G01X117505Y-537335D02*
X117885Y-537918D01*
X118391Y-538252D01*
X118961Y-538335D01*
X119468Y-538252D01*
X119975Y-537835D01*
X120291Y-537335D01*
X120355Y-536835D01*
X120228Y-536252D01*
X119785Y-535835D01*
X119341Y-535668D01*
X118771D01*
G01X119341D02*
X119721Y-535418D01*
X120038Y-535002D01*
X120165Y-534502D01*
X120038Y-534002D01*
X119721Y-533585D01*
X119151Y-533335D01*
X118581Y-533418D01*
X118011Y-533752D01*
G01X122921Y-537752D02*
X123365Y-538168D01*
X123871Y-538335D01*
X124378Y-538168D01*
X124821Y-537668D01*
X125138Y-536918D01*
X125265Y-536168D01*
Y-535252D01*
X125138Y-534502D01*
X124821Y-533835D01*
X124441Y-533502D01*
X123998Y-533335D01*
X123491Y-533502D01*
X123111Y-533835D01*
X122858Y-534335D01*
X122731Y-535002D01*
X122858Y-535585D01*
X123175Y-536168D01*
X123555Y-536502D01*
X123998Y-536585D01*
X124505Y-536418D01*
X124885Y-536002D01*
X125265Y-535252D01*
G01X128971Y-538335D02*
X129098Y-537252D01*
X129288Y-536335D01*
X129541Y-535502D01*
X129858Y-534585D01*
X130365Y-533335D01*
X127831D01*
G01X133375Y-536668D02*
X135021D01*
G01X137905Y-537335D02*
X138285Y-537918D01*
X138791Y-538252D01*
X139361Y-538335D01*
X139868Y-538252D01*
X140375Y-537835D01*
X140691Y-537335D01*
X140755Y-536835D01*
X140628Y-536252D01*
X140185Y-535835D01*
X139741Y-535668D01*
X139171D01*
G01X139741D02*
X140121Y-535418D01*
X140438Y-535002D01*
X140565Y-534502D01*
X140438Y-534002D01*
X140121Y-533585D01*
X139551Y-533335D01*
X138981Y-533418D01*
X138411Y-533752D01*
G01X143195Y-536252D02*
X143638Y-535668D01*
X144018Y-535335D01*
X144525Y-535168D01*
X144968Y-535335D01*
X145285Y-535668D01*
X145538Y-536168D01*
X145601Y-536752D01*
X145538Y-537252D01*
X145285Y-537752D01*
X144905Y-538168D01*
X144461Y-538335D01*
X143955Y-538168D01*
X143511Y-537668D01*
X143258Y-536918D01*
X143195Y-536085D01*
X143321Y-535002D01*
X143511Y-534418D01*
X143828Y-533835D01*
X144271Y-533418D01*
X144715Y-533335D01*
X145158Y-533502D01*
X145475Y-533918D01*
G01X149498Y-538335D02*
Y-533335D01*
X148738Y-534335D01*
G01Y-538335D02*
X150258D01*
G01X155358D02*
Y-533335D01*
X153015Y-536918D01*
X156181D01*
G01X174398Y-468335D02*
Y-543335D01*
G01Y-518335D02*
X277398D01*
Y-493335D01*
G01X174398D02*
X277398D01*
G01Y-468335D02*
Y-543335D01*
G01X279398Y-468335D02*
Y-543335D01*
G01X284905Y-528335D02*
Y-523335D01*
X286171D01*
X286678Y-523585D01*
X287058Y-523918D01*
X287375Y-524418D01*
X287628Y-525002D01*
X287691Y-525835D01*
X287628Y-526668D01*
X287375Y-527252D01*
X287058Y-527752D01*
X286678Y-528085D01*
X286171Y-528335D01*
X284905D01*
G01X289815D02*
X291398Y-523335D01*
X292981Y-528335D01*
G01X292411Y-526585D02*
X290385D01*
G01X296498Y-523335D02*
Y-528335D01*
G01X295041Y-523335D02*
X297955D01*
G01X302865Y-528335D02*
X300331D01*
Y-523335D01*
X302865D01*
G01X301851Y-525752D02*
X300331D01*
G01X306698Y-528502D02*
X306571Y-528418D01*
Y-528252D01*
X306698Y-528168D01*
X306825Y-528252D01*
Y-528418D01*
X306698Y-528502D01*
G01Y-526252D02*
X306571Y-526168D01*
Y-526002D01*
X306698Y-525918D01*
X306825Y-526002D01*
Y-526168D01*
X306698Y-526252D01*
G01X279398Y-518335D02*
X479398D01*
G01X285031Y-503335D02*
Y-498335D01*
X286551D01*
X287058Y-498585D01*
X287438Y-499168D01*
X287565Y-499835D01*
X287438Y-500502D01*
X287121Y-501002D01*
X286551Y-501252D01*
X285031D01*
G01X290258Y-503502D02*
X292538Y-498335D01*
G01X295041Y-503335D02*
Y-498335D01*
X297955Y-503335D01*
Y-498335D01*
G01X301598Y-503502D02*
X301471Y-503418D01*
Y-503252D01*
X301598Y-503168D01*
X301725Y-503252D01*
Y-503418D01*
X301598Y-503502D01*
G01Y-501252D02*
X301471Y-501168D01*
Y-501002D01*
X301598Y-500918D01*
X301725Y-501002D01*
Y-501168D01*
X301598Y-501252D01*
G01X279398Y-493335D02*
X479398D01*
G01X285031Y-478335D02*
Y-473335D01*
X286551D01*
X287058Y-473585D01*
X287438Y-474168D01*
X287565Y-474835D01*
X287438Y-475502D01*
X287121Y-476002D01*
X286551Y-476252D01*
X285031D01*
G01X290131Y-478335D02*
Y-473335D01*
X291715D01*
X292221Y-473585D01*
X292538Y-473918D01*
X292665Y-474585D01*
X292538Y-475252D01*
X292158Y-475668D01*
X291715Y-475918D01*
X290131D01*
G01X291715D02*
X292665Y-478335D01*
G01X296498D02*
X295991Y-478252D01*
X295548Y-477918D01*
X295168Y-477418D01*
X294915Y-476835D01*
X294788Y-476168D01*
Y-475502D01*
X294915Y-474835D01*
X295168Y-474252D01*
X295548Y-473752D01*
X295991Y-473418D01*
X296498Y-473335D01*
X297005Y-473418D01*
X297448Y-473752D01*
X297828Y-474252D01*
X298081Y-474835D01*
X298208Y-475502D01*
Y-476168D01*
X298081Y-476835D01*
X297828Y-477418D01*
X297448Y-477918D01*
X297005Y-478252D01*
X296498Y-478335D01*
G01X300331Y-477335D02*
X300648Y-477835D01*
X301028Y-478168D01*
X301471Y-478335D01*
X301978Y-478168D01*
X302358Y-477835D01*
X302738Y-477335D01*
X302865Y-476668D01*
Y-473335D01*
G01X307965Y-478335D02*
X305431D01*
Y-473335D01*
X307965D01*
G01X306951Y-475752D02*
X305431D01*
G01X313191Y-473752D02*
X312811Y-473502D01*
X312368Y-473335D01*
X311861D01*
X311291Y-473585D01*
X310848Y-474002D01*
X310531Y-474502D01*
X310278Y-475335D01*
X310215Y-476085D01*
X310341Y-476835D01*
X310531Y-477335D01*
X310911Y-477835D01*
X311355Y-478168D01*
X311798Y-478335D01*
X312241D01*
X312685Y-478168D01*
X313065Y-477918D01*
X313381Y-477585D01*
G01X316898Y-473335D02*
Y-478335D01*
G01X315441Y-473335D02*
X318355D01*
G01X321998Y-478502D02*
X321871Y-478418D01*
Y-478252D01*
X321998Y-478168D01*
X322125Y-478252D01*
Y-478418D01*
X321998Y-478502D01*
G01Y-476252D02*
X321871Y-476168D01*
Y-476002D01*
X321998Y-475918D01*
X322125Y-476002D01*
Y-476168D01*
X321998Y-476252D01*
G01X394258Y-543563D02*
Y-518563D01*
G01X397031Y-520835D02*
Y-525835D01*
X399565D01*
G01X402638Y-520835D02*
X404158D01*
G01X403398D02*
Y-525835D01*
G01X402638D02*
X404158D01*
G01X409005Y-523168D02*
X409258Y-522918D01*
X409448Y-522502D01*
X409575Y-521918D01*
X409448Y-521418D01*
X409195Y-521085D01*
X408751Y-520835D01*
X407041D01*
Y-525835D01*
X409131D01*
X409575Y-525502D01*
X409828Y-525002D01*
X409955Y-524418D01*
X409828Y-523835D01*
X409448Y-523335D01*
X409005Y-523168D01*
X407041D01*
G01X413598Y-526002D02*
X413471Y-525918D01*
Y-525752D01*
X413598Y-525668D01*
X413725Y-525752D01*
Y-525918D01*
X413598Y-526002D01*
G01Y-523752D02*
X413471Y-523668D01*
Y-523502D01*
X413598Y-523418D01*
X413725Y-523502D01*
Y-523668D01*
X413598Y-523752D01*
G01X437258Y-518563D02*
Y-543563D01*
G01X437398Y-518335D02*
Y-543335D01*
G01X441298Y-520835D02*
Y-525835D01*
G01X439841Y-520835D02*
X442755D01*
G01X446398Y-525835D02*
X446018Y-525752D01*
X445638Y-525418D01*
X445385Y-524835D01*
X445258Y-524168D01*
X445385Y-523502D01*
X445638Y-522918D01*
X446018Y-522585D01*
X446398Y-522502D01*
X446778Y-522585D01*
X447158Y-522918D01*
X447411Y-523502D01*
X447475Y-524168D01*
X447411Y-524835D01*
X447158Y-525418D01*
X446778Y-525752D01*
X446398Y-525835D01*
G01X451498D02*
X451118Y-525752D01*
X450738Y-525418D01*
X450485Y-524835D01*
X450358Y-524168D01*
X450485Y-523502D01*
X450738Y-522918D01*
X451118Y-522585D01*
X451498Y-522502D01*
X451878Y-522585D01*
X452258Y-522918D01*
X452511Y-523502D01*
X452575Y-524168D01*
X452511Y-524835D01*
X452258Y-525418D01*
X451878Y-525752D01*
X451498Y-525835D01*
G01X456598D02*
Y-520835D01*
G01X461698Y-526002D02*
X461571Y-525918D01*
Y-525752D01*
X461698Y-525668D01*
X461825Y-525752D01*
Y-525918D01*
X461698Y-526002D01*
G01Y-523752D02*
X461571Y-523668D01*
Y-523502D01*
X461698Y-523418D01*
X461825Y-523502D01*
Y-523668D01*
X461698Y-523752D01*
G01X437398Y-493335D02*
Y-518335D01*
G01X440031Y-500835D02*
Y-495835D01*
X441615D01*
X442121Y-496085D01*
X442438Y-496418D01*
X442565Y-497085D01*
X442438Y-497752D01*
X442058Y-498168D01*
X441615Y-498418D01*
X440031D01*
G01X441615D02*
X442565Y-500835D01*
G01X447665D02*
X445131D01*
Y-495835D01*
X447665D01*
G01X446651Y-498252D02*
X445131D01*
G01X449915Y-495835D02*
X451498Y-500835D01*
X453081Y-495835D01*
G01X456598Y-501002D02*
X456471Y-500918D01*
Y-500752D01*
X456598Y-500668D01*
X456725Y-500752D01*
Y-500918D01*
X456598Y-501002D01*
G01Y-498752D02*
X456471Y-498668D01*
Y-498502D01*
X456598Y-498418D01*
X456725Y-498502D01*
Y-498668D01*
X456598Y-498752D01*
G01X445411Y-546502D02*
X445518Y-546377D01*
X445598Y-546168D01*
X445651Y-545877D01*
X445598Y-545627D01*
X445491Y-545460D01*
X445305Y-545335D01*
X444585D01*
Y-547835D01*
X445465D01*
X445651Y-547668D01*
X445758Y-547418D01*
X445811Y-547127D01*
X445758Y-546835D01*
X445598Y-546585D01*
X445411Y-546502D01*
X444585D01*
G01X447878Y-547835D02*
Y-546168D01*
G01Y-546460D02*
X447771Y-546293D01*
X447611Y-546210D01*
X447425Y-546168D01*
X447238Y-546252D01*
X447078Y-546418D01*
X446971Y-546668D01*
X446918Y-547002D01*
X446971Y-547335D01*
X447078Y-547585D01*
X447238Y-547752D01*
X447425Y-547835D01*
X447611Y-547793D01*
X447771Y-547668D01*
X447878Y-547502D01*
G01X449198Y-547543D02*
X449331Y-547710D01*
X449518Y-547835D01*
X449678D01*
X449838Y-547752D01*
X449945Y-547627D01*
X449998Y-547460D01*
X449971Y-547210D01*
X449865Y-547085D01*
X449385Y-546835D01*
X449278Y-546543D01*
X449331Y-546335D01*
X449438Y-546210D01*
X449598Y-546168D01*
X449758Y-546210D01*
X449918Y-546335D01*
G01X451398Y-546710D02*
X452251D01*
X452171Y-546418D01*
X452038Y-546252D01*
X451851Y-546168D01*
X451665Y-546210D01*
X451505Y-546335D01*
X451398Y-546627D01*
X451345Y-546877D01*
Y-547127D01*
X451398Y-547377D01*
X451531Y-547627D01*
X451691Y-547793D01*
X451878Y-547835D01*
X452065Y-547752D01*
X452251Y-547502D01*
G01X453518Y-547835D02*
Y-545335D01*
G01Y-546585D02*
X453651Y-546335D01*
X453811Y-546210D01*
X453971Y-546168D01*
X454211Y-546252D01*
X454371Y-546418D01*
X454478Y-546710D01*
Y-547043D01*
X454425Y-547377D01*
X454318Y-547627D01*
X454131Y-547793D01*
X453971Y-547835D01*
X453811Y-547793D01*
X453651Y-547668D01*
X453518Y-547460D01*
G01X456198Y-547835D02*
X456038Y-547793D01*
X455878Y-547627D01*
X455771Y-547335D01*
X455718Y-547002D01*
X455771Y-546668D01*
X455878Y-546377D01*
X456038Y-546210D01*
X456198Y-546168D01*
X456358Y-546210D01*
X456518Y-546377D01*
X456625Y-546668D01*
X456651Y-547002D01*
X456625Y-547335D01*
X456518Y-547627D01*
X456358Y-547793D01*
X456198Y-547835D01*
G01X458878D02*
Y-546168D01*
G01Y-546460D02*
X458771Y-546293D01*
X458611Y-546210D01*
X458425Y-546168D01*
X458238Y-546252D01*
X458078Y-546418D01*
X457971Y-546668D01*
X457918Y-547002D01*
X457971Y-547335D01*
X458078Y-547585D01*
X458238Y-547752D01*
X458425Y-547835D01*
X458611Y-547793D01*
X458771Y-547668D01*
X458878Y-547502D01*
G01X460225Y-547835D02*
Y-546168D01*
G01Y-546502D02*
X460358Y-546335D01*
X460491Y-546210D01*
X460678Y-546168D01*
X460811Y-546210D01*
X460971Y-546335D01*
G01X463278Y-545335D02*
Y-547835D01*
G01Y-547460D02*
X463171Y-547668D01*
X463011Y-547793D01*
X462825Y-547835D01*
X462611Y-547752D01*
X462451Y-547543D01*
X462345Y-547293D01*
X462318Y-547002D01*
X462345Y-546710D01*
X462451Y-546460D01*
X462611Y-546252D01*
X462825Y-546168D01*
X463011Y-546210D01*
X463145Y-546293D01*
X463278Y-546460D01*
G01X466665Y-547835D02*
Y-545335D01*
X467331D01*
X467545Y-545460D01*
X467678Y-545627D01*
X467731Y-545960D01*
X467678Y-546293D01*
X467518Y-546502D01*
X467331Y-546627D01*
X466665D01*
G01X467331D02*
X467731Y-547835D01*
G01X468998Y-546710D02*
X469851D01*
X469771Y-546418D01*
X469638Y-546252D01*
X469451Y-546168D01*
X469265Y-546210D01*
X469105Y-546335D01*
X468998Y-546627D01*
X468945Y-546877D01*
Y-547127D01*
X468998Y-547377D01*
X469131Y-547627D01*
X469291Y-547793D01*
X469478Y-547835D01*
X469665Y-547752D01*
X469851Y-547502D01*
G01X471118Y-546168D02*
X471598Y-547835D01*
X472078Y-546168D01*
G01X473798Y-547918D02*
X473745Y-547877D01*
Y-547793D01*
X473798Y-547752D01*
X473851Y-547793D01*
Y-547877D01*
X473798Y-547918D01*
G01X475545Y-547543D02*
X475731Y-547752D01*
X475945Y-547835D01*
X476158Y-547752D01*
X476345Y-547502D01*
X476478Y-547127D01*
X476531Y-546752D01*
Y-546293D01*
X476478Y-545918D01*
X476345Y-545585D01*
X476185Y-545418D01*
X475998Y-545335D01*
X475785Y-545418D01*
X475625Y-545585D01*
X475518Y-545835D01*
X475465Y-546168D01*
X475518Y-546460D01*
X475651Y-546752D01*
X475811Y-546918D01*
X475998Y-546960D01*
X476211Y-546877D01*
X476371Y-546668D01*
X476531Y-546293D01*
G01X478411Y-546502D02*
X478518Y-546377D01*
X478598Y-546168D01*
X478651Y-545877D01*
X478598Y-545627D01*
X478491Y-545460D01*
X478305Y-545335D01*
X477585D01*
Y-547835D01*
X478465D01*
X478651Y-547668D01*
X478758Y-547418D01*
X478811Y-547127D01*
X478758Y-546835D01*
X478598Y-546585D01*
X478411Y-546502D01*
X477585D01*
G01X-1490433Y-1677216D02*
Y3837819D01*
X4496476D01*
Y-1677216D01*
X-1490433D01*
G01X-7782Y-515685D02*
X-6215D01*
Y-517575D01*
X-6685Y-518205D01*
X-7234Y-518625D01*
X-8017Y-518835D01*
X-8800Y-518625D01*
X-9349Y-518205D01*
X-9819Y-517575D01*
X-10132Y-516840D01*
X-10289Y-516000D01*
Y-515265D01*
X-10132Y-514635D01*
X-9819Y-513900D01*
X-9349Y-513270D01*
X-8879Y-512850D01*
X-8252Y-512535D01*
X-7704D01*
X-7077Y-512745D01*
X-6607Y-513165D01*
G01X-3675Y-512535D02*
Y-517050D01*
X-3362Y-517995D01*
X-2735Y-518625D01*
X-1952Y-518835D01*
X-1169Y-518625D01*
X-542Y-517995D01*
X-229Y-517050D01*
Y-512535D01*
G01X3408D02*
X5288D01*
G01X4348D02*
Y-518835D01*
G01X3408D02*
X5288D01*
G01X9003Y-517995D02*
X9630Y-518520D01*
X10335Y-518835D01*
X10961D01*
X11588Y-518520D01*
X12058Y-517995D01*
X12293Y-517260D01*
X12136Y-516525D01*
X11745Y-515895D01*
X11040Y-515475D01*
X10100Y-515265D01*
X9551Y-514845D01*
X9316Y-514110D01*
X9473Y-513375D01*
X9865Y-512850D01*
X10413Y-512535D01*
X10961D01*
X11510Y-512745D01*
X11980Y-513270D01*
G01X15303Y-518835D02*
Y-512535D01*
G01X18593D02*
Y-518835D01*
G01Y-515685D02*
X15303D01*
G01X21290Y-518835D02*
X23248Y-512535D01*
X25206Y-518835D01*
G01X24501Y-516630D02*
X21995D01*
G01X27746Y-518835D02*
Y-512535D01*
X31350Y-518835D01*
Y-512535D01*
G01X40425Y-518835D02*
Y-512535D01*
X41991D01*
X42618Y-512850D01*
X43088Y-513270D01*
X43480Y-513900D01*
X43793Y-514635D01*
X43871Y-515685D01*
X43793Y-516735D01*
X43480Y-517470D01*
X43088Y-518100D01*
X42618Y-518520D01*
X41991Y-518835D01*
X40425D01*
G01X47508Y-512535D02*
X49388D01*
G01X48448D02*
Y-518835D01*
G01X47508D02*
X49388D01*
G01X53103Y-517995D02*
X53730Y-518520D01*
X54435Y-518835D01*
X55061D01*
X55688Y-518520D01*
X56158Y-517995D01*
X56393Y-517260D01*
X56236Y-516525D01*
X55845Y-515895D01*
X55140Y-515475D01*
X54200Y-515265D01*
X53651Y-514845D01*
X53416Y-514110D01*
X53573Y-513375D01*
X53965Y-512850D01*
X54513Y-512535D01*
X55061D01*
X55610Y-512745D01*
X56080Y-513270D01*
G01X61048Y-512535D02*
Y-518835D01*
G01X59246Y-512535D02*
X62850D01*
G01X67348Y-519045D02*
X67191Y-518940D01*
Y-518730D01*
X67348Y-518625D01*
X67505Y-518730D01*
Y-518940D01*
X67348Y-519045D01*
G01X73491Y-519990D02*
X73805Y-518625D01*
G01X79948Y-512535D02*
Y-518835D01*
G01X78146Y-512535D02*
X81750D01*
G01X84290Y-518835D02*
X86248Y-512535D01*
X88206Y-518835D01*
G01X87501Y-516630D02*
X84995D01*
G01X92548Y-518835D02*
X91921Y-518730D01*
X91373Y-518310D01*
X90903Y-517680D01*
X90590Y-516945D01*
X90433Y-516105D01*
Y-515265D01*
X90590Y-514425D01*
X90903Y-513690D01*
X91373Y-513060D01*
X91921Y-512640D01*
X92548Y-512535D01*
X93175Y-512640D01*
X93723Y-513060D01*
X94193Y-513690D01*
X94506Y-514425D01*
X94663Y-515265D01*
Y-516105D01*
X94506Y-516945D01*
X94193Y-517680D01*
X93723Y-518310D01*
X93175Y-518730D01*
X92548Y-518835D01*
G01X98848D02*
Y-516000D01*
X97281Y-512535D01*
G01X100415D02*
X98848Y-516000D01*
G01X103425Y-512535D02*
Y-517050D01*
X103738Y-517995D01*
X104365Y-518625D01*
X105148Y-518835D01*
X105931Y-518625D01*
X106558Y-517995D01*
X106871Y-517050D01*
Y-512535D01*
G01X109490Y-518835D02*
X111448Y-512535D01*
X113406Y-518835D01*
G01X112701Y-516630D02*
X110195D01*
G01X115946Y-518835D02*
Y-512535D01*
X119550Y-518835D01*
Y-512535D01*
G01X-6529Y-523060D02*
X-6999Y-522745D01*
X-7547Y-522535D01*
X-8174D01*
X-8879Y-522850D01*
X-9427Y-523375D01*
X-9819Y-524005D01*
X-10132Y-525055D01*
X-10210Y-526000D01*
X-10054Y-526945D01*
X-9819Y-527575D01*
X-9349Y-528205D01*
X-8800Y-528625D01*
X-8252Y-528835D01*
X-7704D01*
X-7155Y-528625D01*
X-6685Y-528310D01*
X-6294Y-527890D01*
G01X-2892Y-522535D02*
X-1012D01*
G01X-1952D02*
Y-528835D01*
G01X-2892D02*
X-1012D01*
G01X4348Y-522535D02*
Y-528835D01*
G01X2546Y-522535D02*
X6150D01*
G01X10648Y-528835D02*
Y-526000D01*
X9081Y-522535D01*
G01X12215D02*
X10648Y-526000D01*
G01X21525Y-527575D02*
X21995Y-528310D01*
X22621Y-528730D01*
X23326Y-528835D01*
X23953Y-528730D01*
X24580Y-528205D01*
X24971Y-527575D01*
X25050Y-526945D01*
X24893Y-526210D01*
X24345Y-525685D01*
X23796Y-525475D01*
X23091D01*
G01X23796D02*
X24266Y-525160D01*
X24658Y-524635D01*
X24815Y-524005D01*
X24658Y-523375D01*
X24266Y-522850D01*
X23561Y-522535D01*
X22856Y-522640D01*
X22151Y-523060D01*
G01X27825Y-527575D02*
X28295Y-528310D01*
X28921Y-528730D01*
X29626Y-528835D01*
X30253Y-528730D01*
X30880Y-528205D01*
X31271Y-527575D01*
X31350Y-526945D01*
X31193Y-526210D01*
X30645Y-525685D01*
X30096Y-525475D01*
X29391D01*
G01X30096D02*
X30566Y-525160D01*
X30958Y-524635D01*
X31115Y-524005D01*
X30958Y-523375D01*
X30566Y-522850D01*
X29861Y-522535D01*
X29156Y-522640D01*
X28451Y-523060D01*
G01X34125Y-527575D02*
X34595Y-528310D01*
X35221Y-528730D01*
X35926Y-528835D01*
X36553Y-528730D01*
X37180Y-528205D01*
X37571Y-527575D01*
X37650Y-526945D01*
X37493Y-526210D01*
X36945Y-525685D01*
X36396Y-525475D01*
X35691D01*
G01X36396D02*
X36866Y-525160D01*
X37258Y-524635D01*
X37415Y-524005D01*
X37258Y-523375D01*
X36866Y-522850D01*
X36161Y-522535D01*
X35456Y-522640D01*
X34751Y-523060D01*
G01X41991Y-528835D02*
X42148Y-527470D01*
X42383Y-526315D01*
X42696Y-525265D01*
X43088Y-524110D01*
X43715Y-522535D01*
X40581D01*
G01X48291Y-528835D02*
X48448Y-527470D01*
X48683Y-526315D01*
X48996Y-525265D01*
X49388Y-524110D01*
X50015Y-522535D01*
X46881D01*
G01X54591Y-529990D02*
X54905Y-528625D01*
G01X61048Y-522535D02*
Y-528835D01*
G01X59246Y-522535D02*
X62850D01*
G01X65390Y-528835D02*
X67348Y-522535D01*
X69306Y-528835D01*
G01X68601Y-526630D02*
X66095D01*
G01X72708Y-522535D02*
X74588D01*
G01X73648D02*
Y-528835D01*
G01X72708D02*
X74588D01*
G01X77598Y-522535D02*
X78695Y-528835D01*
X79948Y-522535D01*
X81201Y-528835D01*
X82298Y-522535D01*
G01X84290Y-528835D02*
X86248Y-522535D01*
X88206Y-528835D01*
G01X87501Y-526630D02*
X84995D01*
G01X90746Y-528835D02*
Y-522535D01*
X94350Y-528835D01*
Y-522535D01*
G01X104756Y-530935D02*
X103973Y-529885D01*
X103581Y-528835D01*
Y-524635D01*
X103973Y-523585D01*
X104756Y-522535D01*
G01X116181Y-528835D02*
Y-522535D01*
X118140D01*
X118766Y-522850D01*
X119158Y-523270D01*
X119315Y-524110D01*
X119158Y-524950D01*
X118688Y-525475D01*
X118140Y-525790D01*
X116181D01*
G01X118140D02*
X119315Y-528835D01*
G01X124048Y-529045D02*
X123891Y-528940D01*
Y-528730D01*
X124048Y-528625D01*
X124205Y-528730D01*
Y-528940D01*
X124048Y-529045D01*
G01X130348Y-528835D02*
X129721Y-528730D01*
X129173Y-528310D01*
X128703Y-527680D01*
X128390Y-526945D01*
X128233Y-526105D01*
Y-525265D01*
X128390Y-524425D01*
X128703Y-523690D01*
X129173Y-523060D01*
X129721Y-522640D01*
X130348Y-522535D01*
X130975Y-522640D01*
X131523Y-523060D01*
X131993Y-523690D01*
X132306Y-524425D01*
X132463Y-525265D01*
Y-526105D01*
X132306Y-526945D01*
X131993Y-527680D01*
X131523Y-528310D01*
X130975Y-528730D01*
X130348Y-528835D01*
G01X136648Y-529045D02*
X136491Y-528940D01*
Y-528730D01*
X136648Y-528625D01*
X136805Y-528730D01*
Y-528940D01*
X136648Y-529045D01*
G01X144671Y-523060D02*
X144201Y-522745D01*
X143653Y-522535D01*
X143026D01*
X142321Y-522850D01*
X141773Y-523375D01*
X141381Y-524005D01*
X141068Y-525055D01*
X140990Y-526000D01*
X141146Y-526945D01*
X141381Y-527575D01*
X141851Y-528205D01*
X142400Y-528625D01*
X142948Y-528835D01*
X143496D01*
X144045Y-528625D01*
X144515Y-528310D01*
X144906Y-527890D01*
G01X149248Y-529045D02*
X149091Y-528940D01*
Y-528730D01*
X149248Y-528625D01*
X149405Y-528730D01*
Y-528940D01*
X149248Y-529045D01*
G01X155940Y-530935D02*
X156723Y-529885D01*
X157115Y-528835D01*
Y-524635D01*
X156723Y-523585D01*
X155940Y-522535D01*
G01X-10054Y-508835D02*
Y-502535D01*
X-6450Y-508835D01*
Y-502535D01*
G01X-1952Y-508835D02*
X-2579Y-508730D01*
X-3127Y-508310D01*
X-3597Y-507680D01*
X-3910Y-506945D01*
X-4067Y-506105D01*
Y-505265D01*
X-3910Y-504425D01*
X-3597Y-503690D01*
X-3127Y-503060D01*
X-2579Y-502640D01*
X-1952Y-502535D01*
X-1325Y-502640D01*
X-777Y-503060D01*
X-307Y-503690D01*
X6Y-504425D01*
X163Y-505265D01*
Y-506105D01*
X6Y-506945D01*
X-307Y-507680D01*
X-777Y-508310D01*
X-1325Y-508730D01*
X-1952Y-508835D01*
G01X4348Y-509045D02*
X4191Y-508940D01*
Y-508730D01*
X4348Y-508625D01*
X4505Y-508730D01*
Y-508940D01*
X4348Y-509045D01*
G01X9160Y-503585D02*
X9630Y-502955D01*
X10178Y-502640D01*
X10805Y-502535D01*
X11588Y-502745D01*
X12136Y-503270D01*
X12293Y-503900D01*
X12215Y-504530D01*
X11901Y-505055D01*
X10335Y-506105D01*
X9630Y-506840D01*
X9160Y-507890D01*
X9003Y-508835D01*
X12293D01*
G01X16948D02*
Y-502535D01*
X16008Y-503795D01*
G01Y-508835D02*
X17888D01*
G01X23248D02*
Y-502535D01*
X22308Y-503795D01*
G01Y-508835D02*
X24188D01*
G01X29391Y-509990D02*
X29705Y-508625D01*
G01X33498Y-502535D02*
X34595Y-508835D01*
X35848Y-502535D01*
X37101Y-508835D01*
X38198Y-502535D01*
G01X43715Y-508835D02*
X40581D01*
Y-502535D01*
X43715D01*
G01X42461Y-505580D02*
X40581D01*
G01X46646Y-508835D02*
Y-502535D01*
X50250Y-508835D01*
Y-502535D01*
G01X53103Y-508835D02*
Y-502535D01*
G01X56393D02*
Y-508835D01*
G01Y-505685D02*
X53103D01*
G01X59325Y-502535D02*
Y-507050D01*
X59638Y-507995D01*
X60265Y-508625D01*
X61048Y-508835D01*
X61831Y-508625D01*
X62458Y-507995D01*
X62771Y-507050D01*
Y-502535D01*
G01X65390Y-508835D02*
X67348Y-502535D01*
X69306Y-508835D01*
G01X68601Y-506630D02*
X66095D01*
G01X78460Y-503585D02*
X78930Y-502955D01*
X79478Y-502640D01*
X80105Y-502535D01*
X80888Y-502745D01*
X81436Y-503270D01*
X81593Y-503900D01*
X81515Y-504530D01*
X81201Y-505055D01*
X79635Y-506105D01*
X78930Y-506840D01*
X78460Y-507890D01*
X78303Y-508835D01*
X81593D01*
G01X84446D02*
Y-502535D01*
X88050Y-508835D01*
Y-502535D01*
G01X90825Y-508835D02*
Y-502535D01*
X92391D01*
X93018Y-502850D01*
X93488Y-503270D01*
X93880Y-503900D01*
X94193Y-504635D01*
X94271Y-505685D01*
X94193Y-506735D01*
X93880Y-507470D01*
X93488Y-508100D01*
X93018Y-508520D01*
X92391Y-508835D01*
X90825D01*
G01X103581D02*
Y-502535D01*
X105540D01*
X106166Y-502850D01*
X106558Y-503270D01*
X106715Y-504110D01*
X106558Y-504950D01*
X106088Y-505475D01*
X105540Y-505790D01*
X103581D01*
G01X105540D02*
X106715Y-508835D01*
G01X109725D02*
Y-502535D01*
X111291D01*
X111918Y-502850D01*
X112388Y-503270D01*
X112780Y-503900D01*
X113093Y-504635D01*
X113171Y-505685D01*
X113093Y-506735D01*
X112780Y-507470D01*
X112388Y-508100D01*
X111918Y-508520D01*
X111291Y-508835D01*
X109725D01*
G01X117748Y-509045D02*
X117591Y-508940D01*
Y-508730D01*
X117748Y-508625D01*
X117905Y-508730D01*
Y-508940D01*
X117748Y-509045D01*
G01X14048Y-498135D02*
X11528Y-497718D01*
X9323Y-496052D01*
X7433Y-493552D01*
X6173Y-490635D01*
X5543Y-487302D01*
Y-483968D01*
X6173Y-480635D01*
X7433Y-477718D01*
X9323Y-475219D01*
X11528Y-473552D01*
X14048Y-473135D01*
X16568Y-473552D01*
X18773Y-475219D01*
X20663Y-477718D01*
X21923Y-480635D01*
X22553Y-483968D01*
Y-487302D01*
X21923Y-490635D01*
X20663Y-493552D01*
X18773Y-496052D01*
X16568Y-497718D01*
X14048Y-498135D01*
G01X16568Y-491468D02*
X20348Y-498135D01*
G01X33893Y-481469D02*
Y-493135D01*
X35153Y-496052D01*
X37043Y-497718D01*
X39248Y-498135D01*
X41453Y-497718D01*
X43343Y-496052D01*
X44603Y-493135D01*
G01Y-498135D02*
Y-481469D01*
G01X70118Y-498135D02*
Y-481469D01*
G01Y-484385D02*
X68858Y-482719D01*
X66968Y-481885D01*
X64763Y-481469D01*
X62558Y-482302D01*
X60668Y-483968D01*
X59408Y-486469D01*
X58778Y-489802D01*
X59408Y-493135D01*
X60668Y-495636D01*
X62558Y-497302D01*
X64763Y-498135D01*
X66968Y-497718D01*
X68858Y-496469D01*
X70118Y-494802D01*
G01X84293Y-498135D02*
Y-481469D01*
G01Y-485635D02*
X85553Y-483552D01*
X87443Y-481885D01*
X89963Y-481469D01*
X92168Y-481885D01*
X94058Y-483552D01*
X95003Y-486469D01*
Y-498135D01*
G01X114848Y-473135D02*
Y-498135D01*
G01X110438Y-481469D02*
X119258D01*
G01X145718Y-498135D02*
Y-481469D01*
G01Y-484385D02*
X144458Y-482719D01*
X142568Y-481885D01*
X140363Y-481469D01*
X138158Y-482302D01*
X136268Y-483968D01*
X135008Y-486469D01*
X134378Y-489802D01*
X135008Y-493135D01*
X136268Y-495636D01*
X138158Y-497302D01*
X140363Y-498135D01*
X142568Y-497718D01*
X144458Y-496469D01*
X145718Y-494802D01*
G01X185398Y-477835D02*
Y-485835D01*
X189398D01*
G01X197198D02*
Y-480502D01*
G01Y-481435D02*
X196798Y-480902D01*
X196198Y-480635D01*
X195498Y-480502D01*
X194798Y-480768D01*
X194198Y-481302D01*
X193798Y-482102D01*
X193598Y-483168D01*
X193798Y-484235D01*
X194198Y-485035D01*
X194798Y-485568D01*
X195498Y-485835D01*
X196198Y-485702D01*
X196798Y-485302D01*
X197198Y-484769D01*
G01X201298Y-488235D02*
X201898Y-488502D01*
X202698Y-488235D01*
X203198Y-487702D01*
X203598Y-487035D01*
X204198Y-484902D01*
X205498Y-480502D01*
G01X202298D02*
X204198Y-484902D01*
G01X209898Y-482235D02*
X213098D01*
X212798Y-481302D01*
X212298Y-480768D01*
X211598Y-480502D01*
X210898Y-480635D01*
X210298Y-481035D01*
X209898Y-481968D01*
X209698Y-482769D01*
Y-483568D01*
X209898Y-484368D01*
X210398Y-485168D01*
X210998Y-485702D01*
X211698Y-485835D01*
X212398Y-485568D01*
X213098Y-484769D01*
G01X217998Y-485835D02*
Y-480502D01*
G01Y-481568D02*
X218498Y-481035D01*
X218998Y-480635D01*
X219698Y-480502D01*
X220198Y-480635D01*
X220798Y-481035D01*
G01X211398Y-535835D02*
Y-532235D01*
X209398Y-527835D01*
G01X213398D02*
X211398Y-532235D01*
G01X217698Y-530502D02*
Y-534235D01*
X218098Y-535168D01*
X218698Y-535702D01*
X219398Y-535835D01*
X220098Y-535702D01*
X220698Y-535168D01*
X221098Y-534235D01*
G01Y-535835D02*
Y-530502D01*
G01X225698Y-535835D02*
Y-530502D01*
G01Y-531835D02*
X226098Y-531168D01*
X226698Y-530635D01*
X227498Y-530502D01*
X228198Y-530635D01*
X228798Y-531168D01*
X229098Y-532102D01*
Y-535835D01*
G01X237198D02*
Y-530502D01*
G01Y-531435D02*
X236798Y-530902D01*
X236198Y-530635D01*
X235498Y-530502D01*
X234798Y-530768D01*
X234198Y-531302D01*
X233798Y-532102D01*
X233598Y-533168D01*
X233798Y-534235D01*
X234198Y-535035D01*
X234798Y-535568D01*
X235498Y-535835D01*
X236198Y-535702D01*
X236798Y-535302D01*
X237198Y-534769D01*
G01X213198Y-506235D02*
X215198D01*
Y-508635D01*
X214598Y-509435D01*
X213898Y-509968D01*
X212898Y-510235D01*
X211898Y-509968D01*
X211198Y-509435D01*
X210598Y-508635D01*
X210198Y-507702D01*
X209998Y-506635D01*
Y-505702D01*
X210198Y-504902D01*
X210598Y-503968D01*
X211198Y-503168D01*
X211798Y-502635D01*
X212598Y-502235D01*
X213298D01*
X214098Y-502502D01*
X214698Y-503035D01*
G01X218298Y-510235D02*
Y-502235D01*
X222898Y-510235D01*
Y-502235D01*
G01X226398Y-510235D02*
Y-502235D01*
X228398D01*
X229198Y-502635D01*
X229798Y-503168D01*
X230298Y-503968D01*
X230698Y-504902D01*
X230798Y-506235D01*
X230698Y-507568D01*
X230298Y-508502D01*
X229798Y-509302D01*
X229198Y-509835D01*
X228398Y-510235D01*
X226398D01*
G01X237798D02*
Y-502235D01*
X234098Y-507968D01*
X239098D01*
G01X247398Y-486535D02*
Y-478535D01*
X246198Y-480135D01*
G01Y-486535D02*
X248598D01*
G01X255398D02*
Y-478535D01*
X254198Y-480135D01*
G01Y-486535D02*
X256598D01*
G01X311998Y-529168D02*
X312598Y-528368D01*
X313298Y-527968D01*
X314098Y-527835D01*
X315098Y-528102D01*
X315798Y-528768D01*
X315998Y-529568D01*
X315898Y-530369D01*
X315498Y-531035D01*
X313498Y-532368D01*
X312598Y-533302D01*
X311998Y-534635D01*
X311798Y-535835D01*
X315998D01*
G01X321898Y-527835D02*
X321098Y-528102D01*
X320498Y-528768D01*
X320098Y-529568D01*
X319798Y-530635D01*
X319698Y-531835D01*
X319798Y-533035D01*
X320098Y-534102D01*
X320498Y-534902D01*
X321098Y-535568D01*
X321898Y-535835D01*
X322698Y-535568D01*
X323298Y-534902D01*
X323698Y-534102D01*
X323998Y-533035D01*
X324098Y-531835D01*
X323998Y-530635D01*
X323698Y-529568D01*
X323298Y-528768D01*
X322698Y-528102D01*
X321898Y-527835D01*
G01X327998Y-529168D02*
X328598Y-528368D01*
X329298Y-527968D01*
X330098Y-527835D01*
X331098Y-528102D01*
X331798Y-528768D01*
X331998Y-529568D01*
X331898Y-530369D01*
X331498Y-531035D01*
X329498Y-532368D01*
X328598Y-533302D01*
X327998Y-534635D01*
X327798Y-535835D01*
X331998D01*
G01X335698Y-534235D02*
X336298Y-535168D01*
X337098Y-535702D01*
X337998Y-535835D01*
X338798Y-535702D01*
X339598Y-535035D01*
X340098Y-534235D01*
X340198Y-533435D01*
X339998Y-532502D01*
X339298Y-531835D01*
X338598Y-531568D01*
X337698D01*
G01X338598D02*
X339198Y-531168D01*
X339698Y-530502D01*
X339898Y-529702D01*
X339698Y-528902D01*
X339198Y-528235D01*
X338298Y-527835D01*
X337398Y-527968D01*
X336498Y-528502D01*
G01X344098Y-536102D02*
X347698Y-527835D01*
G01X353898D02*
X353098Y-528102D01*
X352498Y-528768D01*
X352098Y-529568D01*
X351798Y-530635D01*
X351698Y-531835D01*
X351798Y-533035D01*
X352098Y-534102D01*
X352498Y-534902D01*
X353098Y-535568D01*
X353898Y-535835D01*
X354698Y-535568D01*
X355298Y-534902D01*
X355698Y-534102D01*
X355998Y-533035D01*
X356098Y-531835D01*
X355998Y-530635D01*
X355698Y-529568D01*
X355298Y-528768D01*
X354698Y-528102D01*
X353898Y-527835D01*
G01X361898Y-535835D02*
Y-527835D01*
X360698Y-529435D01*
G01Y-535835D02*
X363098D01*
G01X368098Y-536102D02*
X371698Y-527835D01*
G01X377898D02*
X377098Y-528102D01*
X376498Y-528768D01*
X376098Y-529568D01*
X375798Y-530635D01*
X375698Y-531835D01*
X375798Y-533035D01*
X376098Y-534102D01*
X376498Y-534902D01*
X377098Y-535568D01*
X377898Y-535835D01*
X378698Y-535568D01*
X379298Y-534902D01*
X379698Y-534102D01*
X379998Y-533035D01*
X380098Y-531835D01*
X379998Y-530635D01*
X379698Y-529568D01*
X379298Y-528768D01*
X378698Y-528102D01*
X377898Y-527835D01*
G01X384198Y-534902D02*
X384898Y-535568D01*
X385698Y-535835D01*
X386498Y-535568D01*
X387198Y-534769D01*
X387698Y-533568D01*
X387898Y-532368D01*
Y-530902D01*
X387698Y-529702D01*
X387198Y-528635D01*
X386598Y-528102D01*
X385898Y-527835D01*
X385098Y-528102D01*
X384498Y-528635D01*
X384098Y-529435D01*
X383898Y-530502D01*
X384098Y-531435D01*
X384598Y-532368D01*
X385198Y-532902D01*
X385898Y-533035D01*
X386698Y-532769D01*
X387298Y-532102D01*
X387898Y-530902D01*
G01X311698Y-510835D02*
Y-502835D01*
X313698D01*
X314498Y-503235D01*
X315098Y-503768D01*
X315598Y-504568D01*
X315998Y-505502D01*
X316098Y-506835D01*
X315998Y-508168D01*
X315598Y-509102D01*
X315098Y-509902D01*
X314498Y-510435D01*
X313698Y-510835D01*
X311698D01*
G01X319398D02*
X321898Y-502835D01*
X324398Y-510835D01*
G01X323498Y-508035D02*
X320298D01*
G01X329898Y-502835D02*
X329098Y-503102D01*
X328498Y-503768D01*
X328098Y-504568D01*
X327798Y-505635D01*
X327698Y-506835D01*
X327798Y-508035D01*
X328098Y-509102D01*
X328498Y-509902D01*
X329098Y-510568D01*
X329898Y-510835D01*
X330698Y-510568D01*
X331298Y-509902D01*
X331698Y-509102D01*
X331998Y-508035D01*
X332098Y-506835D01*
X331998Y-505635D01*
X331698Y-504568D01*
X331298Y-503768D01*
X330698Y-503102D01*
X329898Y-502835D01*
G01X335998Y-510835D02*
Y-502835D01*
X339798D01*
G01X338398Y-506702D02*
X335998D01*
G01X345898Y-502835D02*
X345098Y-503102D01*
X344498Y-503768D01*
X344098Y-504568D01*
X343798Y-505635D01*
X343698Y-506835D01*
X343798Y-508035D01*
X344098Y-509102D01*
X344498Y-509902D01*
X345098Y-510568D01*
X345898Y-510835D01*
X346698Y-510568D01*
X347298Y-509902D01*
X347698Y-509102D01*
X347998Y-508035D01*
X348098Y-506835D01*
X347998Y-505635D01*
X347698Y-504568D01*
X347298Y-503768D01*
X346698Y-503102D01*
X345898Y-502835D01*
G01X353898D02*
Y-510835D01*
G01X351598Y-502835D02*
X356198D01*
G01X363898Y-510835D02*
X359898D01*
Y-502835D01*
X363898D01*
G01X362298Y-506702D02*
X359898D01*
G01X370698Y-506568D02*
X371098Y-506168D01*
X371398Y-505502D01*
X371598Y-504568D01*
X371398Y-503768D01*
X370998Y-503235D01*
X370298Y-502835D01*
X367598D01*
Y-510835D01*
X370898D01*
X371598Y-510302D01*
X371998Y-509502D01*
X372198Y-508568D01*
X371998Y-507635D01*
X371398Y-506835D01*
X370698Y-506568D01*
X367598D01*
G01X376698Y-502835D02*
X379098D01*
G01X377898D02*
Y-510835D01*
G01X376698D02*
X379098D01*
G01X383998D02*
Y-502835D01*
X387798D01*
G01X386398Y-506702D02*
X383998D01*
G01X393898Y-502835D02*
X393098Y-503102D01*
X392498Y-503768D01*
X392098Y-504568D01*
X391798Y-505635D01*
X391698Y-506835D01*
X391798Y-508035D01*
X392098Y-509102D01*
X392498Y-509902D01*
X393098Y-510568D01*
X393898Y-510835D01*
X394698Y-510568D01*
X395298Y-509902D01*
X395698Y-509102D01*
X395998Y-508035D01*
X396098Y-506835D01*
X395998Y-505635D01*
X395698Y-504568D01*
X395298Y-503768D01*
X394698Y-503102D01*
X393898Y-502835D01*
G01X329498Y-485835D02*
Y-477835D01*
X333298D01*
G01X331898Y-481702D02*
X329498D01*
G01X339398Y-477835D02*
X338598Y-478102D01*
X337998Y-478768D01*
X337598Y-479568D01*
X337298Y-480635D01*
X337198Y-481835D01*
X337298Y-483035D01*
X337598Y-484102D01*
X337998Y-484902D01*
X338598Y-485568D01*
X339398Y-485835D01*
X340198Y-485568D01*
X340798Y-484902D01*
X341198Y-484102D01*
X341498Y-483035D01*
X341598Y-481835D01*
X341498Y-480635D01*
X341198Y-479568D01*
X340798Y-478768D01*
X340198Y-478102D01*
X339398Y-477835D01*
G01X347398D02*
Y-485835D01*
G01X345098Y-477835D02*
X349698D01*
G01X352398Y-488502D02*
X358398D01*
G01X361898Y-482235D02*
X365098D01*
X364798Y-481302D01*
X364298Y-480768D01*
X363598Y-480502D01*
X362898Y-480635D01*
X362298Y-481035D01*
X361898Y-481968D01*
X361698Y-482769D01*
Y-483568D01*
X361898Y-484368D01*
X362398Y-485168D01*
X362998Y-485702D01*
X363698Y-485835D01*
X364398Y-485568D01*
X365098Y-484769D01*
G01X369898Y-480502D02*
X372898Y-485835D01*
G01Y-480502D02*
X369898Y-485835D01*
G01X377598Y-488502D02*
Y-480502D01*
G01Y-481702D02*
X378098Y-481035D01*
X378598Y-480635D01*
X379398Y-480502D01*
X380098Y-480635D01*
X380798Y-481302D01*
X381098Y-482235D01*
X381198Y-483168D01*
X381098Y-484102D01*
X380798Y-485035D01*
X380198Y-485568D01*
X379398Y-485835D01*
X378698Y-485702D01*
X377998Y-485302D01*
X377598Y-484769D01*
G01X389198Y-485835D02*
Y-480502D01*
G01Y-481435D02*
X388798Y-480902D01*
X388198Y-480635D01*
X387498Y-480502D01*
X386798Y-480768D01*
X386198Y-481302D01*
X385798Y-482102D01*
X385598Y-483168D01*
X385798Y-484235D01*
X386198Y-485035D01*
X386798Y-485568D01*
X387498Y-485835D01*
X388198Y-485702D01*
X388798Y-485302D01*
X389198Y-484769D01*
G01X393698Y-485835D02*
Y-480502D01*
G01Y-481835D02*
X394098Y-481168D01*
X394698Y-480635D01*
X395498Y-480502D01*
X396198Y-480635D01*
X396798Y-481168D01*
X397098Y-482102D01*
Y-485835D01*
G01X405198Y-477835D02*
Y-485835D01*
G01Y-484635D02*
X404798Y-485302D01*
X404198Y-485702D01*
X403498Y-485835D01*
X402698Y-485568D01*
X402098Y-484902D01*
X401698Y-484102D01*
X401598Y-483168D01*
X401698Y-482235D01*
X402098Y-481435D01*
X402698Y-480768D01*
X403498Y-480502D01*
X404198Y-480635D01*
X404698Y-480902D01*
X405198Y-481435D01*
G01X409898Y-482235D02*
X413098D01*
X412798Y-481302D01*
X412298Y-480768D01*
X411598Y-480502D01*
X410898Y-480635D01*
X410298Y-481035D01*
X409898Y-481968D01*
X409698Y-482769D01*
Y-483568D01*
X409898Y-484368D01*
X410398Y-485168D01*
X410998Y-485702D01*
X411698Y-485835D01*
X412398Y-485568D01*
X413098Y-484769D01*
G01X417998Y-485835D02*
Y-480502D01*
G01Y-481568D02*
X418498Y-481035D01*
X418998Y-480635D01*
X419698Y-480502D01*
X420198Y-480635D01*
X420798Y-481035D01*
G01X424398Y-488502D02*
X430398D01*
G01X433598Y-485835D02*
Y-477835D01*
G01Y-481835D02*
X434098Y-481035D01*
X434698Y-480635D01*
X435298Y-480502D01*
X436198Y-480768D01*
X436798Y-481302D01*
X437198Y-482235D01*
Y-483302D01*
X436998Y-484368D01*
X436598Y-485168D01*
X435898Y-485702D01*
X435298Y-485835D01*
X434698Y-485702D01*
X434098Y-485302D01*
X433598Y-484635D01*
G01X445198Y-477835D02*
Y-485835D01*
G01Y-484635D02*
X444798Y-485302D01*
X444198Y-485702D01*
X443498Y-485835D01*
X442698Y-485568D01*
X442098Y-484902D01*
X441698Y-484102D01*
X441598Y-483168D01*
X441698Y-482235D01*
X442098Y-481435D01*
X442698Y-480768D01*
X443498Y-480502D01*
X444198Y-480635D01*
X444698Y-480902D01*
X445198Y-481435D01*
G01X400398Y-538835D02*
Y-530835D01*
X399198Y-532435D01*
G01Y-538835D02*
X401598D01*
G01X406498Y-535502D02*
X407198Y-534568D01*
X407798Y-534035D01*
X408598Y-533768D01*
X409298Y-534035D01*
X409798Y-534568D01*
X410198Y-535368D01*
X410298Y-536302D01*
X410198Y-537102D01*
X409798Y-537902D01*
X409198Y-538568D01*
X408498Y-538835D01*
X407698Y-538568D01*
X406998Y-537769D01*
X406598Y-536568D01*
X406498Y-535235D01*
X406698Y-533502D01*
X406998Y-532568D01*
X407498Y-531635D01*
X408198Y-530968D01*
X408898Y-530835D01*
X409598Y-531102D01*
X410098Y-531768D01*
G01X416398Y-539102D02*
X416198Y-538968D01*
Y-538702D01*
X416398Y-538568D01*
X416598Y-538702D01*
Y-538968D01*
X416398Y-539102D01*
G01X422498Y-535502D02*
X423198Y-534568D01*
X423798Y-534035D01*
X424598Y-533768D01*
X425298Y-534035D01*
X425798Y-534568D01*
X426198Y-535368D01*
X426298Y-536302D01*
X426198Y-537102D01*
X425798Y-537902D01*
X425198Y-538568D01*
X424498Y-538835D01*
X423698Y-538568D01*
X422998Y-537769D01*
X422598Y-536568D01*
X422498Y-535235D01*
X422698Y-533502D01*
X422998Y-532568D01*
X423498Y-531635D01*
X424198Y-530968D01*
X424898Y-530835D01*
X425598Y-531102D01*
X426098Y-531768D01*
G01X445398Y-538835D02*
Y-530835D01*
X444198Y-532435D01*
G01Y-538835D02*
X446598D01*
G01X453198D02*
X453398Y-537102D01*
X453698Y-535635D01*
X454098Y-534302D01*
X454598Y-532835D01*
X455398Y-530835D01*
X451398D01*
G01X461398Y-539102D02*
X461198Y-538968D01*
Y-538702D01*
X461398Y-538568D01*
X461598Y-538702D01*
Y-538968D01*
X461398Y-539102D01*
G01X467498Y-532168D02*
X468098Y-531368D01*
X468798Y-530968D01*
X469598Y-530835D01*
X470598Y-531102D01*
X471298Y-531768D01*
X471498Y-532568D01*
X471398Y-533369D01*
X470998Y-534035D01*
X468998Y-535368D01*
X468098Y-536302D01*
X467498Y-537635D01*
X467298Y-538835D01*
X471498D01*
G01X465498Y-513835D02*
Y-505835D01*
X469298D01*
G01X467898Y-509702D02*
X465498D01*
M02*
